G04 ================== begin FILE IDENTIFICATION RECORD ==================*
G04 Layout Name:  D:/<user>/Wistron_project/16318-2/gbr/16318-2.brd*
G04 Film Name:    16318-2_X_Y*
G04 File Format:  Gerber RS274X*
G04 File Origin:  Cadence Allegro 16.5-S056*
G04 Origin Date:  Mon Aug 07 11:09:09 2017*
G04 *
G04 Layer:  BOARD GEOMETRY/PANEL_DRAWING*
G04 *
G04 Offset:    (0.00 0.00)*
G04 Mirror:    No*
G04 Mode:      Positive*
G04 Rotation:  0*
G04 FullContactRelief:  No*
G04 UndefLineWidth:     6.00*
G04 ================== end FILE IDENTIFICATION RECORD ====================*
%FSLAX35Y35*MOIN*%
%IR0*IPPOS*OFA0.00000B0.00000*MIA0B0*SFA1.00000B1.00000*%
%ADD10C,.006*%
G75*
%LPD*%
G75*
G36*
G01X-1669948Y102731D02*
X-1664685Y111728D01*
X-1668397Y113039D01*
X-1669948Y102731D01*
G37*
G36*
G01X-1622733Y1124571D02*
X-1630451Y1131578D01*
X-1632499Y1128215D01*
X-1622733Y1124571D01*
G37*
G36*
G01X-1561460Y783449D02*
X-1556055Y774536D01*
X-1553135Y777177D01*
X-1561460Y783449D01*
G37*
G36*
G01X-1613857Y1111429D02*
X-1623935Y1108765D01*
X-1622228Y1105217D01*
X-1613857Y1111429D01*
G37*
G36*
G01X-1541828Y631902D02*
X-1546503Y622585D01*
X-1538706Y629503D01*
X-1541828Y631902D01*
G37*
G36*
G01X-1501024Y1043279D02*
X-1511389Y1044376D01*
X-1511057Y1040453D01*
X-1501024Y1043279D01*
G37*
G36*
G01X-1501537Y1028706D02*
X-1493883Y1035782D01*
X-1503615Y1032049D01*
X-1501537Y1028706D01*
G37*
G36*
G01X-1506447Y1038379D02*
X-1516665Y1036320D01*
X-1515172Y1032676D01*
X-1506447Y1038379D01*
G37*
G36*
G01X-1351502Y527758D02*
X-1360119Y521892D01*
X-1357329Y519115D01*
X-1351502Y527758D01*
G37*
G36*
G01X-1239866Y-521601D02*
X-1248115Y-527974D01*
X-1245163Y-530579D01*
X-1239866Y-521601D01*
G37*
G36*
G01X-1239775Y-527134D02*
X-1244993Y-536158D01*
X-1241274Y-537450D01*
X-1239775Y-527134D01*
G37*
G36*
G01X-1240602Y-487857D02*
X-1248334Y-480866D01*
X-1250375Y-484232D01*
X-1240602Y-487857D01*
G37*
G36*
G01X-1274117Y824035D02*
X-1281921Y817125D01*
X-1272111Y820647D01*
X-1274117Y824035D01*
G37*
G36*
G01X-1093469Y-606825D02*
X-1093322Y-617248D01*
X-1089467Y-616450D01*
X-1093469Y-606825D01*
G37*
G36*
G01X-1094283Y-601354D02*
X-1093389Y-611739D01*
X-1089601Y-610667D01*
X-1094283Y-601354D01*
G37*
G36*
G01X-1009937Y-604316D02*
X-1004305Y-613088D01*
X-1001454Y-610373D01*
X-1009937Y-604316D01*
G37*
G36*
G01X-1013252Y-599776D02*
X-1006224Y-607474D01*
X-1003870Y-604319D01*
X-1013252Y-599776D01*
G37*
G36*
G01X-994268Y546978D02*
X-987796Y538807D01*
X-985227Y541791D01*
X-994268Y546978D01*
G37*
G36*
G01X-1002509Y548822D02*
X-1003233Y538424D01*
X-999324Y538897D01*
X-1002509Y548822D01*
G37*
G36*
G01X-845081Y103292D02*
X-840802Y112796D01*
X-844632Y113706D01*
X-845081Y103292D01*
G37*
G36*
G01X-838178Y-581046D02*
X-830461Y-574039D01*
X-833611Y-571677D01*
X-838178Y-581046D01*
G37*
G36*
G01X-774568Y439450D02*
X-766093Y445519D01*
X-768948Y448229D01*
X-774568Y439450D01*
G37*
G36*
G01X-781933Y715285D02*
X-773070Y720772D01*
X-775737Y723668D01*
X-781933Y715285D01*
G37*
G36*
G01X-785119Y705135D02*
X-776300Y699578D01*
X-774868Y703245D01*
X-785119Y705135D01*
G37*
G36*
G01X-776609Y1133235D02*
X-772822Y1142947D01*
X-776694Y1143659D01*
X-776609Y1133235D01*
G37*
G36*
G01X-774584Y1119115D02*
X-765333Y1123917D01*
X-767774Y1127005D01*
X-774584Y1119115D01*
G37*
G36*
G01X-773031Y416382D02*
X-771050Y406148D01*
X-767395Y407613D01*
X-773031Y416382D01*
G37*
G54D10*
G01X-2055893Y-733164D02*
X-2055182Y-734300D01*
X-2054330Y-735057D01*
X-2053336Y-735436D01*
X-2052200Y-735057D01*
X-2051348Y-734300D01*
X-2050495Y-733164D01*
X-2050211Y-731649D01*
Y-724074D01*
G01X-2054756Y-508192D02*
X-2051348D01*
G01X-2053052D02*
Y-519554D01*
G01X-2054756D02*
X-2051348D01*
G01X-2056035Y-303862D02*
Y-292500D01*
G01X-2050069D02*
Y-303862D01*
G01Y-298181D02*
X-2056035D01*
G01X-2052200Y-82299D02*
X-2049359D01*
Y-85708D01*
X-2050211Y-86844D01*
X-2051206Y-87601D01*
X-2052626Y-87980D01*
X-2054046Y-87601D01*
X-2055040Y-86844D01*
X-2055893Y-85708D01*
X-2056461Y-84382D01*
X-2056745Y-82867D01*
Y-81542D01*
X-2056461Y-80406D01*
X-2055893Y-79080D01*
X-2055040Y-77944D01*
X-2054188Y-77186D01*
X-2053052Y-76618D01*
X-2052058D01*
X-2050922Y-76997D01*
X-2050069Y-77754D01*
G01X-2056129Y128092D02*
Y139454D01*
X-2050731D01*
G01X-2052720Y133962D02*
X-2056129D01*
G01X-2050211Y344163D02*
X-2055893D01*
Y355525D01*
X-2050211D01*
G01X-2052484Y350033D02*
X-2055893D01*
G01X-2056177Y559855D02*
Y571217D01*
X-2053336D01*
X-2052200Y570649D01*
X-2051348Y569891D01*
X-2050637Y568755D01*
X-2050069Y567429D01*
X-2049927Y565536D01*
X-2050069Y563642D01*
X-2050637Y562317D01*
X-2051348Y561180D01*
X-2052200Y560423D01*
X-2053336Y559855D01*
X-2056177D01*
G01X-2049927Y786342D02*
X-2050780Y786910D01*
X-2051774Y787289D01*
X-2052910D01*
X-2054188Y786721D01*
X-2055182Y785774D01*
X-2055893Y784638D01*
X-2056461Y782744D01*
X-2056603Y781040D01*
X-2056319Y779336D01*
X-2055893Y778199D01*
X-2055040Y777063D01*
X-2054046Y776306D01*
X-2053052Y775927D01*
X-2052058D01*
X-2051064Y776306D01*
X-2050211Y776874D01*
X-2049501Y777631D01*
G01X-2051916Y997679D02*
X-2051348Y998247D01*
X-2050922Y999193D01*
X-2050637Y1000519D01*
X-2050922Y1001655D01*
X-2051490Y1002413D01*
X-2052484Y1002981D01*
X-2056319D01*
Y991619D01*
X-2051632D01*
X-2050637Y992376D01*
X-2050069Y993513D01*
X-2049785Y994838D01*
X-2050069Y996164D01*
X-2050922Y997300D01*
X-2051916Y997679D01*
X-2056319D01*
G01X-2056603Y1207501D02*
X-2053052Y1218863D01*
X-2049501Y1207501D01*
G01X-2050780Y1211478D02*
X-2055325D01*
G01X-1973635Y976273D02*
X-1974718Y977717D01*
X-1975259Y979160D01*
Y984934D01*
X-1974718Y986378D01*
X-1973635Y987821D01*
G01X-1966923Y979160D02*
Y987821D01*
X-1961943Y979160D01*
Y987821D01*
G01X-1955772Y979160D02*
X-1956638Y979304D01*
X-1957396Y979882D01*
X-1958046Y980748D01*
X-1958479Y981758D01*
X-1958695Y982913D01*
Y984068D01*
X-1958479Y985223D01*
X-1958046Y986233D01*
X-1957396Y987099D01*
X-1956638Y987677D01*
X-1955772Y987821D01*
X-1954906Y987677D01*
X-1954148Y987099D01*
X-1953498Y986233D01*
X-1953065Y985223D01*
X-1952849Y984068D01*
Y982913D01*
X-1953065Y981758D01*
X-1953498Y980748D01*
X-1954148Y979882D01*
X-1954906Y979304D01*
X-1955772Y979160D01*
G01X-1938450Y987821D02*
Y979160D01*
G01X-1940940Y987821D02*
X-1935960D01*
G01X-1931954Y979160D02*
Y987821D01*
X-1929248D01*
X-1928382Y987388D01*
X-1927840Y986811D01*
X-1927624Y985656D01*
X-1927840Y984501D01*
X-1928490Y983779D01*
X-1929248Y983346D01*
X-1931954D01*
G01X-1929248D02*
X-1927624Y979160D01*
G01X-1923835D02*
X-1921128Y987821D01*
X-1918421Y979160D01*
G01X-1919396Y982191D02*
X-1922860D01*
G01X-1910085Y987099D02*
X-1910735Y987532D01*
X-1911493Y987821D01*
X-1912359D01*
X-1913333Y987388D01*
X-1914091Y986666D01*
X-1914632Y985800D01*
X-1915066Y984357D01*
X-1915174Y983057D01*
X-1914957Y981758D01*
X-1914632Y980892D01*
X-1913983Y980026D01*
X-1913225Y979449D01*
X-1912467Y979160D01*
X-1911709D01*
X-1910951Y979449D01*
X-1910302Y979882D01*
X-1909760Y980459D01*
G01X-1901641Y979160D02*
X-1905971D01*
Y987821D01*
X-1901641D01*
G01X-1903373Y983635D02*
X-1905971D01*
G01X-1889191Y979160D02*
X-1886484Y987821D01*
X-1883777Y979160D01*
G01X-1884752Y982191D02*
X-1888216D01*
G01X-1877823Y987821D02*
Y979160D01*
G01X-1880313Y987821D02*
X-1875333D01*
G01X-1863208Y979160D02*
X-1860501Y987821D01*
X-1857794Y979160D01*
G01X-1858769Y982191D02*
X-1862233D01*
G01X-1854005Y987821D02*
Y979160D01*
X-1849675D01*
G01X-1845344Y987821D02*
Y979160D01*
X-1841014D01*
G01X-1828022Y987821D02*
Y979160D01*
X-1823692D01*
G01X-1819903D02*
X-1817196Y987821D01*
X-1814489Y979160D01*
G01X-1815464Y982191D02*
X-1818928D01*
G01X-1808535Y979160D02*
Y983057D01*
X-1810700Y987821D01*
G01X-1806370D02*
X-1808535Y983057D01*
G01X-1797709Y979160D02*
X-1802039D01*
Y987821D01*
X-1797709D01*
G01X-1799441Y983635D02*
X-1802039D01*
G01X-1793378Y979160D02*
Y987821D01*
X-1790672D01*
X-1789806Y987388D01*
X-1789264Y986811D01*
X-1789048Y985656D01*
X-1789264Y984501D01*
X-1789914Y983779D01*
X-1790672Y983346D01*
X-1793378D01*
G01X-1790672D02*
X-1789048Y979160D01*
G01X-1784826Y980315D02*
X-1783959Y979593D01*
X-1782985Y979160D01*
X-1782119D01*
X-1781253Y979593D01*
X-1780603Y980315D01*
X-1780278Y981325D01*
X-1780495Y982336D01*
X-1781036Y983202D01*
X-1782011Y983779D01*
X-1783310Y984068D01*
X-1784068Y984645D01*
X-1784393Y985656D01*
X-1784176Y986666D01*
X-1783635Y987388D01*
X-1782877Y987821D01*
X-1782119D01*
X-1781361Y987532D01*
X-1780711Y986811D01*
G01X-1763065Y979160D02*
X-1767395D01*
Y987821D01*
X-1763065D01*
G01X-1764797Y983635D02*
X-1767395D01*
G01X-1758843Y979160D02*
X-1754295Y987821D01*
G01X-1758843D02*
X-1754295Y979160D01*
G01X-1745526Y987099D02*
X-1746176Y987532D01*
X-1746934Y987821D01*
X-1747800D01*
X-1748774Y987388D01*
X-1749532Y986666D01*
X-1750073Y985800D01*
X-1750507Y984357D01*
X-1750615Y983057D01*
X-1750398Y981758D01*
X-1750073Y980892D01*
X-1749424Y980026D01*
X-1748666Y979449D01*
X-1747908Y979160D01*
X-1747150D01*
X-1746392Y979449D01*
X-1745743Y979882D01*
X-1745201Y980459D01*
G01X-1737082Y979160D02*
X-1741412D01*
Y987821D01*
X-1737082D01*
G01X-1738814Y983635D02*
X-1741412D01*
G01X-1732751Y979160D02*
Y987821D01*
X-1730153D01*
X-1729287Y987388D01*
X-1728637Y986378D01*
X-1728421Y985223D01*
X-1728637Y984068D01*
X-1729179Y983202D01*
X-1730153Y982769D01*
X-1732751D01*
G01X-1721925Y987821D02*
Y979160D01*
G01X-1724415Y987821D02*
X-1719435D01*
G01X-1703953Y983490D02*
X-1701788D01*
Y980892D01*
X-1702438Y980026D01*
X-1703196Y979449D01*
X-1704278Y979160D01*
X-1705361Y979449D01*
X-1706119Y980026D01*
X-1706768Y980892D01*
X-1707202Y981903D01*
X-1707418Y983057D01*
Y984068D01*
X-1707202Y984934D01*
X-1706768Y985945D01*
X-1706119Y986811D01*
X-1705469Y987388D01*
X-1704603Y987821D01*
X-1703845D01*
X-1702979Y987532D01*
X-1702329Y986955D01*
G01X-1698432Y979160D02*
Y987821D01*
X-1693452Y979160D01*
Y987821D01*
G01X-1689663Y979160D02*
Y987821D01*
X-1687498D01*
X-1686631Y987388D01*
X-1685982Y986811D01*
X-1685440Y985945D01*
X-1685007Y984934D01*
X-1684899Y983490D01*
X-1685007Y982047D01*
X-1685440Y981036D01*
X-1685982Y980170D01*
X-1686631Y979593D01*
X-1687498Y979160D01*
X-1689663D01*
G01X-1678079Y976273D02*
X-1676996Y977717D01*
X-1676455Y979160D01*
Y984934D01*
X-1676996Y986378D01*
X-1678079Y987821D01*
G01X-1981104Y1182414D02*
X-1982187Y1183858D01*
X-1982728Y1185301D01*
Y1191075D01*
X-1982187Y1192519D01*
X-1981104Y1193962D01*
G01X-1974067Y1185301D02*
Y1193962D01*
X-1971469D01*
X-1970603Y1193529D01*
X-1969953Y1192519D01*
X-1969737Y1191364D01*
X-1969953Y1190209D01*
X-1970495Y1189343D01*
X-1971469Y1188910D01*
X-1974067D01*
G01X-1965948Y1185301D02*
X-1963241Y1193962D01*
X-1960534Y1185301D01*
G01X-1961509Y1188332D02*
X-1964973D01*
G01X-1956962Y1185301D02*
Y1193962D01*
X-1954797D01*
X-1953930Y1193529D01*
X-1953281Y1192952D01*
X-1952739Y1192086D01*
X-1952306Y1191075D01*
X-1952198Y1189631D01*
X-1952306Y1188188D01*
X-1952739Y1187177D01*
X-1953281Y1186311D01*
X-1953930Y1185734D01*
X-1954797Y1185301D01*
X-1956962D01*
G01X-1945378Y1182414D02*
X-1944295Y1183858D01*
X-1943754Y1185301D01*
Y1191075D01*
X-1944295Y1192519D01*
X-1945378Y1193962D01*
G01X-1937799Y1182414D02*
X-1938882Y1183858D01*
X-1939423Y1185301D01*
Y1191075D01*
X-1938882Y1192519D01*
X-1937799Y1193962D01*
G01X-1931087Y1185301D02*
Y1193962D01*
X-1926107Y1185301D01*
Y1193962D01*
G01X-1919936Y1185301D02*
X-1920802Y1185445D01*
X-1921560Y1186023D01*
X-1922210Y1186889D01*
X-1922643Y1187899D01*
X-1922859Y1189054D01*
Y1190209D01*
X-1922643Y1191364D01*
X-1922210Y1192374D01*
X-1921560Y1193240D01*
X-1920802Y1193818D01*
X-1919936Y1193962D01*
X-1919070Y1193818D01*
X-1918312Y1193240D01*
X-1917662Y1192374D01*
X-1917229Y1191364D01*
X-1917013Y1190209D01*
Y1189054D01*
X-1917229Y1187899D01*
X-1917662Y1186889D01*
X-1918312Y1186023D01*
X-1919070Y1185445D01*
X-1919936Y1185301D01*
G01X-1902614Y1193962D02*
Y1185301D01*
G01X-1905104Y1193962D02*
X-1900124D01*
G01X-1896118Y1185301D02*
Y1193962D01*
X-1893412D01*
X-1892546Y1193529D01*
X-1892004Y1192952D01*
X-1891788Y1191797D01*
X-1892004Y1190642D01*
X-1892654Y1189920D01*
X-1893412Y1189487D01*
X-1896118D01*
G01X-1893412D02*
X-1891788Y1185301D01*
G01X-1887999D02*
X-1885292Y1193962D01*
X-1882585Y1185301D01*
G01X-1883560Y1188332D02*
X-1887024D01*
G01X-1874249Y1193240D02*
X-1874899Y1193673D01*
X-1875657Y1193962D01*
X-1876523D01*
X-1877497Y1193529D01*
X-1878255Y1192807D01*
X-1878796Y1191941D01*
X-1879230Y1190498D01*
X-1879338Y1189198D01*
X-1879121Y1187899D01*
X-1878796Y1187033D01*
X-1878147Y1186167D01*
X-1877389Y1185590D01*
X-1876631Y1185301D01*
X-1875873D01*
X-1875115Y1185590D01*
X-1874466Y1186023D01*
X-1873924Y1186600D01*
G01X-1865805Y1185301D02*
X-1870135D01*
Y1193962D01*
X-1865805D01*
G01X-1867537Y1189776D02*
X-1870135D01*
G01X-1853355Y1185301D02*
X-1850648Y1193962D01*
X-1847941Y1185301D01*
G01X-1848916Y1188332D02*
X-1852380D01*
G01X-1841987Y1193962D02*
Y1185301D01*
G01X-1844477Y1193962D02*
X-1839497D01*
G01X-1827372Y1185301D02*
X-1824665Y1193962D01*
X-1821958Y1185301D01*
G01X-1822933Y1188332D02*
X-1826397D01*
G01X-1818169Y1193962D02*
Y1185301D01*
X-1813839D01*
G01X-1809508Y1193962D02*
Y1185301D01*
X-1805178D01*
G01X-1792186Y1193962D02*
Y1185301D01*
X-1787856D01*
G01X-1784067D02*
X-1781360Y1193962D01*
X-1778653Y1185301D01*
G01X-1779628Y1188332D02*
X-1783092D01*
G01X-1772699Y1185301D02*
Y1189198D01*
X-1774864Y1193962D01*
G01X-1770534D02*
X-1772699Y1189198D01*
G01X-1761873Y1185301D02*
X-1766203D01*
Y1193962D01*
X-1761873D01*
G01X-1763605Y1189776D02*
X-1766203D01*
G01X-1757542Y1185301D02*
Y1193962D01*
X-1754836D01*
X-1753970Y1193529D01*
X-1753428Y1192952D01*
X-1753212Y1191797D01*
X-1753428Y1190642D01*
X-1754078Y1189920D01*
X-1754836Y1189487D01*
X-1757542D01*
G01X-1754836D02*
X-1753212Y1185301D01*
G01X-1748990Y1186456D02*
X-1748123Y1185734D01*
X-1747149Y1185301D01*
X-1746283D01*
X-1745417Y1185734D01*
X-1744767Y1186456D01*
X-1744442Y1187466D01*
X-1744659Y1188477D01*
X-1745200Y1189343D01*
X-1746175Y1189920D01*
X-1747474Y1190209D01*
X-1748232Y1190786D01*
X-1748557Y1191797D01*
X-1748340Y1192807D01*
X-1747799Y1193529D01*
X-1747041Y1193962D01*
X-1746283D01*
X-1745525Y1193673D01*
X-1744875Y1192952D01*
G01X-1737514Y1182414D02*
X-1736431Y1183858D01*
X-1735890Y1185301D01*
Y1191075D01*
X-1736431Y1192519D01*
X-1737514Y1193962D01*
G01X-1926174Y-852846D02*
Y-841484D01*
X-1927878Y-843756D01*
G01Y-852846D02*
X-1924470D01*
G01X-1915011Y900021D02*
X-1914144Y899299D01*
X-1913170Y898866D01*
X-1912304D01*
X-1911438Y899299D01*
X-1910788Y900021D01*
X-1910463Y901031D01*
X-1910680Y902042D01*
X-1911221Y902908D01*
X-1912196Y903485D01*
X-1913495Y903774D01*
X-1914253Y904351D01*
X-1914578Y905362D01*
X-1914361Y906372D01*
X-1913820Y907094D01*
X-1913062Y907527D01*
X-1912304D01*
X-1911546Y907238D01*
X-1910896Y906517D01*
G01X-1906891Y898866D02*
Y907527D01*
X-1904076Y900309D01*
X-1901261Y907527D01*
Y898866D01*
G01X-1895415Y907527D02*
Y898866D01*
G01X-1897905Y907527D02*
X-1892925D01*
G01X-1880583Y898866D02*
Y907527D01*
X-1875603Y898866D01*
Y907527D01*
G01X-1871814D02*
Y901320D01*
X-1871381Y900021D01*
X-1870515Y899155D01*
X-1869432Y898866D01*
X-1868349Y899155D01*
X-1867483Y900021D01*
X-1867050Y901320D01*
Y907527D01*
G01X-1860771D02*
Y898866D01*
G01X-1863261Y907527D02*
X-1858281D01*
G01X-1852651Y895979D02*
X-1853734Y897423D01*
X-1854275Y898866D01*
Y904640D01*
X-1853734Y906084D01*
X-1852651Y907527D01*
G01X-1843449D02*
X-1844315Y907238D01*
X-1844965Y906517D01*
X-1845398Y905651D01*
X-1845723Y904496D01*
X-1845831Y903196D01*
X-1845723Y901897D01*
X-1845398Y900742D01*
X-1844965Y899876D01*
X-1844315Y899155D01*
X-1843449Y898866D01*
X-1842583Y899155D01*
X-1841933Y899876D01*
X-1841500Y900742D01*
X-1841175Y901897D01*
X-1841067Y903196D01*
X-1841175Y904496D01*
X-1841500Y905651D01*
X-1841933Y906517D01*
X-1842583Y907238D01*
X-1843449Y907527D01*
G01X-1834788Y898866D02*
X-1834030Y899010D01*
X-1833164Y899443D01*
X-1832623Y900165D01*
X-1832406Y901176D01*
X-1832623Y902186D01*
X-1833272Y903052D01*
X-1834247Y903485D01*
X-1835329D01*
X-1835979Y903774D01*
X-1836520Y904496D01*
X-1836737Y905506D01*
X-1836412Y906517D01*
X-1835654Y907238D01*
X-1834788Y907527D01*
X-1833922Y907238D01*
X-1833164Y906517D01*
X-1832839Y905506D01*
X-1833056Y904496D01*
X-1833597Y903774D01*
X-1834247Y903485D01*
X-1835329D01*
X-1836304Y903052D01*
X-1836953Y902186D01*
X-1837170Y901176D01*
X-1836953Y900165D01*
X-1836412Y899443D01*
X-1835546Y899010D01*
X-1834788Y898866D01*
G01X-1826344D02*
X-1826127Y900742D01*
X-1825802Y902330D01*
X-1825369Y903774D01*
X-1824828Y905362D01*
X-1823962Y907527D01*
X-1828292D01*
G01X-1820714Y895979D02*
X-1814218D01*
G01X-1809022Y898866D02*
X-1808805Y900742D01*
X-1808480Y902330D01*
X-1808047Y903774D01*
X-1807506Y905362D01*
X-1806640Y907527D01*
X-1810970D01*
G01X-1800144Y898866D02*
Y907527D01*
X-1801443Y905795D01*
G01Y898866D02*
X-1798845D01*
G01X-1793540Y906084D02*
X-1792890Y906949D01*
X-1792133Y907383D01*
X-1791266Y907527D01*
X-1790184Y907238D01*
X-1789426Y906517D01*
X-1789209Y905651D01*
X-1789318Y904784D01*
X-1789751Y904063D01*
X-1791916Y902619D01*
X-1792890Y901609D01*
X-1793540Y900165D01*
X-1793757Y898866D01*
X-1789209D01*
G01X-1781523D02*
Y907527D01*
X-1785529Y901320D01*
X-1780115D01*
G01X-1776218Y906084D02*
X-1775568Y906949D01*
X-1774811Y907383D01*
X-1773944Y907527D01*
X-1772862Y907238D01*
X-1772104Y906517D01*
X-1771887Y905651D01*
X-1771996Y904784D01*
X-1772429Y904063D01*
X-1774594Y902619D01*
X-1775568Y901609D01*
X-1776218Y900165D01*
X-1776435Y898866D01*
X-1771887D01*
G01X-1768748Y895979D02*
X-1762252D01*
G01X-1756839Y907527D02*
X-1757705Y907238D01*
X-1758355Y906517D01*
X-1758788Y905651D01*
X-1759113Y904496D01*
X-1759221Y903196D01*
X-1759113Y901897D01*
X-1758788Y900742D01*
X-1758355Y899876D01*
X-1757705Y899155D01*
X-1756839Y898866D01*
X-1755973Y899155D01*
X-1755323Y899876D01*
X-1754890Y900742D01*
X-1754565Y901897D01*
X-1754457Y903196D01*
X-1754565Y904496D01*
X-1754890Y905651D01*
X-1755323Y906517D01*
X-1755973Y907238D01*
X-1756839Y907527D01*
G01X-1746879Y898866D02*
Y907527D01*
X-1750885Y901320D01*
X-1745471D01*
G01X-1741574Y902475D02*
X-1740816Y903485D01*
X-1740167Y904063D01*
X-1739300Y904351D01*
X-1738543Y904063D01*
X-1738001Y903485D01*
X-1737568Y902619D01*
X-1737460Y901609D01*
X-1737568Y900742D01*
X-1738001Y899876D01*
X-1738651Y899155D01*
X-1739409Y898866D01*
X-1740275Y899155D01*
X-1741033Y900021D01*
X-1741466Y901320D01*
X-1741574Y902763D01*
X-1741358Y904640D01*
X-1741033Y905651D01*
X-1740491Y906661D01*
X-1739734Y907383D01*
X-1738976Y907527D01*
X-1738218Y907238D01*
X-1737676Y906517D01*
G01X-1733238Y900165D02*
X-1732588Y899443D01*
X-1731830Y899010D01*
X-1730856Y898866D01*
X-1729882Y899155D01*
X-1729124Y899732D01*
X-1728582Y900742D01*
X-1728474Y901897D01*
X-1728691Y903052D01*
X-1729232Y903774D01*
X-1729990Y904351D01*
X-1730748Y904496D01*
X-1731506Y904351D01*
X-1732480Y903774D01*
X-1732155Y907527D01*
X-1729232D01*
G01X-1721654Y895979D02*
X-1720571Y897423D01*
X-1720030Y898866D01*
Y904640D01*
X-1720571Y906084D01*
X-1721654Y907527D01*
G01X-1926174Y1324910D02*
Y1336272D01*
X-1927878Y1334000D01*
G01Y1324910D02*
X-1924470D01*
G01X-1827698Y979160D02*
Y984934D01*
G01Y983490D02*
X-1827264Y984212D01*
X-1826615Y984790D01*
X-1825749Y984934D01*
X-1824991Y984790D01*
X-1824341Y984212D01*
X-1824016Y983202D01*
Y979160D01*
G01X-1839066D02*
X-1838849Y981036D01*
X-1838524Y982624D01*
X-1838091Y984068D01*
X-1837550Y985656D01*
X-1836684Y987821D01*
X-1841014D01*
G01X-1830188Y978871D02*
X-1830405Y979016D01*
Y979304D01*
X-1830188Y979449D01*
X-1829971Y979304D01*
Y979016D01*
X-1830188Y978871D01*
G01X-1823909Y980459D02*
X-1823259Y979737D01*
X-1822501Y979304D01*
X-1821527Y979160D01*
X-1820553Y979449D01*
X-1819795Y980026D01*
X-1819253Y981036D01*
X-1819145Y982191D01*
X-1819362Y983346D01*
X-1819903Y984068D01*
X-1820661Y984645D01*
X-1821419Y984790D01*
X-1822177Y984645D01*
X-1823151Y984068D01*
X-1822826Y987821D01*
X-1819903D01*
G01X-1812866D02*
X-1813732Y987532D01*
X-1814382Y986811D01*
X-1814815Y985945D01*
X-1815140Y984790D01*
X-1815248Y983490D01*
X-1815140Y982191D01*
X-1814815Y981036D01*
X-1814382Y980170D01*
X-1813732Y979449D01*
X-1812866Y979160D01*
X-1812000Y979449D01*
X-1811350Y980170D01*
X-1810917Y981036D01*
X-1810592Y982191D01*
X-1810484Y983490D01*
X-1810592Y984790D01*
X-1810917Y985945D01*
X-1811350Y986811D01*
X-1812000Y987532D01*
X-1812866Y987821D01*
G01X-1874142Y1186311D02*
X-1873384Y1185590D01*
X-1872518Y1185301D01*
X-1871651Y1185590D01*
X-1870894Y1186456D01*
X-1870352Y1187755D01*
X-1870136Y1189054D01*
Y1190642D01*
X-1870352Y1191941D01*
X-1870894Y1193096D01*
X-1871543Y1193673D01*
X-1872301Y1193962D01*
X-1873167Y1193673D01*
X-1873817Y1193096D01*
X-1874250Y1192230D01*
X-1874466Y1191075D01*
X-1874250Y1190065D01*
X-1873708Y1189054D01*
X-1873059Y1188477D01*
X-1872301Y1188332D01*
X-1871435Y1188621D01*
X-1870785Y1189343D01*
X-1870136Y1190642D01*
G01X-1863640Y1185012D02*
X-1863857Y1185157D01*
Y1185445D01*
X-1863640Y1185590D01*
X-1863423Y1185445D01*
Y1185157D01*
X-1863640Y1185012D01*
G01X-1857361Y1186600D02*
X-1856711Y1185878D01*
X-1855953Y1185445D01*
X-1854979Y1185301D01*
X-1854005Y1185590D01*
X-1853247Y1186167D01*
X-1852705Y1187177D01*
X-1852597Y1188332D01*
X-1852814Y1189487D01*
X-1853355Y1190209D01*
X-1854113Y1190786D01*
X-1854871Y1190931D01*
X-1855629Y1190786D01*
X-1856603Y1190209D01*
X-1856278Y1193962D01*
X-1853355D01*
G01X-1846318D02*
X-1847184Y1193673D01*
X-1847834Y1192952D01*
X-1848267Y1192086D01*
X-1848592Y1190931D01*
X-1848700Y1189631D01*
X-1848592Y1188332D01*
X-1848267Y1187177D01*
X-1847834Y1186311D01*
X-1847184Y1185590D01*
X-1846318Y1185301D01*
X-1845452Y1185590D01*
X-1844802Y1186311D01*
X-1844369Y1187177D01*
X-1844044Y1188332D01*
X-1843936Y1189631D01*
X-1844044Y1190931D01*
X-1844369Y1192086D01*
X-1844802Y1192952D01*
X-1845452Y1193673D01*
X-1846318Y1193962D01*
G01X-1793337Y-644235D02*
X-1794203Y-644524D01*
X-1794853Y-645245D01*
X-1795286Y-646111D01*
X-1795611Y-647266D01*
X-1795719Y-648566D01*
X-1795611Y-649865D01*
X-1795286Y-651020D01*
X-1794853Y-651886D01*
X-1794203Y-652607D01*
X-1793337Y-652896D01*
X-1792471Y-652607D01*
X-1791821Y-651886D01*
X-1791388Y-651020D01*
X-1791063Y-649865D01*
X-1790955Y-648566D01*
X-1791063Y-647266D01*
X-1791388Y-646111D01*
X-1791821Y-645245D01*
X-1792471Y-644524D01*
X-1793337Y-644235D01*
G01X-1784676Y-653185D02*
X-1784893Y-653040D01*
Y-652752D01*
X-1784676Y-652607D01*
X-1784459Y-652752D01*
Y-653040D01*
X-1784676Y-653185D01*
G01X-1776015Y-644235D02*
X-1776881Y-644524D01*
X-1777531Y-645245D01*
X-1777964Y-646111D01*
X-1778289Y-647266D01*
X-1778397Y-648566D01*
X-1778289Y-649865D01*
X-1777964Y-651020D01*
X-1777531Y-651886D01*
X-1776881Y-652607D01*
X-1776015Y-652896D01*
X-1775149Y-652607D01*
X-1774499Y-651886D01*
X-1774066Y-651020D01*
X-1773741Y-649865D01*
X-1773633Y-648566D01*
X-1773741Y-647266D01*
X-1774066Y-646111D01*
X-1774499Y-645245D01*
X-1775149Y-644524D01*
X-1776015Y-644235D01*
G01X-1767354D02*
X-1768220Y-644524D01*
X-1768870Y-645245D01*
X-1769303Y-646111D01*
X-1769628Y-647266D01*
X-1769736Y-648566D01*
X-1769628Y-649865D01*
X-1769303Y-651020D01*
X-1768870Y-651886D01*
X-1768220Y-652607D01*
X-1767354Y-652896D01*
X-1766488Y-652607D01*
X-1765838Y-651886D01*
X-1765405Y-651020D01*
X-1765080Y-649865D01*
X-1764972Y-648566D01*
X-1765080Y-647266D01*
X-1765405Y-646111D01*
X-1765838Y-645245D01*
X-1766488Y-644524D01*
X-1767354Y-644235D01*
G01X-1759970Y1117008D02*
Y1125669D01*
X-1761269Y1123937D01*
G01Y1117008D02*
X-1758671D01*
G01X-1751309D02*
X-1750551Y1117152D01*
X-1749685Y1117585D01*
X-1749144Y1118307D01*
X-1748927Y1119318D01*
X-1749144Y1120328D01*
X-1749793Y1121194D01*
X-1750768Y1121627D01*
X-1751850D01*
X-1752500Y1121916D01*
X-1753041Y1122638D01*
X-1753258Y1123648D01*
X-1752933Y1124659D01*
X-1752175Y1125380D01*
X-1751309Y1125669D01*
X-1750443Y1125380D01*
X-1749685Y1124659D01*
X-1749360Y1123648D01*
X-1749577Y1122638D01*
X-1750118Y1121916D01*
X-1750768Y1121627D01*
X-1751850D01*
X-1752825Y1121194D01*
X-1753474Y1120328D01*
X-1753691Y1119318D01*
X-1753474Y1118307D01*
X-1752933Y1117585D01*
X-1752067Y1117152D01*
X-1751309Y1117008D01*
G01X-1742648D02*
X-1741890Y1117152D01*
X-1741024Y1117585D01*
X-1740483Y1118307D01*
X-1740266Y1119318D01*
X-1740483Y1120328D01*
X-1741132Y1121194D01*
X-1742107Y1121627D01*
X-1743189D01*
X-1743839Y1121916D01*
X-1744380Y1122638D01*
X-1744597Y1123648D01*
X-1744272Y1124659D01*
X-1743514Y1125380D01*
X-1742648Y1125669D01*
X-1741782Y1125380D01*
X-1741024Y1124659D01*
X-1740699Y1123648D01*
X-1740916Y1122638D01*
X-1741457Y1121916D01*
X-1742107Y1121627D01*
X-1743189D01*
X-1744164Y1121194D01*
X-1744813Y1120328D01*
X-1745030Y1119318D01*
X-1744813Y1118307D01*
X-1744272Y1117585D01*
X-1743406Y1117152D01*
X-1742648Y1117008D01*
G01X-1733987Y1116719D02*
X-1734204Y1116864D01*
Y1117152D01*
X-1733987Y1117297D01*
X-1733770Y1117152D01*
Y1116864D01*
X-1733987Y1116719D01*
G01X-1725326Y1125669D02*
X-1726192Y1125380D01*
X-1726842Y1124659D01*
X-1727275Y1123793D01*
X-1727600Y1122638D01*
X-1727708Y1121338D01*
X-1727600Y1120039D01*
X-1727275Y1118884D01*
X-1726842Y1118018D01*
X-1726192Y1117297D01*
X-1725326Y1117008D01*
X-1724460Y1117297D01*
X-1723810Y1118018D01*
X-1723377Y1118884D01*
X-1723052Y1120039D01*
X-1722944Y1121338D01*
X-1723052Y1122638D01*
X-1723377Y1123793D01*
X-1723810Y1124659D01*
X-1724460Y1125380D01*
X-1725326Y1125669D01*
G01X-1716665D02*
X-1717531Y1125380D01*
X-1718181Y1124659D01*
X-1718614Y1123793D01*
X-1718939Y1122638D01*
X-1719047Y1121338D01*
X-1718939Y1120039D01*
X-1718614Y1118884D01*
X-1718181Y1118018D01*
X-1717531Y1117297D01*
X-1716665Y1117008D01*
X-1715799Y1117297D01*
X-1715149Y1118018D01*
X-1714716Y1118884D01*
X-1714391Y1120039D01*
X-1714283Y1121338D01*
X-1714391Y1122638D01*
X-1714716Y1123793D01*
X-1715149Y1124659D01*
X-1715799Y1125380D01*
X-1716665Y1125669D01*
G01X-1711097Y-843378D02*
X-1710244Y-842242D01*
X-1709250Y-841673D01*
X-1708114Y-841484D01*
X-1706694Y-841863D01*
X-1705699Y-842810D01*
X-1705415Y-843946D01*
X-1705557Y-845082D01*
X-1706126Y-846029D01*
X-1708966Y-847922D01*
X-1710244Y-849248D01*
X-1711097Y-851142D01*
X-1711381Y-852846D01*
X-1705415D01*
G01X-1740542Y-727344D02*
X-1740253Y-728210D01*
X-1739532Y-728860D01*
X-1738666Y-729293D01*
X-1737511Y-729618D01*
X-1736211Y-729726D01*
X-1734912Y-729618D01*
X-1733757Y-729293D01*
X-1732891Y-728860D01*
X-1732170Y-728210D01*
X-1731881Y-727344D01*
X-1732170Y-726478D01*
X-1732891Y-725828D01*
X-1733757Y-725395D01*
X-1734912Y-725070D01*
X-1736211Y-724962D01*
X-1737511Y-725070D01*
X-1738666Y-725395D01*
X-1739532Y-725828D01*
X-1740253Y-726478D01*
X-1740542Y-727344D01*
G01X-1731592Y-718683D02*
X-1731737Y-718900D01*
X-1732025D01*
X-1732170Y-718683D01*
X-1732025Y-718466D01*
X-1731737D01*
X-1731592Y-718683D01*
G01X-1740542Y-710022D02*
X-1740253Y-710888D01*
X-1739532Y-711538D01*
X-1738666Y-711971D01*
X-1737511Y-712296D01*
X-1736211Y-712404D01*
X-1734912Y-712296D01*
X-1733757Y-711971D01*
X-1732891Y-711538D01*
X-1732170Y-710888D01*
X-1731881Y-710022D01*
X-1732170Y-709156D01*
X-1732891Y-708506D01*
X-1733757Y-708073D01*
X-1734912Y-707748D01*
X-1736211Y-707640D01*
X-1737511Y-707748D01*
X-1738666Y-708073D01*
X-1739532Y-708506D01*
X-1740253Y-709156D01*
X-1740542Y-710022D01*
G01Y-701361D02*
X-1740253Y-702227D01*
X-1739532Y-702877D01*
X-1738666Y-703310D01*
X-1737511Y-703635D01*
X-1736211Y-703743D01*
X-1734912Y-703635D01*
X-1733757Y-703310D01*
X-1732891Y-702877D01*
X-1732170Y-702227D01*
X-1731881Y-701361D01*
X-1732170Y-700495D01*
X-1732891Y-699845D01*
X-1733757Y-699412D01*
X-1734912Y-699087D01*
X-1736211Y-698979D01*
X-1737511Y-699087D01*
X-1738666Y-699412D01*
X-1739532Y-699845D01*
X-1740253Y-700495D01*
X-1740542Y-701361D01*
G01X-1735718Y385511D02*
X-1736584Y385222D01*
X-1737234Y384501D01*
X-1737667Y383635D01*
X-1737992Y382480D01*
X-1738100Y381180D01*
X-1737992Y379881D01*
X-1737667Y378726D01*
X-1737234Y377860D01*
X-1736584Y377139D01*
X-1735718Y376850D01*
X-1734852Y377139D01*
X-1734202Y377860D01*
X-1733769Y378726D01*
X-1733444Y379881D01*
X-1733336Y381180D01*
X-1733444Y382480D01*
X-1733769Y383635D01*
X-1734202Y384501D01*
X-1734852Y385222D01*
X-1735718Y385511D01*
G01X-1727057Y376561D02*
X-1727274Y376706D01*
Y376994D01*
X-1727057Y377139D01*
X-1726840Y376994D01*
Y376706D01*
X-1727057Y376561D01*
G01X-1718396Y385511D02*
X-1719262Y385222D01*
X-1719912Y384501D01*
X-1720345Y383635D01*
X-1720670Y382480D01*
X-1720778Y381180D01*
X-1720670Y379881D01*
X-1720345Y378726D01*
X-1719912Y377860D01*
X-1719262Y377139D01*
X-1718396Y376850D01*
X-1717530Y377139D01*
X-1716880Y377860D01*
X-1716447Y378726D01*
X-1716122Y379881D01*
X-1716014Y381180D01*
X-1716122Y382480D01*
X-1716447Y383635D01*
X-1716880Y384501D01*
X-1717530Y385222D01*
X-1718396Y385511D01*
G01X-1709735D02*
X-1710601Y385222D01*
X-1711251Y384501D01*
X-1711684Y383635D01*
X-1712009Y382480D01*
X-1712117Y381180D01*
X-1712009Y379881D01*
X-1711684Y378726D01*
X-1711251Y377860D01*
X-1710601Y377139D01*
X-1709735Y376850D01*
X-1708869Y377139D01*
X-1708219Y377860D01*
X-1707786Y378726D01*
X-1707461Y379881D01*
X-1707353Y381180D01*
X-1707461Y382480D01*
X-1707786Y383635D01*
X-1708219Y384501D01*
X-1708869Y385222D01*
X-1709735Y385511D01*
G01X-1746003Y482494D02*
X-1745353Y483359D01*
X-1744596Y483793D01*
X-1743729Y483937D01*
X-1742647Y483648D01*
X-1741889Y482927D01*
X-1741672Y482061D01*
X-1741781Y481194D01*
X-1742214Y480473D01*
X-1744379Y479029D01*
X-1745353Y478019D01*
X-1746003Y476575D01*
X-1746220Y475276D01*
X-1741672D01*
G01X-1737667Y476575D02*
X-1737017Y475853D01*
X-1736259Y475420D01*
X-1735285Y475276D01*
X-1734311Y475565D01*
X-1733553Y476142D01*
X-1733011Y477152D01*
X-1732903Y478307D01*
X-1733120Y479462D01*
X-1733661Y480184D01*
X-1734419Y480761D01*
X-1735177Y480906D01*
X-1735935Y480761D01*
X-1736909Y480184D01*
X-1736584Y483937D01*
X-1733661D01*
G01X-1726624Y474987D02*
X-1726841Y475132D01*
Y475420D01*
X-1726624Y475565D01*
X-1726407Y475420D01*
Y475132D01*
X-1726624Y474987D01*
G01X-1717963Y483937D02*
X-1718829Y483648D01*
X-1719479Y482927D01*
X-1719912Y482061D01*
X-1720237Y480906D01*
X-1720345Y479606D01*
X-1720237Y478307D01*
X-1719912Y477152D01*
X-1719479Y476286D01*
X-1718829Y475565D01*
X-1717963Y475276D01*
X-1717097Y475565D01*
X-1716447Y476286D01*
X-1716014Y477152D01*
X-1715689Y478307D01*
X-1715581Y479606D01*
X-1715689Y480906D01*
X-1716014Y482061D01*
X-1716447Y482927D01*
X-1717097Y483648D01*
X-1717963Y483937D01*
G01X-1709302D02*
X-1710168Y483648D01*
X-1710818Y482927D01*
X-1711251Y482061D01*
X-1711576Y480906D01*
X-1711684Y479606D01*
X-1711576Y478307D01*
X-1711251Y477152D01*
X-1710818Y476286D01*
X-1710168Y475565D01*
X-1709302Y475276D01*
X-1708436Y475565D01*
X-1707786Y476286D01*
X-1707353Y477152D01*
X-1707028Y478307D01*
X-1706920Y479606D01*
X-1707028Y480906D01*
X-1707353Y482061D01*
X-1707786Y482927D01*
X-1708436Y483648D01*
X-1709302Y483937D01*
G01X-1746003Y618845D02*
X-1745245Y619855D01*
X-1744596Y620433D01*
X-1743729Y620721D01*
X-1742972Y620433D01*
X-1742430Y619855D01*
X-1741997Y618989D01*
X-1741889Y617979D01*
X-1741997Y617112D01*
X-1742430Y616246D01*
X-1743080Y615525D01*
X-1743838Y615236D01*
X-1744704Y615525D01*
X-1745462Y616391D01*
X-1745895Y617690D01*
X-1746003Y619133D01*
X-1745787Y621010D01*
X-1745462Y622021D01*
X-1744920Y623031D01*
X-1744163Y623753D01*
X-1743405Y623897D01*
X-1742647Y623608D01*
X-1742105Y622887D01*
G01X-1735285Y623897D02*
X-1736151Y623608D01*
X-1736801Y622887D01*
X-1737234Y622021D01*
X-1737559Y620866D01*
X-1737667Y619566D01*
X-1737559Y618267D01*
X-1737234Y617112D01*
X-1736801Y616246D01*
X-1736151Y615525D01*
X-1735285Y615236D01*
X-1734419Y615525D01*
X-1733769Y616246D01*
X-1733336Y617112D01*
X-1733011Y618267D01*
X-1732903Y619566D01*
X-1733011Y620866D01*
X-1733336Y622021D01*
X-1733769Y622887D01*
X-1734419Y623608D01*
X-1735285Y623897D01*
G01X-1726624Y614947D02*
X-1726841Y615092D01*
Y615380D01*
X-1726624Y615525D01*
X-1726407Y615380D01*
Y615092D01*
X-1726624Y614947D01*
G01X-1720345Y616535D02*
X-1719695Y615813D01*
X-1718937Y615380D01*
X-1717963Y615236D01*
X-1716989Y615525D01*
X-1716231Y616102D01*
X-1715689Y617112D01*
X-1715581Y618267D01*
X-1715798Y619422D01*
X-1716339Y620144D01*
X-1717097Y620721D01*
X-1717855Y620866D01*
X-1718613Y620721D01*
X-1719587Y620144D01*
X-1719262Y623897D01*
X-1716339D01*
G01X-1711684Y616535D02*
X-1711034Y615813D01*
X-1710276Y615380D01*
X-1709302Y615236D01*
X-1708328Y615525D01*
X-1707570Y616102D01*
X-1707028Y617112D01*
X-1706920Y618267D01*
X-1707137Y619422D01*
X-1707678Y620144D01*
X-1708436Y620721D01*
X-1709194Y620866D01*
X-1709952Y620721D01*
X-1710926Y620144D01*
X-1710601Y623897D01*
X-1707678D01*
G01X-1752175Y790433D02*
Y799094D01*
X-1753474Y797362D01*
G01Y790433D02*
X-1750876D01*
G01X-1743514Y799094D02*
X-1744380Y798805D01*
X-1745030Y798084D01*
X-1745463Y797218D01*
X-1745788Y796063D01*
X-1745896Y794763D01*
X-1745788Y793464D01*
X-1745463Y792309D01*
X-1745030Y791443D01*
X-1744380Y790722D01*
X-1743514Y790433D01*
X-1742648Y790722D01*
X-1741998Y791443D01*
X-1741565Y792309D01*
X-1741240Y793464D01*
X-1741132Y794763D01*
X-1741240Y796063D01*
X-1741565Y797218D01*
X-1741998Y798084D01*
X-1742648Y798805D01*
X-1743514Y799094D01*
G01X-1737235Y791732D02*
X-1736585Y791010D01*
X-1735827Y790577D01*
X-1734853Y790433D01*
X-1733879Y790722D01*
X-1733121Y791299D01*
X-1732579Y792309D01*
X-1732471Y793464D01*
X-1732688Y794619D01*
X-1733229Y795341D01*
X-1733987Y795918D01*
X-1734745Y796063D01*
X-1735503Y795918D01*
X-1736477Y795341D01*
X-1736152Y799094D01*
X-1733229D01*
G01X-1726192Y790144D02*
X-1726409Y790289D01*
Y790577D01*
X-1726192Y790722D01*
X-1725975Y790577D01*
Y790289D01*
X-1726192Y790144D01*
G01X-1717531Y799094D02*
X-1718397Y798805D01*
X-1719047Y798084D01*
X-1719480Y797218D01*
X-1719805Y796063D01*
X-1719913Y794763D01*
X-1719805Y793464D01*
X-1719480Y792309D01*
X-1719047Y791443D01*
X-1718397Y790722D01*
X-1717531Y790433D01*
X-1716665Y790722D01*
X-1716015Y791443D01*
X-1715582Y792309D01*
X-1715257Y793464D01*
X-1715149Y794763D01*
X-1715257Y796063D01*
X-1715582Y797218D01*
X-1716015Y798084D01*
X-1716665Y798805D01*
X-1717531Y799094D01*
G01X-1711252Y791732D02*
X-1710602Y791010D01*
X-1709844Y790577D01*
X-1708870Y790433D01*
X-1707896Y790722D01*
X-1707138Y791299D01*
X-1706596Y792309D01*
X-1706488Y793464D01*
X-1706705Y794619D01*
X-1707246Y795341D01*
X-1708004Y795918D01*
X-1708762Y796063D01*
X-1709520Y795918D01*
X-1710494Y795341D01*
X-1710169Y799094D01*
X-1707246D01*
G01X-1752175Y810118D02*
Y818779D01*
X-1753474Y817047D01*
G01Y810118D02*
X-1750876D01*
G01X-1743514D02*
Y818779D01*
X-1744813Y817047D01*
G01Y810118D02*
X-1742215D01*
G01X-1734853Y818779D02*
X-1735719Y818490D01*
X-1736369Y817769D01*
X-1736802Y816903D01*
X-1737127Y815748D01*
X-1737235Y814448D01*
X-1737127Y813149D01*
X-1736802Y811994D01*
X-1736369Y811128D01*
X-1735719Y810407D01*
X-1734853Y810118D01*
X-1733987Y810407D01*
X-1733337Y811128D01*
X-1732904Y811994D01*
X-1732579Y813149D01*
X-1732471Y814448D01*
X-1732579Y815748D01*
X-1732904Y816903D01*
X-1733337Y817769D01*
X-1733987Y818490D01*
X-1734853Y818779D01*
G01X-1726192Y809829D02*
X-1726409Y809974D01*
Y810262D01*
X-1726192Y810407D01*
X-1725975Y810262D01*
Y809974D01*
X-1726192Y809829D01*
G01X-1717531Y818779D02*
X-1718397Y818490D01*
X-1719047Y817769D01*
X-1719480Y816903D01*
X-1719805Y815748D01*
X-1719913Y814448D01*
X-1719805Y813149D01*
X-1719480Y811994D01*
X-1719047Y811128D01*
X-1718397Y810407D01*
X-1717531Y810118D01*
X-1716665Y810407D01*
X-1716015Y811128D01*
X-1715582Y811994D01*
X-1715257Y813149D01*
X-1715149Y814448D01*
X-1715257Y815748D01*
X-1715582Y816903D01*
X-1716015Y817769D01*
X-1716665Y818490D01*
X-1717531Y818779D01*
G01X-1711252Y811417D02*
X-1710602Y810695D01*
X-1709844Y810262D01*
X-1708870Y810118D01*
X-1707896Y810407D01*
X-1707138Y810984D01*
X-1706596Y811994D01*
X-1706488Y813149D01*
X-1706705Y814304D01*
X-1707246Y815026D01*
X-1708004Y815603D01*
X-1708762Y815748D01*
X-1709520Y815603D01*
X-1710494Y815026D01*
X-1710169Y818779D01*
X-1707246D01*
G01X-1752175Y849291D02*
Y857952D01*
X-1753474Y856220D01*
G01Y849291D02*
X-1750876D01*
G01X-1745571Y856509D02*
X-1744921Y857374D01*
X-1744164Y857808D01*
X-1743297Y857952D01*
X-1742215Y857663D01*
X-1741457Y856942D01*
X-1741240Y856076D01*
X-1741349Y855209D01*
X-1741782Y854488D01*
X-1743947Y853044D01*
X-1744921Y852034D01*
X-1745571Y850590D01*
X-1745788Y849291D01*
X-1741240D01*
G01X-1734853Y857952D02*
X-1735719Y857663D01*
X-1736369Y856942D01*
X-1736802Y856076D01*
X-1737127Y854921D01*
X-1737235Y853621D01*
X-1737127Y852322D01*
X-1736802Y851167D01*
X-1736369Y850301D01*
X-1735719Y849580D01*
X-1734853Y849291D01*
X-1733987Y849580D01*
X-1733337Y850301D01*
X-1732904Y851167D01*
X-1732579Y852322D01*
X-1732471Y853621D01*
X-1732579Y854921D01*
X-1732904Y856076D01*
X-1733337Y856942D01*
X-1733987Y857663D01*
X-1734853Y857952D01*
G01X-1726192Y849002D02*
X-1726409Y849147D01*
Y849435D01*
X-1726192Y849580D01*
X-1725975Y849435D01*
Y849147D01*
X-1726192Y849002D01*
G01X-1717531Y857952D02*
X-1718397Y857663D01*
X-1719047Y856942D01*
X-1719480Y856076D01*
X-1719805Y854921D01*
X-1719913Y853621D01*
X-1719805Y852322D01*
X-1719480Y851167D01*
X-1719047Y850301D01*
X-1718397Y849580D01*
X-1717531Y849291D01*
X-1716665Y849580D01*
X-1716015Y850301D01*
X-1715582Y851167D01*
X-1715257Y852322D01*
X-1715149Y853621D01*
X-1715257Y854921D01*
X-1715582Y856076D01*
X-1716015Y856942D01*
X-1716665Y857663D01*
X-1717531Y857952D01*
G01X-1708870D02*
X-1709736Y857663D01*
X-1710386Y856942D01*
X-1710819Y856076D01*
X-1711144Y854921D01*
X-1711252Y853621D01*
X-1711144Y852322D01*
X-1710819Y851167D01*
X-1710386Y850301D01*
X-1709736Y849580D01*
X-1708870Y849291D01*
X-1708004Y849580D01*
X-1707354Y850301D01*
X-1706921Y851167D01*
X-1706596Y852322D01*
X-1706488Y853621D01*
X-1706596Y854921D01*
X-1706921Y856076D01*
X-1707354Y856942D01*
X-1708004Y857663D01*
X-1708870Y857952D01*
G01X-1732123Y1031320D02*
Y1039981D01*
X-1736129Y1033774D01*
X-1730715D01*
G01X-1724761Y1031031D02*
X-1724978Y1031176D01*
Y1031464D01*
X-1724761Y1031609D01*
X-1724544Y1031464D01*
Y1031176D01*
X-1724761Y1031031D01*
G01X-1718157Y1038538D02*
X-1717507Y1039403D01*
X-1716750Y1039837D01*
X-1715883Y1039981D01*
X-1714801Y1039692D01*
X-1714043Y1038971D01*
X-1713826Y1038105D01*
X-1713935Y1037238D01*
X-1714368Y1036517D01*
X-1716533Y1035073D01*
X-1717507Y1034063D01*
X-1718157Y1032619D01*
X-1718374Y1031320D01*
X-1713826D01*
G01X-1707439Y1039981D02*
X-1708305Y1039692D01*
X-1708955Y1038971D01*
X-1709388Y1038105D01*
X-1709713Y1036950D01*
X-1709821Y1035650D01*
X-1709713Y1034351D01*
X-1709388Y1033196D01*
X-1708955Y1032330D01*
X-1708305Y1031609D01*
X-1707439Y1031320D01*
X-1706573Y1031609D01*
X-1705923Y1032330D01*
X-1705490Y1033196D01*
X-1705165Y1034351D01*
X-1705057Y1035650D01*
X-1705165Y1036950D01*
X-1705490Y1038105D01*
X-1705923Y1038971D01*
X-1706573Y1039692D01*
X-1707439Y1039981D01*
G01X-1738293Y1028433D02*
X-1739376Y1029877D01*
X-1739917Y1031320D01*
Y1037094D01*
X-1739376Y1038538D01*
X-1738293Y1039981D01*
G01X-1731256Y1031320D02*
Y1039981D01*
X-1728658D01*
X-1727792Y1039548D01*
X-1727142Y1038538D01*
X-1726926Y1037383D01*
X-1727142Y1036228D01*
X-1727684Y1035362D01*
X-1728658Y1034929D01*
X-1731256D01*
G01X-1720430Y1039981D02*
Y1031320D01*
G01X-1722920Y1039981D02*
X-1717940D01*
G01X-1714043Y1031320D02*
Y1039981D01*
G01X-1709495D02*
Y1031320D01*
G01Y1035650D02*
X-1714043D01*
G01X-1702567Y1028433D02*
X-1701484Y1029877D01*
X-1700943Y1031320D01*
Y1037094D01*
X-1701484Y1038538D01*
X-1702567Y1039981D01*
G01X-1722271Y1031320D02*
Y1037094D01*
G01Y1035650D02*
X-1721837Y1036372D01*
X-1721188Y1036950D01*
X-1720322Y1037094D01*
X-1719564Y1036950D01*
X-1718914Y1036372D01*
X-1718589Y1035362D01*
Y1031320D01*
G01X-1733217Y1087660D02*
Y1093434D01*
G01Y1091990D02*
X-1732783Y1092712D01*
X-1732134Y1093290D01*
X-1731268Y1093434D01*
X-1730510Y1093290D01*
X-1729860Y1092712D01*
X-1729535Y1091702D01*
Y1087660D01*
G01X-1743069D02*
Y1096321D01*
X-1747075Y1090114D01*
X-1741661D01*
G01X-1735707Y1087371D02*
X-1735924Y1087516D01*
Y1087804D01*
X-1735707Y1087949D01*
X-1735490Y1087804D01*
Y1087516D01*
X-1735707Y1087371D01*
G01X-1727046Y1096321D02*
X-1727912Y1096032D01*
X-1728562Y1095311D01*
X-1728995Y1094445D01*
X-1729320Y1093290D01*
X-1729428Y1091990D01*
X-1729320Y1090691D01*
X-1728995Y1089536D01*
X-1728562Y1088670D01*
X-1727912Y1087949D01*
X-1727046Y1087660D01*
X-1726180Y1087949D01*
X-1725530Y1088670D01*
X-1725097Y1089536D01*
X-1724772Y1090691D01*
X-1724664Y1091990D01*
X-1724772Y1093290D01*
X-1725097Y1094445D01*
X-1725530Y1095311D01*
X-1726180Y1096032D01*
X-1727046Y1096321D01*
G01X-1718385D02*
X-1719251Y1096032D01*
X-1719901Y1095311D01*
X-1720334Y1094445D01*
X-1720659Y1093290D01*
X-1720767Y1091990D01*
X-1720659Y1090691D01*
X-1720334Y1089536D01*
X-1719901Y1088670D01*
X-1719251Y1087949D01*
X-1718385Y1087660D01*
X-1717519Y1087949D01*
X-1716869Y1088670D01*
X-1716436Y1089536D01*
X-1716111Y1090691D01*
X-1716003Y1091990D01*
X-1716111Y1093290D01*
X-1716436Y1094445D01*
X-1716869Y1095311D01*
X-1717519Y1096032D01*
X-1718385Y1096321D01*
G01X-1749239Y1084773D02*
X-1750322Y1086217D01*
X-1750863Y1087660D01*
Y1093434D01*
X-1750322Y1094878D01*
X-1749239Y1096321D01*
G01X-1742202Y1087660D02*
Y1096321D01*
X-1739604D01*
X-1738738Y1095888D01*
X-1738088Y1094878D01*
X-1737872Y1093723D01*
X-1738088Y1092568D01*
X-1738630Y1091702D01*
X-1739604Y1091269D01*
X-1742202D01*
G01X-1731376Y1096321D02*
Y1087660D01*
G01X-1733866Y1096321D02*
X-1728886D01*
G01X-1724989Y1087660D02*
Y1096321D01*
G01X-1720441D02*
Y1087660D01*
G01Y1091990D02*
X-1724989D01*
G01X-1713513Y1084773D02*
X-1712430Y1086217D01*
X-1711889Y1087660D01*
Y1093434D01*
X-1712430Y1094878D01*
X-1713513Y1096321D01*
G01X-1741349Y1117008D02*
Y1125669D01*
X-1745355Y1119462D01*
X-1739941D01*
G01X-1735394Y1119895D02*
X-1732580D01*
G01X-1752175Y1140630D02*
Y1149291D01*
X-1753474Y1147559D01*
G01Y1140630D02*
X-1750876D01*
G01X-1745355Y1141640D02*
X-1744597Y1140919D01*
X-1743731Y1140630D01*
X-1742864Y1140919D01*
X-1742107Y1141785D01*
X-1741565Y1143084D01*
X-1741349Y1144383D01*
Y1145971D01*
X-1741565Y1147270D01*
X-1742107Y1148425D01*
X-1742756Y1149002D01*
X-1743514Y1149291D01*
X-1744380Y1149002D01*
X-1745030Y1148425D01*
X-1745463Y1147559D01*
X-1745679Y1146404D01*
X-1745463Y1145394D01*
X-1744921Y1144383D01*
X-1744272Y1143806D01*
X-1743514Y1143661D01*
X-1742648Y1143950D01*
X-1741998Y1144672D01*
X-1741349Y1145971D01*
G01X-1733554Y1140630D02*
Y1149291D01*
X-1737560Y1143084D01*
X-1732146D01*
G01X-1726192Y1140341D02*
X-1726409Y1140486D01*
Y1140774D01*
X-1726192Y1140919D01*
X-1725975Y1140774D01*
Y1140486D01*
X-1726192Y1140341D01*
G01X-1717531Y1149291D02*
X-1718397Y1149002D01*
X-1719047Y1148281D01*
X-1719480Y1147415D01*
X-1719805Y1146260D01*
X-1719913Y1144960D01*
X-1719805Y1143661D01*
X-1719480Y1142506D01*
X-1719047Y1141640D01*
X-1718397Y1140919D01*
X-1717531Y1140630D01*
X-1716665Y1140919D01*
X-1716015Y1141640D01*
X-1715582Y1142506D01*
X-1715257Y1143661D01*
X-1715149Y1144960D01*
X-1715257Y1146260D01*
X-1715582Y1147415D01*
X-1716015Y1148281D01*
X-1716665Y1149002D01*
X-1717531Y1149291D01*
G01X-1708870D02*
X-1709736Y1149002D01*
X-1710386Y1148281D01*
X-1710819Y1147415D01*
X-1711144Y1146260D01*
X-1711252Y1144960D01*
X-1711144Y1143661D01*
X-1710819Y1142506D01*
X-1710386Y1141640D01*
X-1709736Y1140919D01*
X-1708870Y1140630D01*
X-1708004Y1140919D01*
X-1707354Y1141640D01*
X-1706921Y1142506D01*
X-1706596Y1143661D01*
X-1706488Y1144960D01*
X-1706596Y1146260D01*
X-1706921Y1147415D01*
X-1707354Y1148281D01*
X-1708004Y1149002D01*
X-1708870Y1149291D01*
G01X-1711097Y1334378D02*
X-1710244Y1335514D01*
X-1709250Y1336083D01*
X-1708114Y1336272D01*
X-1706694Y1335893D01*
X-1705699Y1334946D01*
X-1705415Y1333810D01*
X-1705557Y1332674D01*
X-1706126Y1331727D01*
X-1708966Y1329834D01*
X-1710244Y1328508D01*
X-1711097Y1326614D01*
X-1711381Y1324910D01*
X-1705415D01*
G01X-1671131Y263032D02*
X-1670842Y262166D01*
X-1670121Y261516D01*
X-1669255Y261083D01*
X-1668100Y260758D01*
X-1666800Y260650D01*
X-1665501Y260758D01*
X-1664346Y261083D01*
X-1663480Y261516D01*
X-1662759Y262166D01*
X-1662470Y263032D01*
X-1662759Y263898D01*
X-1663480Y264548D01*
X-1664346Y264981D01*
X-1665501Y265306D01*
X-1666800Y265414D01*
X-1668100Y265306D01*
X-1669255Y264981D01*
X-1670121Y264548D01*
X-1670842Y263898D01*
X-1671131Y263032D01*
G01X-1662181Y271693D02*
X-1662326Y271476D01*
X-1662614D01*
X-1662759Y271693D01*
X-1662614Y271910D01*
X-1662326D01*
X-1662181Y271693D01*
G01X-1671131Y280354D02*
X-1670842Y279488D01*
X-1670121Y278838D01*
X-1669255Y278405D01*
X-1668100Y278080D01*
X-1666800Y277972D01*
X-1665501Y278080D01*
X-1664346Y278405D01*
X-1663480Y278838D01*
X-1662759Y279488D01*
X-1662470Y280354D01*
X-1662759Y281220D01*
X-1663480Y281870D01*
X-1664346Y282303D01*
X-1665501Y282628D01*
X-1666800Y282736D01*
X-1668100Y282628D01*
X-1669255Y282303D01*
X-1670121Y281870D01*
X-1670842Y281220D01*
X-1671131Y280354D01*
G01Y289015D02*
X-1670842Y288149D01*
X-1670121Y287499D01*
X-1669255Y287066D01*
X-1668100Y286741D01*
X-1666800Y286633D01*
X-1665501Y286741D01*
X-1664346Y287066D01*
X-1663480Y287499D01*
X-1662759Y288149D01*
X-1662470Y289015D01*
X-1662759Y289881D01*
X-1663480Y290531D01*
X-1664346Y290964D01*
X-1665501Y291289D01*
X-1666800Y291397D01*
X-1668100Y291289D01*
X-1669255Y290964D01*
X-1670121Y290531D01*
X-1670842Y289881D01*
X-1671131Y289015D01*
G01X-1614819Y-695153D02*
X-1615902Y-693709D01*
X-1616443Y-692266D01*
Y-686492D01*
X-1615902Y-685048D01*
X-1614819Y-683605D01*
G01X-1608107Y-692266D02*
Y-683605D01*
X-1603127Y-692266D01*
Y-683605D01*
G01X-1596956Y-692266D02*
X-1597822Y-692122D01*
X-1598580Y-691544D01*
X-1599230Y-690678D01*
X-1599663Y-689668D01*
X-1599879Y-688513D01*
Y-687358D01*
X-1599663Y-686203D01*
X-1599230Y-685193D01*
X-1598580Y-684327D01*
X-1597822Y-683749D01*
X-1596956Y-683605D01*
X-1596090Y-683749D01*
X-1595332Y-684327D01*
X-1594682Y-685193D01*
X-1594249Y-686203D01*
X-1594033Y-687358D01*
Y-688513D01*
X-1594249Y-689668D01*
X-1594682Y-690678D01*
X-1595332Y-691544D01*
X-1596090Y-692122D01*
X-1596956Y-692266D01*
G01X-1579634Y-683605D02*
Y-692266D01*
G01X-1582124Y-683605D02*
X-1577144D01*
G01X-1573138Y-692266D02*
Y-683605D01*
X-1570432D01*
X-1569566Y-684038D01*
X-1569024Y-684615D01*
X-1568808Y-685770D01*
X-1569024Y-686925D01*
X-1569674Y-687647D01*
X-1570432Y-688080D01*
X-1573138D01*
G01X-1570432D02*
X-1568808Y-692266D01*
G01X-1565019D02*
X-1562312Y-683605D01*
X-1559605Y-692266D01*
G01X-1560580Y-689235D02*
X-1564044D01*
G01X-1551269Y-684327D02*
X-1551919Y-683894D01*
X-1552677Y-683605D01*
X-1553543D01*
X-1554517Y-684038D01*
X-1555275Y-684760D01*
X-1555816Y-685626D01*
X-1556250Y-687069D01*
X-1556358Y-688369D01*
X-1556141Y-689668D01*
X-1555816Y-690534D01*
X-1555167Y-691400D01*
X-1554409Y-691977D01*
X-1553651Y-692266D01*
X-1552893D01*
X-1552135Y-691977D01*
X-1551486Y-691544D01*
X-1550944Y-690967D01*
G01X-1542825Y-692266D02*
X-1547155D01*
Y-683605D01*
X-1542825D01*
G01X-1544557Y-687791D02*
X-1547155D01*
G01X-1530375Y-692266D02*
X-1527668Y-683605D01*
X-1524961Y-692266D01*
G01X-1525936Y-689235D02*
X-1529400D01*
G01X-1519007Y-683605D02*
Y-692266D01*
G01X-1521497Y-683605D02*
X-1516517D01*
G01X-1504392Y-692266D02*
X-1501685Y-683605D01*
X-1498978Y-692266D01*
G01X-1499953Y-689235D02*
X-1503417D01*
G01X-1495189Y-683605D02*
Y-692266D01*
X-1490859D01*
G01X-1486528Y-683605D02*
Y-692266D01*
X-1482198D01*
G01X-1469206Y-683605D02*
Y-692266D01*
X-1464876D01*
G01X-1461087D02*
X-1458380Y-683605D01*
X-1455673Y-692266D01*
G01X-1456648Y-689235D02*
X-1460112D01*
G01X-1449719Y-692266D02*
Y-688369D01*
X-1451884Y-683605D01*
G01X-1447554D02*
X-1449719Y-688369D01*
G01X-1438893Y-692266D02*
X-1443223D01*
Y-683605D01*
X-1438893D01*
G01X-1440625Y-687791D02*
X-1443223D01*
G01X-1434562Y-692266D02*
Y-683605D01*
X-1431856D01*
X-1430990Y-684038D01*
X-1430448Y-684615D01*
X-1430232Y-685770D01*
X-1430448Y-686925D01*
X-1431098Y-687647D01*
X-1431856Y-688080D01*
X-1434562D01*
G01X-1431856D02*
X-1430232Y-692266D01*
G01X-1426010Y-691111D02*
X-1425143Y-691833D01*
X-1424169Y-692266D01*
X-1423303D01*
X-1422437Y-691833D01*
X-1421787Y-691111D01*
X-1421462Y-690101D01*
X-1421679Y-689090D01*
X-1422220Y-688224D01*
X-1423195Y-687647D01*
X-1424494Y-687358D01*
X-1425252Y-686781D01*
X-1425577Y-685770D01*
X-1425360Y-684760D01*
X-1424819Y-684038D01*
X-1424061Y-683605D01*
X-1423303D01*
X-1422545Y-683894D01*
X-1421895Y-684615D01*
G01X-1404249Y-692266D02*
X-1408579D01*
Y-683605D01*
X-1404249D01*
G01X-1405981Y-687791D02*
X-1408579D01*
G01X-1400027Y-692266D02*
X-1395479Y-683605D01*
G01X-1400027D02*
X-1395479Y-692266D01*
G01X-1386710Y-684327D02*
X-1387360Y-683894D01*
X-1388118Y-683605D01*
X-1388984D01*
X-1389958Y-684038D01*
X-1390716Y-684760D01*
X-1391257Y-685626D01*
X-1391691Y-687069D01*
X-1391799Y-688369D01*
X-1391582Y-689668D01*
X-1391257Y-690534D01*
X-1390608Y-691400D01*
X-1389850Y-691977D01*
X-1389092Y-692266D01*
X-1388334D01*
X-1387576Y-691977D01*
X-1386927Y-691544D01*
X-1386385Y-690967D01*
G01X-1378266Y-692266D02*
X-1382596D01*
Y-683605D01*
X-1378266D01*
G01X-1379998Y-687791D02*
X-1382596D01*
G01X-1373935Y-692266D02*
Y-683605D01*
X-1371337D01*
X-1370471Y-684038D01*
X-1369821Y-685048D01*
X-1369605Y-686203D01*
X-1369821Y-687358D01*
X-1370363Y-688224D01*
X-1371337Y-688657D01*
X-1373935D01*
G01X-1363109Y-683605D02*
Y-692266D01*
G01X-1365599Y-683605D02*
X-1360619D01*
G01X-1345137Y-687936D02*
X-1342972D01*
Y-690534D01*
X-1343622Y-691400D01*
X-1344380Y-691977D01*
X-1345462Y-692266D01*
X-1346545Y-691977D01*
X-1347303Y-691400D01*
X-1347952Y-690534D01*
X-1348386Y-689523D01*
X-1348602Y-688369D01*
Y-687358D01*
X-1348386Y-686492D01*
X-1347952Y-685481D01*
X-1347303Y-684615D01*
X-1346653Y-684038D01*
X-1345787Y-683605D01*
X-1345029D01*
X-1344163Y-683894D01*
X-1343513Y-684471D01*
G01X-1339616Y-692266D02*
Y-683605D01*
X-1334636Y-692266D01*
Y-683605D01*
G01X-1330847Y-692266D02*
Y-683605D01*
X-1328682D01*
X-1327815Y-684038D01*
X-1327166Y-684615D01*
X-1326624Y-685481D01*
X-1326191Y-686492D01*
X-1326083Y-687936D01*
X-1326191Y-689379D01*
X-1326624Y-690390D01*
X-1327166Y-691256D01*
X-1327815Y-691833D01*
X-1328682Y-692266D01*
X-1330847D01*
G01X-1319263Y-695153D02*
X-1318180Y-693709D01*
X-1317639Y-692266D01*
Y-686492D01*
X-1318180Y-685048D01*
X-1319263Y-683605D01*
G01X-1615630Y186737D02*
X-1616713Y188181D01*
X-1617254Y189624D01*
Y195398D01*
X-1616713Y196842D01*
X-1615630Y198285D01*
G01X-1608593Y189624D02*
Y198285D01*
X-1605995D01*
X-1605129Y197852D01*
X-1604479Y196842D01*
X-1604263Y195687D01*
X-1604479Y194532D01*
X-1605021Y193666D01*
X-1605995Y193233D01*
X-1608593D01*
G01X-1600474Y189624D02*
X-1597767Y198285D01*
X-1595060Y189624D01*
G01X-1596035Y192655D02*
X-1599499D01*
G01X-1591488Y189624D02*
Y198285D01*
X-1589323D01*
X-1588456Y197852D01*
X-1587807Y197275D01*
X-1587265Y196409D01*
X-1586832Y195398D01*
X-1586724Y193954D01*
X-1586832Y192511D01*
X-1587265Y191500D01*
X-1587807Y190634D01*
X-1588456Y190057D01*
X-1589323Y189624D01*
X-1591488D01*
G01X-1579904Y186737D02*
X-1578821Y188181D01*
X-1578280Y189624D01*
Y195398D01*
X-1578821Y196842D01*
X-1579904Y198285D01*
G01X-1572325Y186737D02*
X-1573408Y188181D01*
X-1573949Y189624D01*
Y195398D01*
X-1573408Y196842D01*
X-1572325Y198285D01*
G01X-1565613Y189624D02*
Y198285D01*
X-1560633Y189624D01*
Y198285D01*
G01X-1554462Y189624D02*
X-1555328Y189768D01*
X-1556086Y190346D01*
X-1556736Y191212D01*
X-1557169Y192222D01*
X-1557385Y193377D01*
Y194532D01*
X-1557169Y195687D01*
X-1556736Y196697D01*
X-1556086Y197563D01*
X-1555328Y198141D01*
X-1554462Y198285D01*
X-1553596Y198141D01*
X-1552838Y197563D01*
X-1552188Y196697D01*
X-1551755Y195687D01*
X-1551539Y194532D01*
Y193377D01*
X-1551755Y192222D01*
X-1552188Y191212D01*
X-1552838Y190346D01*
X-1553596Y189768D01*
X-1554462Y189624D01*
G01X-1537140Y198285D02*
Y189624D01*
G01X-1539630Y198285D02*
X-1534650D01*
G01X-1530644Y189624D02*
Y198285D01*
X-1527938D01*
X-1527072Y197852D01*
X-1526530Y197275D01*
X-1526314Y196120D01*
X-1526530Y194965D01*
X-1527180Y194243D01*
X-1527938Y193810D01*
X-1530644D01*
G01X-1527938D02*
X-1526314Y189624D01*
G01X-1522525D02*
X-1519818Y198285D01*
X-1517111Y189624D01*
G01X-1518086Y192655D02*
X-1521550D01*
G01X-1508775Y197563D02*
X-1509425Y197996D01*
X-1510183Y198285D01*
X-1511049D01*
X-1512023Y197852D01*
X-1512781Y197130D01*
X-1513322Y196264D01*
X-1513756Y194821D01*
X-1513864Y193521D01*
X-1513647Y192222D01*
X-1513322Y191356D01*
X-1512673Y190490D01*
X-1511915Y189913D01*
X-1511157Y189624D01*
X-1510399D01*
X-1509641Y189913D01*
X-1508992Y190346D01*
X-1508450Y190923D01*
G01X-1500331Y189624D02*
X-1504661D01*
Y198285D01*
X-1500331D01*
G01X-1502063Y194099D02*
X-1504661D01*
G01X-1487881Y189624D02*
X-1485174Y198285D01*
X-1482467Y189624D01*
G01X-1483442Y192655D02*
X-1486906D01*
G01X-1476513Y198285D02*
Y189624D01*
G01X-1479003Y198285D02*
X-1474023D01*
G01X-1461898Y189624D02*
X-1459191Y198285D01*
X-1456484Y189624D01*
G01X-1457459Y192655D02*
X-1460923D01*
G01X-1452695Y198285D02*
Y189624D01*
X-1448365D01*
G01X-1444034Y198285D02*
Y189624D01*
X-1439704D01*
G01X-1426712Y198285D02*
Y189624D01*
X-1422382D01*
G01X-1418593D02*
X-1415886Y198285D01*
X-1413179Y189624D01*
G01X-1414154Y192655D02*
X-1417618D01*
G01X-1407225Y189624D02*
Y193521D01*
X-1409390Y198285D01*
G01X-1405060D02*
X-1407225Y193521D01*
G01X-1396399Y189624D02*
X-1400729D01*
Y198285D01*
X-1396399D01*
G01X-1398131Y194099D02*
X-1400729D01*
G01X-1392068Y189624D02*
Y198285D01*
X-1389362D01*
X-1388496Y197852D01*
X-1387954Y197275D01*
X-1387738Y196120D01*
X-1387954Y194965D01*
X-1388604Y194243D01*
X-1389362Y193810D01*
X-1392068D01*
G01X-1389362D02*
X-1387738Y189624D01*
G01X-1383516Y190779D02*
X-1382649Y190057D01*
X-1381675Y189624D01*
X-1380809D01*
X-1379943Y190057D01*
X-1379293Y190779D01*
X-1378968Y191789D01*
X-1379185Y192800D01*
X-1379726Y193666D01*
X-1380701Y194243D01*
X-1382000Y194532D01*
X-1382758Y195109D01*
X-1383083Y196120D01*
X-1382866Y197130D01*
X-1382325Y197852D01*
X-1381567Y198285D01*
X-1380809D01*
X-1380051Y197996D01*
X-1379401Y197275D01*
G01X-1372040Y186737D02*
X-1370957Y188181D01*
X-1370416Y189624D01*
Y195398D01*
X-1370957Y196842D01*
X-1372040Y198285D01*
G01X-1591604Y254804D02*
X-1600265D01*
X-1598533Y253505D01*
G01X-1591604D02*
Y256103D01*
G01Y263465D02*
X-1591748Y264223D01*
X-1592181Y265089D01*
X-1592903Y265630D01*
X-1593914Y265847D01*
X-1594924Y265630D01*
X-1595790Y264981D01*
X-1596223Y264006D01*
Y262924D01*
X-1596512Y262274D01*
X-1597234Y261733D01*
X-1598244Y261516D01*
X-1599255Y261841D01*
X-1599976Y262599D01*
X-1600265Y263465D01*
X-1599976Y264331D01*
X-1599255Y265089D01*
X-1598244Y265414D01*
X-1597234Y265197D01*
X-1596512Y264656D01*
X-1596223Y264006D01*
Y262924D01*
X-1595790Y261949D01*
X-1594924Y261300D01*
X-1593914Y261083D01*
X-1592903Y261300D01*
X-1592181Y261841D01*
X-1591748Y262707D01*
X-1591604Y263465D01*
G01X-1591315Y272126D02*
X-1591460Y271909D01*
X-1591748D01*
X-1591893Y272126D01*
X-1591748Y272343D01*
X-1591460D01*
X-1591315Y272126D01*
G01X-1600265Y280787D02*
X-1599976Y279921D01*
X-1599255Y279271D01*
X-1598389Y278838D01*
X-1597234Y278513D01*
X-1595934Y278405D01*
X-1594635Y278513D01*
X-1593480Y278838D01*
X-1592614Y279271D01*
X-1591893Y279921D01*
X-1591604Y280787D01*
X-1591893Y281653D01*
X-1592614Y282303D01*
X-1593480Y282736D01*
X-1594635Y283061D01*
X-1595934Y283169D01*
X-1597234Y283061D01*
X-1598389Y282736D01*
X-1599255Y282303D01*
X-1599976Y281653D01*
X-1600265Y280787D01*
G01Y289448D02*
X-1599976Y288582D01*
X-1599255Y287932D01*
X-1598389Y287499D01*
X-1597234Y287174D01*
X-1595934Y287066D01*
X-1594635Y287174D01*
X-1593480Y287499D01*
X-1592614Y287932D01*
X-1591893Y288582D01*
X-1591604Y289448D01*
X-1591893Y290314D01*
X-1592614Y290964D01*
X-1593480Y291397D01*
X-1594635Y291722D01*
X-1595934Y291830D01*
X-1597234Y291722D01*
X-1598389Y291397D01*
X-1599255Y290964D01*
X-1599976Y290314D01*
X-1600265Y289448D01*
G01X-1579924Y252747D02*
X-1580789Y253397D01*
X-1581223Y254154D01*
X-1581367Y255021D01*
X-1581078Y256103D01*
X-1580357Y256861D01*
X-1579491Y257078D01*
X-1578624Y256969D01*
X-1577903Y256536D01*
X-1576459Y254371D01*
X-1575449Y253397D01*
X-1574005Y252747D01*
X-1572706Y252530D01*
Y257078D01*
G01X-1579924Y261408D02*
X-1580789Y262058D01*
X-1581223Y262815D01*
X-1581367Y263682D01*
X-1581078Y264764D01*
X-1580357Y265522D01*
X-1579491Y265739D01*
X-1578624Y265630D01*
X-1577903Y265197D01*
X-1576459Y263032D01*
X-1575449Y262058D01*
X-1574005Y261408D01*
X-1572706Y261191D01*
Y265739D01*
G01X-1572417Y272126D02*
X-1572562Y271909D01*
X-1572850D01*
X-1572995Y272126D01*
X-1572850Y272343D01*
X-1572562D01*
X-1572417Y272126D01*
G01X-1572706Y280787D02*
X-1572850Y281545D01*
X-1573283Y282411D01*
X-1574005Y282952D01*
X-1575016Y283169D01*
X-1576026Y282952D01*
X-1576892Y282303D01*
X-1577325Y281328D01*
Y280246D01*
X-1577614Y279596D01*
X-1578336Y279055D01*
X-1579346Y278838D01*
X-1580357Y279163D01*
X-1581078Y279921D01*
X-1581367Y280787D01*
X-1581078Y281653D01*
X-1580357Y282411D01*
X-1579346Y282736D01*
X-1578336Y282519D01*
X-1577614Y281978D01*
X-1577325Y281328D01*
Y280246D01*
X-1576892Y279271D01*
X-1576026Y278622D01*
X-1575016Y278405D01*
X-1574005Y278622D01*
X-1573283Y279163D01*
X-1572850Y280029D01*
X-1572706Y280787D01*
G01X-1581367Y289448D02*
X-1581078Y288582D01*
X-1580357Y287932D01*
X-1579491Y287499D01*
X-1578336Y287174D01*
X-1577036Y287066D01*
X-1575737Y287174D01*
X-1574582Y287499D01*
X-1573716Y287932D01*
X-1572995Y288582D01*
X-1572706Y289448D01*
X-1572995Y290314D01*
X-1573716Y290964D01*
X-1574582Y291397D01*
X-1575737Y291722D01*
X-1577036Y291830D01*
X-1578336Y291722D01*
X-1579491Y291397D01*
X-1580357Y290964D01*
X-1581078Y290314D01*
X-1581367Y289448D01*
G01X-1591604Y883910D02*
X-1600265D01*
X-1598533Y882611D01*
G01X-1591604D02*
Y885209D01*
G01Y892571D02*
X-1591748Y893329D01*
X-1592181Y894195D01*
X-1592903Y894736D01*
X-1593914Y894953D01*
X-1594924Y894736D01*
X-1595790Y894087D01*
X-1596223Y893112D01*
Y892030D01*
X-1596512Y891380D01*
X-1597234Y890839D01*
X-1598244Y890622D01*
X-1599255Y890947D01*
X-1599976Y891705D01*
X-1600265Y892571D01*
X-1599976Y893437D01*
X-1599255Y894195D01*
X-1598244Y894520D01*
X-1597234Y894303D01*
X-1596512Y893762D01*
X-1596223Y893112D01*
Y892030D01*
X-1595790Y891055D01*
X-1594924Y890406D01*
X-1593914Y890189D01*
X-1592903Y890406D01*
X-1592181Y890947D01*
X-1591748Y891813D01*
X-1591604Y892571D01*
G01X-1591315Y901232D02*
X-1591460Y901015D01*
X-1591748D01*
X-1591893Y901232D01*
X-1591748Y901449D01*
X-1591460D01*
X-1591315Y901232D01*
G01X-1600265Y909893D02*
X-1599976Y909027D01*
X-1599255Y908377D01*
X-1598389Y907944D01*
X-1597234Y907619D01*
X-1595934Y907511D01*
X-1594635Y907619D01*
X-1593480Y907944D01*
X-1592614Y908377D01*
X-1591893Y909027D01*
X-1591604Y909893D01*
X-1591893Y910759D01*
X-1592614Y911409D01*
X-1593480Y911842D01*
X-1594635Y912167D01*
X-1595934Y912275D01*
X-1597234Y912167D01*
X-1598389Y911842D01*
X-1599255Y911409D01*
X-1599976Y910759D01*
X-1600265Y909893D01*
G01Y918554D02*
X-1599976Y917688D01*
X-1599255Y917038D01*
X-1598389Y916605D01*
X-1597234Y916280D01*
X-1595934Y916172D01*
X-1594635Y916280D01*
X-1593480Y916605D01*
X-1592614Y917038D01*
X-1591893Y917688D01*
X-1591604Y918554D01*
X-1591893Y919420D01*
X-1592614Y920070D01*
X-1593480Y920503D01*
X-1594635Y920828D01*
X-1595934Y920936D01*
X-1597234Y920828D01*
X-1598389Y920503D01*
X-1599255Y920070D01*
X-1599976Y919420D01*
X-1600265Y918554D01*
G01X-1579531Y882478D02*
X-1580396Y883128D01*
X-1580830Y883885D01*
X-1580974Y884752D01*
X-1580685Y885834D01*
X-1579964Y886592D01*
X-1579098Y886809D01*
X-1578231Y886700D01*
X-1577510Y886267D01*
X-1576066Y884102D01*
X-1575056Y883128D01*
X-1573612Y882478D01*
X-1572313Y882261D01*
Y886809D01*
G01X-1579531Y891139D02*
X-1580396Y891789D01*
X-1580830Y892546D01*
X-1580974Y893413D01*
X-1580685Y894495D01*
X-1579964Y895253D01*
X-1579098Y895470D01*
X-1578231Y895361D01*
X-1577510Y894928D01*
X-1576066Y892763D01*
X-1575056Y891789D01*
X-1573612Y891139D01*
X-1572313Y890922D01*
Y895470D01*
G01X-1572024Y901857D02*
X-1572169Y901640D01*
X-1572457D01*
X-1572602Y901857D01*
X-1572457Y902074D01*
X-1572169D01*
X-1572024Y901857D01*
G01X-1573323Y908677D02*
X-1572602Y909435D01*
X-1572313Y910301D01*
X-1572602Y911168D01*
X-1573468Y911925D01*
X-1574767Y912467D01*
X-1576066Y912683D01*
X-1577654D01*
X-1578953Y912467D01*
X-1580108Y911925D01*
X-1580685Y911276D01*
X-1580974Y910518D01*
X-1580685Y909652D01*
X-1580108Y909002D01*
X-1579242Y908569D01*
X-1578087Y908353D01*
X-1577077Y908569D01*
X-1576066Y909111D01*
X-1575489Y909760D01*
X-1575344Y910518D01*
X-1575633Y911384D01*
X-1576355Y912034D01*
X-1577654Y912683D01*
G01X-1580974Y919179D02*
X-1580685Y918313D01*
X-1579964Y917663D01*
X-1579098Y917230D01*
X-1577943Y916905D01*
X-1576643Y916797D01*
X-1575344Y916905D01*
X-1574189Y917230D01*
X-1573323Y917663D01*
X-1572602Y918313D01*
X-1572313Y919179D01*
X-1572602Y920045D01*
X-1573323Y920695D01*
X-1574189Y921128D01*
X-1575344Y921453D01*
X-1576643Y921561D01*
X-1577943Y921453D01*
X-1579098Y921128D01*
X-1579964Y920695D01*
X-1580685Y920045D01*
X-1580974Y919179D01*
G01X-1613257Y1175670D02*
X-1621918D01*
X-1620186Y1174371D01*
G01X-1613257D02*
Y1176969D01*
G01X-1620475Y1182274D02*
X-1621340Y1182924D01*
X-1621774Y1183681D01*
X-1621918Y1184548D01*
X-1621629Y1185630D01*
X-1620908Y1186388D01*
X-1620042Y1186605D01*
X-1619175Y1186496D01*
X-1618454Y1186063D01*
X-1617010Y1183898D01*
X-1616000Y1182924D01*
X-1614556Y1182274D01*
X-1613257Y1182057D01*
Y1186605D01*
G01X-1612968Y1192992D02*
X-1613113Y1192775D01*
X-1613401D01*
X-1613546Y1192992D01*
X-1613401Y1193209D01*
X-1613113D01*
X-1612968Y1192992D01*
G01X-1614556Y1199271D02*
X-1613834Y1199921D01*
X-1613401Y1200679D01*
X-1613257Y1201653D01*
X-1613546Y1202627D01*
X-1614123Y1203385D01*
X-1615133Y1203927D01*
X-1616288Y1204035D01*
X-1617443Y1203818D01*
X-1618165Y1203277D01*
X-1618742Y1202519D01*
X-1618887Y1201761D01*
X-1618742Y1201003D01*
X-1618165Y1200029D01*
X-1621918Y1200354D01*
Y1203277D01*
G01Y1210314D02*
X-1621629Y1209448D01*
X-1620908Y1208798D01*
X-1620042Y1208365D01*
X-1618887Y1208040D01*
X-1617587Y1207932D01*
X-1616288Y1208040D01*
X-1615133Y1208365D01*
X-1614267Y1208798D01*
X-1613546Y1209448D01*
X-1613257Y1210314D01*
X-1613546Y1211180D01*
X-1614267Y1211830D01*
X-1615133Y1212263D01*
X-1616288Y1212588D01*
X-1617587Y1212696D01*
X-1618887Y1212588D01*
X-1620042Y1212263D01*
X-1620908Y1211830D01*
X-1621629Y1211180D01*
X-1621918Y1210314D01*
G01X-1495676Y189624D02*
Y195398D01*
G01Y193954D02*
X-1495242Y194676D01*
X-1494593Y195254D01*
X-1493727Y195398D01*
X-1492969Y195254D01*
X-1492319Y194676D01*
X-1491994Y193666D01*
Y189624D01*
G01X-1508668Y190634D02*
X-1507910Y189913D01*
X-1507044Y189624D01*
X-1506177Y189913D01*
X-1505420Y190779D01*
X-1504878Y192078D01*
X-1504662Y193377D01*
Y194965D01*
X-1504878Y196264D01*
X-1505420Y197419D01*
X-1506069Y197996D01*
X-1506827Y198285D01*
X-1507693Y197996D01*
X-1508343Y197419D01*
X-1508776Y196553D01*
X-1508992Y195398D01*
X-1508776Y194388D01*
X-1508234Y193377D01*
X-1507585Y192800D01*
X-1506827Y192655D01*
X-1505961Y192944D01*
X-1505311Y193666D01*
X-1504662Y194965D01*
G01X-1498166Y189335D02*
X-1498383Y189480D01*
Y189768D01*
X-1498166Y189913D01*
X-1497949Y189768D01*
Y189480D01*
X-1498166Y189335D01*
G01X-1491887Y190923D02*
X-1491237Y190201D01*
X-1490479Y189768D01*
X-1489505Y189624D01*
X-1488531Y189913D01*
X-1487773Y190490D01*
X-1487231Y191500D01*
X-1487123Y192655D01*
X-1487340Y193810D01*
X-1487881Y194532D01*
X-1488639Y195109D01*
X-1489397Y195254D01*
X-1490155Y195109D01*
X-1491129Y194532D01*
X-1490804Y198285D01*
X-1487881D01*
G01X-1480844D02*
X-1481710Y197996D01*
X-1482360Y197275D01*
X-1482793Y196409D01*
X-1483118Y195254D01*
X-1483226Y193954D01*
X-1483118Y192655D01*
X-1482793Y191500D01*
X-1482360Y190634D01*
X-1481710Y189913D01*
X-1480844Y189624D01*
X-1479978Y189913D01*
X-1479328Y190634D01*
X-1478895Y191500D01*
X-1478570Y192655D01*
X-1478462Y193954D01*
X-1478570Y195254D01*
X-1478895Y196409D01*
X-1479328Y197275D01*
X-1479978Y197996D01*
X-1480844Y198285D01*
G01X-1544005Y252422D02*
X-1542995Y253072D01*
X-1542417Y253938D01*
X-1542273Y254912D01*
X-1542417Y255778D01*
X-1543139Y256645D01*
X-1544005Y257186D01*
X-1544871Y257294D01*
X-1545882Y257078D01*
X-1546603Y256320D01*
X-1546892Y255562D01*
Y254587D01*
G01Y255562D02*
X-1547325Y256211D01*
X-1548047Y256753D01*
X-1548913Y256969D01*
X-1549779Y256753D01*
X-1550501Y256211D01*
X-1550934Y255237D01*
X-1550790Y254263D01*
X-1550212Y253288D01*
G01X-1550934Y263465D02*
X-1550645Y262599D01*
X-1549924Y261949D01*
X-1549058Y261516D01*
X-1547903Y261191D01*
X-1546603Y261083D01*
X-1545304Y261191D01*
X-1544149Y261516D01*
X-1543283Y261949D01*
X-1542562Y262599D01*
X-1542273Y263465D01*
X-1542562Y264331D01*
X-1543283Y264981D01*
X-1544149Y265414D01*
X-1545304Y265739D01*
X-1546603Y265847D01*
X-1547903Y265739D01*
X-1549058Y265414D01*
X-1549924Y264981D01*
X-1550645Y264331D01*
X-1550934Y263465D01*
G01X-1541984Y272126D02*
X-1542129Y271909D01*
X-1542417D01*
X-1542562Y272126D01*
X-1542417Y272343D01*
X-1542129D01*
X-1541984Y272126D01*
G01X-1543572Y278405D02*
X-1542850Y279055D01*
X-1542417Y279813D01*
X-1542273Y280787D01*
X-1542562Y281761D01*
X-1543139Y282519D01*
X-1544149Y283061D01*
X-1545304Y283169D01*
X-1546459Y282952D01*
X-1547181Y282411D01*
X-1547758Y281653D01*
X-1547903Y280895D01*
X-1547758Y280137D01*
X-1547181Y279163D01*
X-1550934Y279488D01*
Y282411D01*
G01X-1544005Y287066D02*
X-1542995Y287716D01*
X-1542417Y288582D01*
X-1542273Y289556D01*
X-1542417Y290422D01*
X-1543139Y291289D01*
X-1544005Y291830D01*
X-1544871Y291938D01*
X-1545882Y291722D01*
X-1546603Y290964D01*
X-1546892Y290206D01*
Y289231D01*
G01Y290206D02*
X-1547325Y290855D01*
X-1548047Y291397D01*
X-1548913Y291613D01*
X-1549779Y291397D01*
X-1550501Y290855D01*
X-1550934Y289881D01*
X-1550790Y288907D01*
X-1550212Y287932D01*
G01X-1506402Y654966D02*
X-1505535Y654244D01*
X-1504561Y653811D01*
X-1503695D01*
X-1502829Y654244D01*
X-1502179Y654966D01*
X-1501854Y655976D01*
X-1502071Y656987D01*
X-1502612Y657853D01*
X-1503587Y658430D01*
X-1504886Y658719D01*
X-1505644Y659296D01*
X-1505969Y660307D01*
X-1505752Y661317D01*
X-1505211Y662039D01*
X-1504453Y662472D01*
X-1503695D01*
X-1502937Y662183D01*
X-1502287Y661462D01*
G01X-1493302Y653811D02*
X-1497632D01*
Y662472D01*
X-1493302D01*
G01X-1495034Y658286D02*
X-1497632D01*
G01X-1484641Y653811D02*
X-1488971D01*
Y662472D01*
X-1484641D01*
G01X-1486373Y658286D02*
X-1488971D01*
G01X-1471866Y653811D02*
Y662472D01*
X-1469701D01*
X-1468834Y662039D01*
X-1468185Y661462D01*
X-1467643Y660596D01*
X-1467210Y659585D01*
X-1467102Y658141D01*
X-1467210Y656698D01*
X-1467643Y655687D01*
X-1468185Y654821D01*
X-1468834Y654244D01*
X-1469701Y653811D01*
X-1471866D01*
G01X-1458658D02*
X-1462988D01*
Y662472D01*
X-1458658D01*
G01X-1460390Y658286D02*
X-1462988D01*
G01X-1452162Y662472D02*
Y653811D01*
G01X-1454652Y662472D02*
X-1449672D01*
G01X-1446208Y653811D02*
X-1443501Y662472D01*
X-1440794Y653811D01*
G01X-1441769Y656842D02*
X-1445233D01*
G01X-1436139Y662472D02*
X-1433541D01*
G01X-1434840D02*
Y653811D01*
G01X-1436139D02*
X-1433541D01*
G01X-1428344Y662472D02*
Y653811D01*
X-1424014D01*
G01X-1411564D02*
X-1408857Y662472D01*
X-1406150Y653811D01*
G01X-1407125Y656842D02*
X-1410589D01*
G01X-1499281Y1095764D02*
X-1507942D01*
X-1501735Y1091758D01*
Y1097172D01*
G01X-1499281Y1103126D02*
X-1507942D01*
X-1506210Y1101827D01*
G01X-1499281D02*
Y1104425D01*
G01X-1498992Y1111787D02*
X-1499137Y1111570D01*
X-1499425D01*
X-1499570Y1111787D01*
X-1499425Y1112004D01*
X-1499137D01*
X-1498992Y1111787D01*
G01X-1499281Y1121747D02*
X-1507942D01*
X-1501735Y1117741D01*
Y1123155D01*
G01X-1500580Y1126727D02*
X-1499858Y1127377D01*
X-1499425Y1128135D01*
X-1499281Y1129109D01*
X-1499570Y1130083D01*
X-1500147Y1130841D01*
X-1501157Y1131383D01*
X-1502312Y1131491D01*
X-1503467Y1131274D01*
X-1504189Y1130733D01*
X-1504766Y1129975D01*
X-1504911Y1129217D01*
X-1504766Y1128459D01*
X-1504189Y1127485D01*
X-1507942Y1127810D01*
Y1130733D01*
G01X-1491854Y-850574D02*
X-1491002Y-851899D01*
X-1489865Y-852657D01*
X-1488587Y-852846D01*
X-1487451Y-852657D01*
X-1486314Y-851710D01*
X-1485604Y-850574D01*
X-1485462Y-849437D01*
X-1485746Y-848112D01*
X-1486741Y-847165D01*
X-1487735Y-846786D01*
X-1489013D01*
G01X-1487735D02*
X-1486883Y-846218D01*
X-1486172Y-845272D01*
X-1485888Y-844135D01*
X-1486172Y-842999D01*
X-1486883Y-842052D01*
X-1488161Y-841484D01*
X-1489439Y-841673D01*
X-1490717Y-842431D01*
G01X-1473212Y-692266D02*
Y-686492D01*
G01Y-687936D02*
X-1472778Y-687214D01*
X-1472129Y-686636D01*
X-1471263Y-686492D01*
X-1470505Y-686636D01*
X-1469855Y-687214D01*
X-1469530Y-688224D01*
Y-692266D01*
G01X-1486745Y-690967D02*
X-1486095Y-691689D01*
X-1485337Y-692122D01*
X-1484363Y-692266D01*
X-1483389Y-691977D01*
X-1482631Y-691400D01*
X-1482089Y-690390D01*
X-1481981Y-689235D01*
X-1482198Y-688080D01*
X-1482739Y-687358D01*
X-1483497Y-686781D01*
X-1484255Y-686636D01*
X-1485013Y-686781D01*
X-1485987Y-687358D01*
X-1485662Y-683605D01*
X-1482739D01*
G01X-1475702Y-692555D02*
X-1475919Y-692410D01*
Y-692122D01*
X-1475702Y-691977D01*
X-1475485Y-692122D01*
Y-692410D01*
X-1475702Y-692555D01*
G01X-1467041Y-683605D02*
X-1467907Y-683894D01*
X-1468557Y-684615D01*
X-1468990Y-685481D01*
X-1469315Y-686636D01*
X-1469423Y-687936D01*
X-1469315Y-689235D01*
X-1468990Y-690390D01*
X-1468557Y-691256D01*
X-1467907Y-691977D01*
X-1467041Y-692266D01*
X-1466175Y-691977D01*
X-1465525Y-691256D01*
X-1465092Y-690390D01*
X-1464767Y-689235D01*
X-1464659Y-687936D01*
X-1464767Y-686636D01*
X-1465092Y-685481D01*
X-1465525Y-684615D01*
X-1466175Y-683894D01*
X-1467041Y-683605D01*
G01X-1458380D02*
X-1459246Y-683894D01*
X-1459896Y-684615D01*
X-1460329Y-685481D01*
X-1460654Y-686636D01*
X-1460762Y-687936D01*
X-1460654Y-689235D01*
X-1460329Y-690390D01*
X-1459896Y-691256D01*
X-1459246Y-691977D01*
X-1458380Y-692266D01*
X-1457514Y-691977D01*
X-1456864Y-691256D01*
X-1456431Y-690390D01*
X-1456106Y-689235D01*
X-1455998Y-687936D01*
X-1456106Y-686636D01*
X-1456431Y-685481D01*
X-1456864Y-684615D01*
X-1457514Y-683894D01*
X-1458380Y-683605D01*
G01X-1444635Y416220D02*
Y424881D01*
X-1445934Y423149D01*
G01Y416220D02*
X-1443336D01*
G01X-1435974Y424881D02*
X-1436840Y424592D01*
X-1437490Y423871D01*
X-1437923Y423005D01*
X-1438248Y421850D01*
X-1438356Y420550D01*
X-1438248Y419251D01*
X-1437923Y418096D01*
X-1437490Y417230D01*
X-1436840Y416509D01*
X-1435974Y416220D01*
X-1435108Y416509D01*
X-1434458Y417230D01*
X-1434025Y418096D01*
X-1433700Y419251D01*
X-1433592Y420550D01*
X-1433700Y421850D01*
X-1434025Y423005D01*
X-1434458Y423871D01*
X-1435108Y424592D01*
X-1435974Y424881D01*
G01X-1427313Y415931D02*
X-1427530Y416076D01*
Y416364D01*
X-1427313Y416509D01*
X-1427096Y416364D01*
Y416076D01*
X-1427313Y415931D01*
G01X-1418652Y424881D02*
X-1419518Y424592D01*
X-1420168Y423871D01*
X-1420601Y423005D01*
X-1420926Y421850D01*
X-1421034Y420550D01*
X-1420926Y419251D01*
X-1420601Y418096D01*
X-1420168Y417230D01*
X-1419518Y416509D01*
X-1418652Y416220D01*
X-1417786Y416509D01*
X-1417136Y417230D01*
X-1416703Y418096D01*
X-1416378Y419251D01*
X-1416270Y420550D01*
X-1416378Y421850D01*
X-1416703Y423005D01*
X-1417136Y423871D01*
X-1417786Y424592D01*
X-1418652Y424881D01*
G01X-1409991D02*
X-1410857Y424592D01*
X-1411507Y423871D01*
X-1411940Y423005D01*
X-1412265Y421850D01*
X-1412373Y420550D01*
X-1412265Y419251D01*
X-1411940Y418096D01*
X-1411507Y417230D01*
X-1410857Y416509D01*
X-1409991Y416220D01*
X-1409125Y416509D01*
X-1408475Y417230D01*
X-1408042Y418096D01*
X-1407717Y419251D01*
X-1407609Y420550D01*
X-1407717Y421850D01*
X-1408042Y423005D01*
X-1408475Y423871D01*
X-1409125Y424592D01*
X-1409991Y424881D01*
G01X-1455011Y484613D02*
Y490387D01*
G01Y488943D02*
X-1454577Y489665D01*
X-1453928Y490243D01*
X-1453062Y490387D01*
X-1452304Y490243D01*
X-1451654Y489665D01*
X-1451329Y488655D01*
Y484613D01*
G01X-1468544Y486345D02*
X-1467894Y485335D01*
X-1467028Y484757D01*
X-1466054Y484613D01*
X-1465188Y484757D01*
X-1464321Y485479D01*
X-1463780Y486345D01*
X-1463672Y487211D01*
X-1463888Y488222D01*
X-1464646Y488943D01*
X-1465404Y489232D01*
X-1466379D01*
G01X-1465404D02*
X-1464755Y489665D01*
X-1464213Y490387D01*
X-1463997Y491253D01*
X-1464213Y492119D01*
X-1464755Y492841D01*
X-1465729Y493274D01*
X-1466703Y493130D01*
X-1467678Y492552D01*
G01X-1457501Y484324D02*
X-1457718Y484469D01*
Y484757D01*
X-1457501Y484902D01*
X-1457284Y484757D01*
Y484469D01*
X-1457501Y484324D01*
G01X-1451222Y486345D02*
X-1450572Y485335D01*
X-1449706Y484757D01*
X-1448732Y484613D01*
X-1447866Y484757D01*
X-1446999Y485479D01*
X-1446458Y486345D01*
X-1446350Y487211D01*
X-1446566Y488222D01*
X-1447324Y488943D01*
X-1448082Y489232D01*
X-1449057D01*
G01X-1448082D02*
X-1447433Y489665D01*
X-1446891Y490387D01*
X-1446675Y491253D01*
X-1446891Y492119D01*
X-1447433Y492841D01*
X-1448407Y493274D01*
X-1449381Y493130D01*
X-1450356Y492552D01*
G01X-1440179Y493274D02*
X-1441045Y492985D01*
X-1441695Y492264D01*
X-1442128Y491398D01*
X-1442453Y490243D01*
X-1442561Y488943D01*
X-1442453Y487644D01*
X-1442128Y486489D01*
X-1441695Y485623D01*
X-1441045Y484902D01*
X-1440179Y484613D01*
X-1439313Y484902D01*
X-1438663Y485623D01*
X-1438230Y486489D01*
X-1437905Y487644D01*
X-1437797Y488943D01*
X-1437905Y490243D01*
X-1438230Y491398D01*
X-1438663Y492264D01*
X-1439313Y492985D01*
X-1440179Y493274D01*
G01X-1475364Y481726D02*
X-1476447Y483170D01*
X-1476988Y484613D01*
Y490387D01*
X-1476447Y491831D01*
X-1475364Y493274D01*
G01X-1468652Y484613D02*
Y493274D01*
X-1463672Y484613D01*
Y493274D01*
G01X-1459666Y484613D02*
Y493274D01*
X-1457068D01*
X-1456202Y492841D01*
X-1455552Y491831D01*
X-1455336Y490676D01*
X-1455552Y489521D01*
X-1456094Y488655D01*
X-1457068Y488222D01*
X-1459666D01*
G01X-1448840Y493274D02*
Y484613D01*
G01X-1451330Y493274D02*
X-1446350D01*
G01X-1442453Y484613D02*
Y493274D01*
G01X-1437905D02*
Y484613D01*
G01Y488943D02*
X-1442453D01*
G01X-1430977Y481726D02*
X-1429894Y483170D01*
X-1429353Y484613D01*
Y490387D01*
X-1429894Y491831D01*
X-1430977Y493274D01*
G01X-1443336Y534528D02*
Y543189D01*
X-1447342Y536982D01*
X-1441928D01*
G01X-1435974Y543189D02*
X-1436840Y542900D01*
X-1437490Y542179D01*
X-1437923Y541313D01*
X-1438248Y540158D01*
X-1438356Y538858D01*
X-1438248Y537559D01*
X-1437923Y536404D01*
X-1437490Y535538D01*
X-1436840Y534817D01*
X-1435974Y534528D01*
X-1435108Y534817D01*
X-1434458Y535538D01*
X-1434025Y536404D01*
X-1433700Y537559D01*
X-1433592Y538858D01*
X-1433700Y540158D01*
X-1434025Y541313D01*
X-1434458Y542179D01*
X-1435108Y542900D01*
X-1435974Y543189D01*
G01X-1427313Y534239D02*
X-1427530Y534384D01*
Y534672D01*
X-1427313Y534817D01*
X-1427096Y534672D01*
Y534384D01*
X-1427313Y534239D01*
G01X-1418652Y543189D02*
X-1419518Y542900D01*
X-1420168Y542179D01*
X-1420601Y541313D01*
X-1420926Y540158D01*
X-1421034Y538858D01*
X-1420926Y537559D01*
X-1420601Y536404D01*
X-1420168Y535538D01*
X-1419518Y534817D01*
X-1418652Y534528D01*
X-1417786Y534817D01*
X-1417136Y535538D01*
X-1416703Y536404D01*
X-1416378Y537559D01*
X-1416270Y538858D01*
X-1416378Y540158D01*
X-1416703Y541313D01*
X-1417136Y542179D01*
X-1417786Y542900D01*
X-1418652Y543189D01*
G01X-1412373Y535827D02*
X-1411723Y535105D01*
X-1410965Y534672D01*
X-1409991Y534528D01*
X-1409017Y534817D01*
X-1408259Y535394D01*
X-1407717Y536404D01*
X-1407609Y537559D01*
X-1407826Y538714D01*
X-1408367Y539436D01*
X-1409125Y540013D01*
X-1409883Y540158D01*
X-1410641Y540013D01*
X-1411615Y539436D01*
X-1411290Y543189D01*
X-1408367D01*
G01X-1443336Y565827D02*
Y574488D01*
X-1447342Y568281D01*
X-1441928D01*
G01X-1435974Y565827D02*
X-1435216Y565971D01*
X-1434350Y566404D01*
X-1433809Y567126D01*
X-1433592Y568137D01*
X-1433809Y569147D01*
X-1434458Y570013D01*
X-1435433Y570446D01*
X-1436515D01*
X-1437165Y570735D01*
X-1437706Y571457D01*
X-1437923Y572467D01*
X-1437598Y573478D01*
X-1436840Y574199D01*
X-1435974Y574488D01*
X-1435108Y574199D01*
X-1434350Y573478D01*
X-1434025Y572467D01*
X-1434242Y571457D01*
X-1434783Y570735D01*
X-1435433Y570446D01*
X-1436515D01*
X-1437490Y570013D01*
X-1438139Y569147D01*
X-1438356Y568137D01*
X-1438139Y567126D01*
X-1437598Y566404D01*
X-1436732Y565971D01*
X-1435974Y565827D01*
G01X-1427313Y565538D02*
X-1427530Y565683D01*
Y565971D01*
X-1427313Y566116D01*
X-1427096Y565971D01*
Y565683D01*
X-1427313Y565538D01*
G01X-1418652Y574488D02*
X-1419518Y574199D01*
X-1420168Y573478D01*
X-1420601Y572612D01*
X-1420926Y571457D01*
X-1421034Y570157D01*
X-1420926Y568858D01*
X-1420601Y567703D01*
X-1420168Y566837D01*
X-1419518Y566116D01*
X-1418652Y565827D01*
X-1417786Y566116D01*
X-1417136Y566837D01*
X-1416703Y567703D01*
X-1416378Y568858D01*
X-1416270Y570157D01*
X-1416378Y571457D01*
X-1416703Y572612D01*
X-1417136Y573478D01*
X-1417786Y574199D01*
X-1418652Y574488D01*
G01X-1409991D02*
X-1410857Y574199D01*
X-1411507Y573478D01*
X-1411940Y572612D01*
X-1412265Y571457D01*
X-1412373Y570157D01*
X-1412265Y568858D01*
X-1411940Y567703D01*
X-1411507Y566837D01*
X-1410857Y566116D01*
X-1409991Y565827D01*
X-1409125Y566116D01*
X-1408475Y566837D01*
X-1408042Y567703D01*
X-1407717Y568858D01*
X-1407609Y570157D01*
X-1407717Y571457D01*
X-1408042Y572612D01*
X-1408475Y573478D01*
X-1409125Y574199D01*
X-1409991Y574488D01*
G01X-1488633Y740191D02*
X-1489716Y741635D01*
X-1490257Y743078D01*
Y748852D01*
X-1489716Y750296D01*
X-1488633Y751739D01*
G01X-1481921Y743078D02*
Y751739D01*
X-1476941Y743078D01*
Y751739D01*
G01X-1472935Y743078D02*
Y751739D01*
X-1470337D01*
X-1469471Y751306D01*
X-1468821Y750296D01*
X-1468605Y749141D01*
X-1468821Y747986D01*
X-1469363Y747120D01*
X-1470337Y746687D01*
X-1472935D01*
G01X-1462109Y751739D02*
Y743078D01*
G01X-1464599Y751739D02*
X-1459619D01*
G01X-1455722Y743078D02*
Y751739D01*
G01X-1451174D02*
Y743078D01*
G01Y747408D02*
X-1455722D01*
G01X-1444246Y740191D02*
X-1443163Y741635D01*
X-1442622Y743078D01*
Y748852D01*
X-1443163Y750296D01*
X-1444246Y751739D01*
G01X-1468280Y743078D02*
Y748852D01*
G01Y747408D02*
X-1467846Y748130D01*
X-1467197Y748708D01*
X-1466331Y748852D01*
X-1465573Y748708D01*
X-1464923Y748130D01*
X-1464598Y747120D01*
Y743078D01*
G01X-1481813Y744810D02*
X-1481163Y743800D01*
X-1480297Y743222D01*
X-1479323Y743078D01*
X-1478457Y743222D01*
X-1477590Y743944D01*
X-1477049Y744810D01*
X-1476941Y745676D01*
X-1477157Y746687D01*
X-1477915Y747408D01*
X-1478673Y747697D01*
X-1479648D01*
G01X-1478673D02*
X-1478024Y748130D01*
X-1477482Y748852D01*
X-1477266Y749718D01*
X-1477482Y750584D01*
X-1478024Y751306D01*
X-1478998Y751739D01*
X-1479972Y751595D01*
X-1480947Y751017D01*
G01X-1470770Y742789D02*
X-1470987Y742934D01*
Y743222D01*
X-1470770Y743367D01*
X-1470553Y743222D01*
Y742934D01*
X-1470770Y742789D01*
G01X-1464491Y744810D02*
X-1463841Y743800D01*
X-1462975Y743222D01*
X-1462001Y743078D01*
X-1461135Y743222D01*
X-1460268Y743944D01*
X-1459727Y744810D01*
X-1459619Y745676D01*
X-1459835Y746687D01*
X-1460593Y747408D01*
X-1461351Y747697D01*
X-1462326D01*
G01X-1461351D02*
X-1460702Y748130D01*
X-1460160Y748852D01*
X-1459944Y749718D01*
X-1460160Y750584D01*
X-1460702Y751306D01*
X-1461676Y751739D01*
X-1462650Y751595D01*
X-1463625Y751017D01*
G01X-1453448Y751739D02*
X-1454314Y751450D01*
X-1454964Y750729D01*
X-1455397Y749863D01*
X-1455722Y748708D01*
X-1455830Y747408D01*
X-1455722Y746109D01*
X-1455397Y744954D01*
X-1454964Y744088D01*
X-1454314Y743367D01*
X-1453448Y743078D01*
X-1452582Y743367D01*
X-1451932Y744088D01*
X-1451499Y744954D01*
X-1451174Y746109D01*
X-1451066Y747408D01*
X-1451174Y748708D01*
X-1451499Y749863D01*
X-1451932Y750729D01*
X-1452582Y751450D01*
X-1453448Y751739D01*
G01X-1491854Y1327182D02*
X-1491002Y1325857D01*
X-1489865Y1325099D01*
X-1488587Y1324910D01*
X-1487451Y1325099D01*
X-1486314Y1326046D01*
X-1485604Y1327182D01*
X-1485462Y1328319D01*
X-1485746Y1329644D01*
X-1486741Y1330591D01*
X-1487735Y1330970D01*
X-1489013D01*
G01X-1487735D02*
X-1486883Y1331538D01*
X-1486172Y1332484D01*
X-1485888Y1333621D01*
X-1486172Y1334757D01*
X-1486883Y1335704D01*
X-1488161Y1336272D01*
X-1489439Y1336083D01*
X-1490717Y1335325D01*
G01X-1366012Y-431664D02*
X-1365362Y-430799D01*
X-1364605Y-430365D01*
X-1363738Y-430221D01*
X-1362656Y-430510D01*
X-1361898Y-431231D01*
X-1361681Y-432097D01*
X-1361790Y-432964D01*
X-1362223Y-433685D01*
X-1364388Y-435129D01*
X-1365362Y-436139D01*
X-1366012Y-437583D01*
X-1366229Y-438882D01*
X-1361681D01*
G01X-1355294Y-439171D02*
X-1355511Y-439026D01*
Y-438738D01*
X-1355294Y-438593D01*
X-1355077Y-438738D01*
Y-439026D01*
X-1355294Y-439171D01*
G01X-1345334Y-438882D02*
Y-430221D01*
X-1349340Y-436428D01*
X-1343926D01*
G01X-1337972Y-438882D02*
Y-430221D01*
X-1339271Y-431953D01*
G01Y-438882D02*
X-1336673D01*
G01X-1374950Y254587D02*
X-1376826Y254804D01*
X-1378414Y255129D01*
X-1379858Y255562D01*
X-1381446Y256103D01*
X-1383611Y256969D01*
Y252639D01*
G01X-1376682Y261083D02*
X-1375672Y261733D01*
X-1375094Y262599D01*
X-1374950Y263573D01*
X-1375094Y264439D01*
X-1375816Y265306D01*
X-1376682Y265847D01*
X-1377548Y265955D01*
X-1378559Y265739D01*
X-1379280Y264981D01*
X-1379569Y264223D01*
Y263248D01*
G01Y264223D02*
X-1380002Y264872D01*
X-1380724Y265414D01*
X-1381590Y265630D01*
X-1382456Y265414D01*
X-1383178Y264872D01*
X-1383611Y263898D01*
X-1383467Y262924D01*
X-1382889Y261949D01*
G01X-1374661Y272126D02*
X-1374806Y271909D01*
X-1375094D01*
X-1375239Y272126D01*
X-1375094Y272343D01*
X-1374806D01*
X-1374661Y272126D01*
G01X-1383611Y280787D02*
X-1383322Y279921D01*
X-1382601Y279271D01*
X-1381735Y278838D01*
X-1380580Y278513D01*
X-1379280Y278405D01*
X-1377981Y278513D01*
X-1376826Y278838D01*
X-1375960Y279271D01*
X-1375239Y279921D01*
X-1374950Y280787D01*
X-1375239Y281653D01*
X-1375960Y282303D01*
X-1376826Y282736D01*
X-1377981Y283061D01*
X-1379280Y283169D01*
X-1380580Y283061D01*
X-1381735Y282736D01*
X-1382601Y282303D01*
X-1383322Y281653D01*
X-1383611Y280787D01*
G01X-1376682Y287066D02*
X-1375672Y287716D01*
X-1375094Y288582D01*
X-1374950Y289556D01*
X-1375094Y290422D01*
X-1375816Y291289D01*
X-1376682Y291830D01*
X-1377548Y291938D01*
X-1378559Y291722D01*
X-1379280Y290964D01*
X-1379569Y290206D01*
Y289231D01*
G01Y290206D02*
X-1380002Y290855D01*
X-1380724Y291397D01*
X-1381590Y291613D01*
X-1382456Y291397D01*
X-1383178Y290855D01*
X-1383611Y289881D01*
X-1383467Y288907D01*
X-1382889Y287932D01*
G01X-1380462Y1046142D02*
Y1054803D01*
X-1381761Y1053071D01*
G01Y1046142D02*
X-1379163D01*
G01X-1372018D02*
X-1371801Y1048018D01*
X-1371476Y1049606D01*
X-1371043Y1051050D01*
X-1370502Y1052638D01*
X-1369636Y1054803D01*
X-1373966D01*
G01X-1363140D02*
X-1364006Y1054514D01*
X-1364656Y1053793D01*
X-1365089Y1052927D01*
X-1365414Y1051772D01*
X-1365522Y1050472D01*
X-1365414Y1049173D01*
X-1365089Y1048018D01*
X-1364656Y1047152D01*
X-1364006Y1046431D01*
X-1363140Y1046142D01*
X-1362274Y1046431D01*
X-1361624Y1047152D01*
X-1361191Y1048018D01*
X-1360866Y1049173D01*
X-1360758Y1050472D01*
X-1360866Y1051772D01*
X-1361191Y1052927D01*
X-1361624Y1053793D01*
X-1362274Y1054514D01*
X-1363140Y1054803D01*
G01X-1354479Y1045853D02*
X-1354696Y1045998D01*
Y1046286D01*
X-1354479Y1046431D01*
X-1354262Y1046286D01*
Y1045998D01*
X-1354479Y1045853D01*
G01X-1345818Y1054803D02*
X-1346684Y1054514D01*
X-1347334Y1053793D01*
X-1347767Y1052927D01*
X-1348092Y1051772D01*
X-1348200Y1050472D01*
X-1348092Y1049173D01*
X-1347767Y1048018D01*
X-1347334Y1047152D01*
X-1346684Y1046431D01*
X-1345818Y1046142D01*
X-1344952Y1046431D01*
X-1344302Y1047152D01*
X-1343869Y1048018D01*
X-1343544Y1049173D01*
X-1343436Y1050472D01*
X-1343544Y1051772D01*
X-1343869Y1052927D01*
X-1344302Y1053793D01*
X-1344952Y1054514D01*
X-1345818Y1054803D01*
G01X-1337157D02*
X-1338023Y1054514D01*
X-1338673Y1053793D01*
X-1339106Y1052927D01*
X-1339431Y1051772D01*
X-1339539Y1050472D01*
X-1339431Y1049173D01*
X-1339106Y1048018D01*
X-1338673Y1047152D01*
X-1338023Y1046431D01*
X-1337157Y1046142D01*
X-1336291Y1046431D01*
X-1335641Y1047152D01*
X-1335208Y1048018D01*
X-1334883Y1049173D01*
X-1334775Y1050472D01*
X-1334883Y1051772D01*
X-1335208Y1052927D01*
X-1335641Y1053793D01*
X-1336291Y1054514D01*
X-1337157Y1054803D01*
G01X-1319265Y-884165D02*
X-1318398Y-884887D01*
X-1317424Y-885320D01*
X-1316558D01*
X-1315692Y-884887D01*
X-1315042Y-884165D01*
X-1314717Y-883155D01*
X-1314934Y-882144D01*
X-1315475Y-881278D01*
X-1316450Y-880701D01*
X-1317749Y-880412D01*
X-1318507Y-879835D01*
X-1318832Y-878824D01*
X-1318615Y-877814D01*
X-1318074Y-877092D01*
X-1317316Y-876659D01*
X-1316558D01*
X-1315800Y-876948D01*
X-1315150Y-877669D01*
G01X-1308330Y-885320D02*
X-1309196Y-885176D01*
X-1309954Y-884598D01*
X-1310604Y-883732D01*
X-1311037Y-882722D01*
X-1311253Y-881567D01*
Y-880412D01*
X-1311037Y-879257D01*
X-1310604Y-878247D01*
X-1309954Y-877381D01*
X-1309196Y-876803D01*
X-1308330Y-876659D01*
X-1307464Y-876803D01*
X-1306706Y-877381D01*
X-1306056Y-878247D01*
X-1305623Y-879257D01*
X-1305407Y-880412D01*
Y-881567D01*
X-1305623Y-882722D01*
X-1306056Y-883732D01*
X-1306706Y-884598D01*
X-1307464Y-885176D01*
X-1308330Y-885320D01*
G01X-1301834Y-876659D02*
Y-885320D01*
X-1297504D01*
G01X-1293390D02*
Y-876659D01*
X-1291225D01*
X-1290358Y-877092D01*
X-1289709Y-877669D01*
X-1289167Y-878535D01*
X-1288734Y-879546D01*
X-1288626Y-880990D01*
X-1288734Y-882433D01*
X-1289167Y-883444D01*
X-1289709Y-884310D01*
X-1290358Y-884887D01*
X-1291225Y-885320D01*
X-1293390D01*
G01X-1280182D02*
X-1284512D01*
Y-876659D01*
X-1280182D01*
G01X-1281914Y-880845D02*
X-1284512D01*
G01X-1275851Y-885320D02*
Y-876659D01*
X-1273145D01*
X-1272279Y-877092D01*
X-1271737Y-877669D01*
X-1271521Y-878824D01*
X-1271737Y-879979D01*
X-1272387Y-880701D01*
X-1273145Y-881134D01*
X-1275851D01*
G01X-1273145D02*
X-1271521Y-885320D01*
G01X-1258638Y-884165D02*
X-1257771Y-884887D01*
X-1256797Y-885320D01*
X-1255931D01*
X-1255065Y-884887D01*
X-1254415Y-884165D01*
X-1254090Y-883155D01*
X-1254307Y-882144D01*
X-1254848Y-881278D01*
X-1255823Y-880701D01*
X-1257122Y-880412D01*
X-1257880Y-879835D01*
X-1258205Y-878824D01*
X-1257988Y-877814D01*
X-1257447Y-877092D01*
X-1256689Y-876659D01*
X-1255931D01*
X-1255173Y-876948D01*
X-1254523Y-877669D01*
G01X-1249002Y-876659D02*
X-1246404D01*
G01X-1247703D02*
Y-885320D01*
G01X-1249002D02*
X-1246404D01*
G01X-1241424D02*
Y-876659D01*
X-1239259D01*
X-1238392Y-877092D01*
X-1237743Y-877669D01*
X-1237201Y-878535D01*
X-1236768Y-879546D01*
X-1236660Y-880990D01*
X-1236768Y-882433D01*
X-1237201Y-883444D01*
X-1237743Y-884310D01*
X-1238392Y-884887D01*
X-1239259Y-885320D01*
X-1241424D01*
G01X-1228216D02*
X-1232546D01*
Y-876659D01*
X-1228216D01*
G01X-1229948Y-880845D02*
X-1232546D01*
G01X-1352029Y-562599D02*
X-1351379Y-561734D01*
X-1350622Y-561300D01*
X-1349755Y-561156D01*
X-1348673Y-561445D01*
X-1347915Y-562166D01*
X-1347698Y-563032D01*
X-1347807Y-563899D01*
X-1348240Y-564620D01*
X-1350405Y-566064D01*
X-1351379Y-567074D01*
X-1352029Y-568518D01*
X-1352246Y-569817D01*
X-1347698D01*
G01X-1341311Y-570106D02*
X-1341528Y-569961D01*
Y-569673D01*
X-1341311Y-569528D01*
X-1341094Y-569673D01*
Y-569961D01*
X-1341311Y-570106D01*
G01X-1335032Y-568518D02*
X-1334382Y-569240D01*
X-1333624Y-569673D01*
X-1332650Y-569817D01*
X-1331676Y-569528D01*
X-1330918Y-568951D01*
X-1330376Y-567941D01*
X-1330268Y-566786D01*
X-1330485Y-565631D01*
X-1331026Y-564909D01*
X-1331784Y-564332D01*
X-1332542Y-564187D01*
X-1333300Y-564332D01*
X-1334274Y-564909D01*
X-1333949Y-561156D01*
X-1331026D01*
G01X-1326371Y-568518D02*
X-1325721Y-569240D01*
X-1324963Y-569673D01*
X-1323989Y-569817D01*
X-1323015Y-569528D01*
X-1322257Y-568951D01*
X-1321715Y-567941D01*
X-1321607Y-566786D01*
X-1321824Y-565631D01*
X-1322365Y-564909D01*
X-1323123Y-564332D01*
X-1323881Y-564187D01*
X-1324639Y-564332D01*
X-1325613Y-564909D01*
X-1325288Y-561156D01*
X-1322365D01*
G01X-1354843Y-572704D02*
X-1355926Y-571260D01*
X-1356467Y-569817D01*
Y-564043D01*
X-1355926Y-562599D01*
X-1354843Y-561156D01*
G01X-1347806Y-569817D02*
Y-561156D01*
X-1345208D01*
X-1344342Y-561589D01*
X-1343692Y-562599D01*
X-1343476Y-563754D01*
X-1343692Y-564909D01*
X-1344234Y-565775D01*
X-1345208Y-566208D01*
X-1347806D01*
G01X-1336980Y-561156D02*
Y-569817D01*
G01X-1339470Y-561156D02*
X-1334490D01*
G01X-1330593Y-569817D02*
Y-561156D01*
G01X-1326045D02*
Y-569817D01*
G01Y-565487D02*
X-1330593D01*
G01X-1319117Y-572704D02*
X-1318034Y-571260D01*
X-1317493Y-569817D01*
Y-564043D01*
X-1318034Y-562599D01*
X-1319117Y-561156D01*
G01X-1338821Y-569817D02*
Y-564043D01*
G01Y-565487D02*
X-1338387Y-564765D01*
X-1337738Y-564187D01*
X-1336872Y-564043D01*
X-1336114Y-564187D01*
X-1335464Y-564765D01*
X-1335139Y-565775D01*
Y-569817D01*
G01X-1334670Y-513939D02*
X-1334020Y-514949D01*
X-1333154Y-515527D01*
X-1332180Y-515671D01*
X-1331314Y-515527D01*
X-1330447Y-514805D01*
X-1329906Y-513939D01*
X-1329798Y-513073D01*
X-1330014Y-512062D01*
X-1330772Y-511341D01*
X-1331530Y-511052D01*
X-1332505D01*
G01X-1331530D02*
X-1330881Y-510619D01*
X-1330339Y-509897D01*
X-1330123Y-509031D01*
X-1330339Y-508165D01*
X-1330881Y-507443D01*
X-1331855Y-507010D01*
X-1332829Y-507154D01*
X-1333804Y-507732D01*
G01X-1322328Y-515671D02*
Y-507010D01*
X-1326334Y-513217D01*
X-1320920D01*
G01X-1314966Y-515960D02*
X-1315183Y-515815D01*
Y-515527D01*
X-1314966Y-515382D01*
X-1314749Y-515527D01*
Y-515815D01*
X-1314966Y-515960D01*
G01X-1306305Y-515671D02*
X-1305547Y-515527D01*
X-1304681Y-515094D01*
X-1304140Y-514372D01*
X-1303923Y-513361D01*
X-1304140Y-512351D01*
X-1304789Y-511485D01*
X-1305764Y-511052D01*
X-1306846D01*
X-1307496Y-510763D01*
X-1308037Y-510041D01*
X-1308254Y-509031D01*
X-1307929Y-508020D01*
X-1307171Y-507299D01*
X-1306305Y-507010D01*
X-1305439Y-507299D01*
X-1304681Y-508020D01*
X-1304356Y-509031D01*
X-1304573Y-510041D01*
X-1305114Y-510763D01*
X-1305764Y-511052D01*
X-1306846D01*
X-1307821Y-511485D01*
X-1308470Y-512351D01*
X-1308687Y-513361D01*
X-1308470Y-514372D01*
X-1307929Y-515094D01*
X-1307063Y-515527D01*
X-1306305Y-515671D01*
G01X-1299701Y-512062D02*
X-1298943Y-511052D01*
X-1298294Y-510474D01*
X-1297427Y-510186D01*
X-1296670Y-510474D01*
X-1296128Y-511052D01*
X-1295695Y-511918D01*
X-1295587Y-512928D01*
X-1295695Y-513795D01*
X-1296128Y-514661D01*
X-1296778Y-515382D01*
X-1297536Y-515671D01*
X-1298402Y-515382D01*
X-1299160Y-514516D01*
X-1299593Y-513217D01*
X-1299701Y-511774D01*
X-1299485Y-509897D01*
X-1299160Y-508886D01*
X-1298618Y-507876D01*
X-1297861Y-507154D01*
X-1297103Y-507010D01*
X-1296345Y-507299D01*
X-1295803Y-508020D01*
G01X-1334425Y-488152D02*
Y-479491D01*
X-1338431Y-485698D01*
X-1333017D01*
G01X-1327063Y-488152D02*
Y-479491D01*
X-1328362Y-481223D01*
G01Y-488152D02*
X-1325764D01*
G01X-1318402Y-488441D02*
X-1318619Y-488296D01*
Y-488008D01*
X-1318402Y-487863D01*
X-1318185Y-488008D01*
Y-488296D01*
X-1318402Y-488441D01*
G01X-1309741Y-488152D02*
X-1308983Y-488008D01*
X-1308117Y-487575D01*
X-1307576Y-486853D01*
X-1307359Y-485842D01*
X-1307576Y-484832D01*
X-1308225Y-483966D01*
X-1309200Y-483533D01*
X-1310282D01*
X-1310932Y-483244D01*
X-1311473Y-482522D01*
X-1311690Y-481512D01*
X-1311365Y-480501D01*
X-1310607Y-479780D01*
X-1309741Y-479491D01*
X-1308875Y-479780D01*
X-1308117Y-480501D01*
X-1307792Y-481512D01*
X-1308009Y-482522D01*
X-1308550Y-483244D01*
X-1309200Y-483533D01*
X-1310282D01*
X-1311257Y-483966D01*
X-1311906Y-484832D01*
X-1312123Y-485842D01*
X-1311906Y-486853D01*
X-1311365Y-487575D01*
X-1310499Y-488008D01*
X-1309741Y-488152D01*
G01X-1303462Y-486853D02*
X-1302812Y-487575D01*
X-1302054Y-488008D01*
X-1301080Y-488152D01*
X-1300106Y-487863D01*
X-1299348Y-487286D01*
X-1298806Y-486276D01*
X-1298698Y-485121D01*
X-1298915Y-483966D01*
X-1299456Y-483244D01*
X-1300214Y-482667D01*
X-1300972Y-482522D01*
X-1301730Y-482667D01*
X-1302704Y-483244D01*
X-1302379Y-479491D01*
X-1299456D01*
G01X-1352804Y-438882D02*
Y-433108D01*
G01Y-434552D02*
X-1352370Y-433830D01*
X-1351721Y-433252D01*
X-1350855Y-433108D01*
X-1350097Y-433252D01*
X-1349447Y-433830D01*
X-1349122Y-434840D01*
Y-438882D01*
G01X-1353415Y438063D02*
X-1355291Y438280D01*
X-1356879Y438605D01*
X-1358323Y439038D01*
X-1359911Y439579D01*
X-1362076Y440445D01*
Y436115D01*
G01X-1353415Y446941D02*
X-1353559Y447699D01*
X-1353992Y448565D01*
X-1354714Y449106D01*
X-1355725Y449323D01*
X-1356735Y449106D01*
X-1357601Y448457D01*
X-1358034Y447482D01*
Y446400D01*
X-1358323Y445750D01*
X-1359045Y445209D01*
X-1360055Y444992D01*
X-1361066Y445317D01*
X-1361787Y446075D01*
X-1362076Y446941D01*
X-1361787Y447807D01*
X-1361066Y448565D01*
X-1360055Y448890D01*
X-1359045Y448673D01*
X-1358323Y448132D01*
X-1358034Y447482D01*
Y446400D01*
X-1357601Y445425D01*
X-1356735Y444776D01*
X-1355725Y444559D01*
X-1354714Y444776D01*
X-1353992Y445317D01*
X-1353559Y446183D01*
X-1353415Y446941D01*
G01X-1353126Y455602D02*
X-1353271Y455385D01*
X-1353559D01*
X-1353704Y455602D01*
X-1353559Y455819D01*
X-1353271D01*
X-1353126Y455602D01*
G01X-1354714Y461881D02*
X-1353992Y462531D01*
X-1353559Y463289D01*
X-1353415Y464263D01*
X-1353704Y465237D01*
X-1354281Y465995D01*
X-1355291Y466537D01*
X-1356446Y466645D01*
X-1357601Y466428D01*
X-1358323Y465887D01*
X-1358900Y465129D01*
X-1359045Y464371D01*
X-1358900Y463613D01*
X-1358323Y462639D01*
X-1362076Y462964D01*
Y465887D01*
G01Y472924D02*
X-1361787Y472058D01*
X-1361066Y471408D01*
X-1360200Y470975D01*
X-1359045Y470650D01*
X-1357745Y470542D01*
X-1356446Y470650D01*
X-1355291Y470975D01*
X-1354425Y471408D01*
X-1353704Y472058D01*
X-1353415Y472924D01*
X-1353704Y473790D01*
X-1354425Y474440D01*
X-1355291Y474873D01*
X-1356446Y475198D01*
X-1357745Y475306D01*
X-1359045Y475198D01*
X-1360200Y474873D01*
X-1361066Y474440D01*
X-1361787Y473790D01*
X-1362076Y472924D01*
G01X-1309406Y849291D02*
Y857952D01*
X-1310705Y856220D01*
G01Y849291D02*
X-1308107D01*
G01X-1302802Y856509D02*
X-1302152Y857374D01*
X-1301395Y857808D01*
X-1300528Y857952D01*
X-1299446Y857663D01*
X-1298688Y856942D01*
X-1298471Y856076D01*
X-1298580Y855209D01*
X-1299013Y854488D01*
X-1301178Y853044D01*
X-1302152Y852034D01*
X-1302802Y850590D01*
X-1303019Y849291D01*
X-1298471D01*
G01X-1292084Y857952D02*
X-1292950Y857663D01*
X-1293600Y856942D01*
X-1294033Y856076D01*
X-1294358Y854921D01*
X-1294466Y853621D01*
X-1294358Y852322D01*
X-1294033Y851167D01*
X-1293600Y850301D01*
X-1292950Y849580D01*
X-1292084Y849291D01*
X-1291218Y849580D01*
X-1290568Y850301D01*
X-1290135Y851167D01*
X-1289810Y852322D01*
X-1289702Y853621D01*
X-1289810Y854921D01*
X-1290135Y856076D01*
X-1290568Y856942D01*
X-1291218Y857663D01*
X-1292084Y857952D01*
G01X-1283423Y849002D02*
X-1283640Y849147D01*
Y849435D01*
X-1283423Y849580D01*
X-1283206Y849435D01*
Y849147D01*
X-1283423Y849002D01*
G01X-1274762Y857952D02*
X-1275628Y857663D01*
X-1276278Y856942D01*
X-1276711Y856076D01*
X-1277036Y854921D01*
X-1277144Y853621D01*
X-1277036Y852322D01*
X-1276711Y851167D01*
X-1276278Y850301D01*
X-1275628Y849580D01*
X-1274762Y849291D01*
X-1273896Y849580D01*
X-1273246Y850301D01*
X-1272813Y851167D01*
X-1272488Y852322D01*
X-1272380Y853621D01*
X-1272488Y854921D01*
X-1272813Y856076D01*
X-1273246Y856942D01*
X-1273896Y857663D01*
X-1274762Y857952D01*
G01X-1266101D02*
X-1266967Y857663D01*
X-1267617Y856942D01*
X-1268050Y856076D01*
X-1268375Y854921D01*
X-1268483Y853621D01*
X-1268375Y852322D01*
X-1268050Y851167D01*
X-1267617Y850301D01*
X-1266967Y849580D01*
X-1266101Y849291D01*
X-1265235Y849580D01*
X-1264585Y850301D01*
X-1264152Y851167D01*
X-1263827Y852322D01*
X-1263719Y853621D01*
X-1263827Y854921D01*
X-1264152Y856076D01*
X-1264585Y856942D01*
X-1265235Y857663D01*
X-1266101Y857952D01*
G01X-1334352Y915535D02*
X-1334496Y916293D01*
X-1334929Y917159D01*
X-1335651Y917700D01*
X-1336662Y917917D01*
X-1337672Y917700D01*
X-1338538Y917051D01*
X-1338971Y916076D01*
Y914994D01*
X-1339260Y914344D01*
X-1339982Y913803D01*
X-1340992Y913586D01*
X-1342003Y913911D01*
X-1342724Y914669D01*
X-1343013Y915535D01*
X-1342724Y916401D01*
X-1342003Y917159D01*
X-1340992Y917484D01*
X-1339982Y917267D01*
X-1339260Y916726D01*
X-1338971Y916076D01*
Y914994D01*
X-1338538Y914019D01*
X-1337672Y913370D01*
X-1336662Y913153D01*
X-1335651Y913370D01*
X-1334929Y913911D01*
X-1334496Y914777D01*
X-1334352Y915535D01*
G01X-1343013Y924196D02*
X-1342724Y923330D01*
X-1342003Y922680D01*
X-1341137Y922247D01*
X-1339982Y921922D01*
X-1338682Y921814D01*
X-1337383Y921922D01*
X-1336228Y922247D01*
X-1335362Y922680D01*
X-1334641Y923330D01*
X-1334352Y924196D01*
X-1334641Y925062D01*
X-1335362Y925712D01*
X-1336228Y926145D01*
X-1337383Y926470D01*
X-1338682Y926578D01*
X-1339982Y926470D01*
X-1341137Y926145D01*
X-1342003Y925712D01*
X-1342724Y925062D01*
X-1343013Y924196D01*
G01X-1334063Y932857D02*
X-1334208Y932640D01*
X-1334496D01*
X-1334641Y932857D01*
X-1334496Y933074D01*
X-1334208D01*
X-1334063Y932857D01*
G01X-1343013Y941518D02*
X-1342724Y940652D01*
X-1342003Y940002D01*
X-1341137Y939569D01*
X-1339982Y939244D01*
X-1338682Y939136D01*
X-1337383Y939244D01*
X-1336228Y939569D01*
X-1335362Y940002D01*
X-1334641Y940652D01*
X-1334352Y941518D01*
X-1334641Y942384D01*
X-1335362Y943034D01*
X-1336228Y943467D01*
X-1337383Y943792D01*
X-1338682Y943900D01*
X-1339982Y943792D01*
X-1341137Y943467D01*
X-1342003Y943034D01*
X-1342724Y942384D01*
X-1343013Y941518D01*
G01Y950179D02*
X-1342724Y949313D01*
X-1342003Y948663D01*
X-1341137Y948230D01*
X-1339982Y947905D01*
X-1338682Y947797D01*
X-1337383Y947905D01*
X-1336228Y948230D01*
X-1335362Y948663D01*
X-1334641Y949313D01*
X-1334352Y950179D01*
X-1334641Y951045D01*
X-1335362Y951695D01*
X-1336228Y952128D01*
X-1337383Y952453D01*
X-1338682Y952561D01*
X-1339982Y952453D01*
X-1341137Y952128D01*
X-1342003Y951695D01*
X-1342724Y951045D01*
X-1343013Y950179D01*
G01X-1353218Y915243D02*
X-1355094Y915460D01*
X-1356682Y915785D01*
X-1358126Y916218D01*
X-1359714Y916759D01*
X-1361879Y917625D01*
Y913295D01*
G01X-1353218Y924121D02*
X-1353362Y924879D01*
X-1353795Y925745D01*
X-1354517Y926286D01*
X-1355528Y926503D01*
X-1356538Y926286D01*
X-1357404Y925637D01*
X-1357837Y924662D01*
Y923580D01*
X-1358126Y922930D01*
X-1358848Y922389D01*
X-1359858Y922172D01*
X-1360869Y922497D01*
X-1361590Y923255D01*
X-1361879Y924121D01*
X-1361590Y924987D01*
X-1360869Y925745D01*
X-1359858Y926070D01*
X-1358848Y925853D01*
X-1358126Y925312D01*
X-1357837Y924662D01*
Y923580D01*
X-1357404Y922605D01*
X-1356538Y921956D01*
X-1355528Y921739D01*
X-1354517Y921956D01*
X-1353795Y922497D01*
X-1353362Y923363D01*
X-1353218Y924121D01*
G01X-1352929Y932782D02*
X-1353074Y932565D01*
X-1353362D01*
X-1353507Y932782D01*
X-1353362Y932999D01*
X-1353074D01*
X-1352929Y932782D01*
G01X-1354517Y939061D02*
X-1353795Y939711D01*
X-1353362Y940469D01*
X-1353218Y941443D01*
X-1353507Y942417D01*
X-1354084Y943175D01*
X-1355094Y943717D01*
X-1356249Y943825D01*
X-1357404Y943608D01*
X-1358126Y943067D01*
X-1358703Y942309D01*
X-1358848Y941551D01*
X-1358703Y940793D01*
X-1358126Y939819D01*
X-1361879Y940144D01*
Y943067D01*
G01X-1354517Y947722D02*
X-1353795Y948372D01*
X-1353362Y949130D01*
X-1353218Y950104D01*
X-1353507Y951078D01*
X-1354084Y951836D01*
X-1355094Y952378D01*
X-1356249Y952486D01*
X-1357404Y952269D01*
X-1358126Y951728D01*
X-1358703Y950970D01*
X-1358848Y950212D01*
X-1358703Y949454D01*
X-1358126Y948480D01*
X-1361879Y948805D01*
Y951728D01*
G01X-1299307Y1173829D02*
X-1298586Y1174587D01*
X-1298297Y1175453D01*
X-1298586Y1176320D01*
X-1299452Y1177077D01*
X-1300751Y1177619D01*
X-1302050Y1177835D01*
X-1303638D01*
X-1304937Y1177619D01*
X-1306092Y1177077D01*
X-1306669Y1176428D01*
X-1306958Y1175670D01*
X-1306669Y1174804D01*
X-1306092Y1174154D01*
X-1305226Y1173721D01*
X-1304071Y1173505D01*
X-1303061Y1173721D01*
X-1302050Y1174263D01*
X-1301473Y1174912D01*
X-1301328Y1175670D01*
X-1301617Y1176536D01*
X-1302339Y1177186D01*
X-1303638Y1177835D01*
G01X-1305515Y1182274D02*
X-1306380Y1182924D01*
X-1306814Y1183681D01*
X-1306958Y1184548D01*
X-1306669Y1185630D01*
X-1305948Y1186388D01*
X-1305082Y1186605D01*
X-1304215Y1186496D01*
X-1303494Y1186063D01*
X-1302050Y1183898D01*
X-1301040Y1182924D01*
X-1299596Y1182274D01*
X-1298297Y1182057D01*
Y1186605D01*
G01X-1298008Y1192992D02*
X-1298153Y1192775D01*
X-1298441D01*
X-1298586Y1192992D01*
X-1298441Y1193209D01*
X-1298153D01*
X-1298008Y1192992D01*
G01X-1299596Y1199271D02*
X-1298874Y1199921D01*
X-1298441Y1200679D01*
X-1298297Y1201653D01*
X-1298586Y1202627D01*
X-1299163Y1203385D01*
X-1300173Y1203927D01*
X-1301328Y1204035D01*
X-1302483Y1203818D01*
X-1303205Y1203277D01*
X-1303782Y1202519D01*
X-1303927Y1201761D01*
X-1303782Y1201003D01*
X-1303205Y1200029D01*
X-1306958Y1200354D01*
Y1203277D01*
G01Y1210314D02*
X-1306669Y1209448D01*
X-1305948Y1208798D01*
X-1305082Y1208365D01*
X-1303927Y1208040D01*
X-1302627Y1207932D01*
X-1301328Y1208040D01*
X-1300173Y1208365D01*
X-1299307Y1208798D01*
X-1298586Y1209448D01*
X-1298297Y1210314D01*
X-1298586Y1211180D01*
X-1299307Y1211830D01*
X-1300173Y1212263D01*
X-1301328Y1212588D01*
X-1302627Y1212696D01*
X-1303927Y1212588D01*
X-1305082Y1212263D01*
X-1305948Y1211830D01*
X-1306669Y1211180D01*
X-1306958Y1210314D01*
G01X-1267356Y-852846D02*
Y-841484D01*
X-1272611Y-849627D01*
X-1265509D01*
G01X-1243042Y-743801D02*
X-1251703D01*
X-1249971Y-745100D01*
G01X-1243042D02*
Y-742502D01*
G01X-1250260Y-737197D02*
X-1251125Y-736547D01*
X-1251559Y-735790D01*
X-1251703Y-734923D01*
X-1251414Y-733841D01*
X-1250693Y-733083D01*
X-1249827Y-732866D01*
X-1248960Y-732975D01*
X-1248239Y-733408D01*
X-1246795Y-735573D01*
X-1245785Y-736547D01*
X-1244341Y-737197D01*
X-1243042Y-737414D01*
Y-732866D01*
G01Y-725180D02*
X-1251703D01*
X-1245496Y-729186D01*
Y-723772D01*
G01X-1242753Y-717818D02*
X-1242898Y-718035D01*
X-1243186D01*
X-1243331Y-717818D01*
X-1243186Y-717601D01*
X-1242898D01*
X-1242753Y-717818D01*
G01X-1243042Y-709157D02*
X-1251703D01*
X-1249971Y-710456D01*
G01X-1243042D02*
Y-707858D01*
G01Y-700713D02*
X-1244918Y-700496D01*
X-1246506Y-700171D01*
X-1247950Y-699738D01*
X-1249538Y-699197D01*
X-1251703Y-698331D01*
Y-702661D01*
G01X-1256958Y246575D02*
X-1265619D01*
X-1263887Y245276D01*
G01X-1256958D02*
Y247874D01*
G01X-1265619Y255236D02*
X-1265330Y254370D01*
X-1264609Y253720D01*
X-1263743Y253287D01*
X-1262588Y252962D01*
X-1261288Y252854D01*
X-1259989Y252962D01*
X-1258834Y253287D01*
X-1257968Y253720D01*
X-1257247Y254370D01*
X-1256958Y255236D01*
X-1257247Y256102D01*
X-1257968Y256752D01*
X-1258834Y257185D01*
X-1259989Y257510D01*
X-1261288Y257618D01*
X-1262588Y257510D01*
X-1263743Y257185D01*
X-1264609Y256752D01*
X-1265330Y256102D01*
X-1265619Y255236D01*
G01X-1258690Y261515D02*
X-1257680Y262165D01*
X-1257102Y263031D01*
X-1256958Y264005D01*
X-1257102Y264871D01*
X-1257824Y265738D01*
X-1258690Y266279D01*
X-1259556Y266387D01*
X-1260567Y266171D01*
X-1261288Y265413D01*
X-1261577Y264655D01*
Y263680D01*
G01Y264655D02*
X-1262010Y265304D01*
X-1262732Y265846D01*
X-1263598Y266062D01*
X-1264464Y265846D01*
X-1265186Y265304D01*
X-1265619Y264330D01*
X-1265475Y263356D01*
X-1264897Y262381D01*
G01X-1256669Y272558D02*
X-1256814Y272341D01*
X-1257102D01*
X-1257247Y272558D01*
X-1257102Y272775D01*
X-1256814D01*
X-1256669Y272558D01*
G01X-1265619Y281219D02*
X-1265330Y280353D01*
X-1264609Y279703D01*
X-1263743Y279270D01*
X-1262588Y278945D01*
X-1261288Y278837D01*
X-1259989Y278945D01*
X-1258834Y279270D01*
X-1257968Y279703D01*
X-1257247Y280353D01*
X-1256958Y281219D01*
X-1257247Y282085D01*
X-1257968Y282735D01*
X-1258834Y283168D01*
X-1259989Y283493D01*
X-1261288Y283601D01*
X-1262588Y283493D01*
X-1263743Y283168D01*
X-1264609Y282735D01*
X-1265330Y282085D01*
X-1265619Y281219D01*
G01Y289880D02*
X-1265330Y289014D01*
X-1264609Y288364D01*
X-1263743Y287931D01*
X-1262588Y287606D01*
X-1261288Y287498D01*
X-1259989Y287606D01*
X-1258834Y287931D01*
X-1257968Y288364D01*
X-1257247Y289014D01*
X-1256958Y289880D01*
X-1257247Y290746D01*
X-1257968Y291396D01*
X-1258834Y291829D01*
X-1259989Y292154D01*
X-1261288Y292262D01*
X-1262588Y292154D01*
X-1263743Y291829D01*
X-1264609Y291396D01*
X-1265330Y290746D01*
X-1265619Y289880D01*
G01X-1254202Y1175237D02*
X-1262863D01*
X-1261131Y1173938D01*
G01X-1254202D02*
Y1176536D01*
G01X-1262863Y1183898D02*
X-1262574Y1183032D01*
X-1261853Y1182382D01*
X-1260987Y1181949D01*
X-1259832Y1181624D01*
X-1258532Y1181516D01*
X-1257233Y1181624D01*
X-1256078Y1181949D01*
X-1255212Y1182382D01*
X-1254491Y1183032D01*
X-1254202Y1183898D01*
X-1254491Y1184764D01*
X-1255212Y1185414D01*
X-1256078Y1185847D01*
X-1257233Y1186172D01*
X-1258532Y1186280D01*
X-1259832Y1186172D01*
X-1260987Y1185847D01*
X-1261853Y1185414D01*
X-1262574Y1184764D01*
X-1262863Y1183898D01*
G01X-1255934Y1190177D02*
X-1254924Y1190827D01*
X-1254346Y1191693D01*
X-1254202Y1192667D01*
X-1254346Y1193533D01*
X-1255068Y1194400D01*
X-1255934Y1194941D01*
X-1256800Y1195049D01*
X-1257811Y1194833D01*
X-1258532Y1194075D01*
X-1258821Y1193317D01*
Y1192342D01*
G01Y1193317D02*
X-1259254Y1193966D01*
X-1259976Y1194508D01*
X-1260842Y1194724D01*
X-1261708Y1194508D01*
X-1262430Y1193966D01*
X-1262863Y1192992D01*
X-1262719Y1192018D01*
X-1262141Y1191043D01*
G01X-1253913Y1201220D02*
X-1254058Y1201003D01*
X-1254346D01*
X-1254491Y1201220D01*
X-1254346Y1201437D01*
X-1254058D01*
X-1253913Y1201220D01*
G01X-1254202Y1209664D02*
X-1256078Y1209881D01*
X-1257666Y1210206D01*
X-1259110Y1210639D01*
X-1260698Y1211180D01*
X-1262863Y1212046D01*
Y1207716D01*
G01Y1218542D02*
X-1262574Y1217676D01*
X-1261853Y1217026D01*
X-1260987Y1216593D01*
X-1259832Y1216268D01*
X-1258532Y1216160D01*
X-1257233Y1216268D01*
X-1256078Y1216593D01*
X-1255212Y1217026D01*
X-1254491Y1217676D01*
X-1254202Y1218542D01*
X-1254491Y1219408D01*
X-1255212Y1220058D01*
X-1256078Y1220491D01*
X-1257233Y1220816D01*
X-1258532Y1220924D01*
X-1259832Y1220816D01*
X-1260987Y1220491D01*
X-1261853Y1220058D01*
X-1262574Y1219408D01*
X-1262863Y1218542D01*
G01X-1267356Y1324910D02*
Y1336272D01*
X-1272611Y1328129D01*
X-1265509D01*
G01X-1178467Y220813D02*
X-1179117Y221246D01*
X-1179875Y221535D01*
X-1180741D01*
X-1181715Y221102D01*
X-1182473Y220380D01*
X-1183014Y219514D01*
X-1183448Y218071D01*
X-1183556Y216771D01*
X-1183339Y215472D01*
X-1183014Y214606D01*
X-1182365Y213740D01*
X-1181607Y213163D01*
X-1180849Y212874D01*
X-1180091D01*
X-1179333Y213163D01*
X-1178684Y213596D01*
X-1178142Y214173D01*
G01X-1172188Y212874D02*
X-1173054Y213018D01*
X-1173812Y213596D01*
X-1174462Y214462D01*
X-1174895Y215472D01*
X-1175111Y216627D01*
Y217782D01*
X-1174895Y218937D01*
X-1174462Y219947D01*
X-1173812Y220813D01*
X-1173054Y221391D01*
X-1172188Y221535D01*
X-1171322Y221391D01*
X-1170564Y220813D01*
X-1169914Y219947D01*
X-1169481Y218937D01*
X-1169265Y217782D01*
Y216627D01*
X-1169481Y215472D01*
X-1169914Y214462D01*
X-1170564Y213596D01*
X-1171322Y213018D01*
X-1172188Y212874D01*
G01X-1166342D02*
Y221535D01*
X-1163527Y214317D01*
X-1160712Y221535D01*
Y212874D01*
G01X-1157031D02*
Y221535D01*
X-1154433D01*
X-1153567Y221102D01*
X-1152917Y220092D01*
X-1152701Y218937D01*
X-1152917Y217782D01*
X-1153459Y216916D01*
X-1154433Y216483D01*
X-1157031D01*
G01X-1146205Y212874D02*
X-1147071Y213018D01*
X-1147829Y213596D01*
X-1148479Y214462D01*
X-1148912Y215472D01*
X-1149128Y216627D01*
Y217782D01*
X-1148912Y218937D01*
X-1148479Y219947D01*
X-1147829Y220813D01*
X-1147071Y221391D01*
X-1146205Y221535D01*
X-1145339Y221391D01*
X-1144581Y220813D01*
X-1143931Y219947D01*
X-1143498Y218937D01*
X-1143282Y217782D01*
Y216627D01*
X-1143498Y215472D01*
X-1143931Y214462D01*
X-1144581Y213596D01*
X-1145339Y213018D01*
X-1146205Y212874D01*
G01X-1140034D02*
Y221535D01*
X-1135054Y212874D01*
Y221535D01*
G01X-1126718Y212874D02*
X-1131048D01*
Y221535D01*
X-1126718D01*
G01X-1128450Y217349D02*
X-1131048D01*
G01X-1122712Y212874D02*
Y221535D01*
X-1117732Y212874D01*
Y221535D01*
G01X-1111561D02*
Y212874D01*
G01X-1114051Y221535D02*
X-1109071D01*
G01X-1096513Y214029D02*
X-1095646Y213307D01*
X-1094672Y212874D01*
X-1093806D01*
X-1092940Y213307D01*
X-1092290Y214029D01*
X-1091965Y215039D01*
X-1092182Y216050D01*
X-1092723Y216916D01*
X-1093698Y217493D01*
X-1094997Y217782D01*
X-1095755Y218359D01*
X-1096080Y219370D01*
X-1095863Y220380D01*
X-1095322Y221102D01*
X-1094564Y221535D01*
X-1093806D01*
X-1093048Y221246D01*
X-1092398Y220525D01*
G01X-1086877Y221535D02*
X-1084279D01*
G01X-1085578D02*
Y212874D01*
G01X-1086877D02*
X-1084279D01*
G01X-1079299D02*
Y221535D01*
X-1077134D01*
X-1076267Y221102D01*
X-1075618Y220525D01*
X-1075076Y219659D01*
X-1074643Y218648D01*
X-1074535Y217204D01*
X-1074643Y215761D01*
X-1075076Y214750D01*
X-1075618Y213884D01*
X-1076267Y213307D01*
X-1077134Y212874D01*
X-1079299D01*
G01X-1066091D02*
X-1070421D01*
Y221535D01*
X-1066091D01*
G01X-1067823Y217349D02*
X-1070421D01*
G01X-1193312Y790433D02*
Y799094D01*
X-1194611Y797362D01*
G01Y790433D02*
X-1192013D01*
G01X-1184651Y799094D02*
X-1185517Y798805D01*
X-1186167Y798084D01*
X-1186600Y797218D01*
X-1186925Y796063D01*
X-1187033Y794763D01*
X-1186925Y793464D01*
X-1186600Y792309D01*
X-1186167Y791443D01*
X-1185517Y790722D01*
X-1184651Y790433D01*
X-1183785Y790722D01*
X-1183135Y791443D01*
X-1182702Y792309D01*
X-1182377Y793464D01*
X-1182269Y794763D01*
X-1182377Y796063D01*
X-1182702Y797218D01*
X-1183135Y798084D01*
X-1183785Y798805D01*
X-1184651Y799094D01*
G01X-1178372Y791732D02*
X-1177722Y791010D01*
X-1176964Y790577D01*
X-1175990Y790433D01*
X-1175016Y790722D01*
X-1174258Y791299D01*
X-1173716Y792309D01*
X-1173608Y793464D01*
X-1173825Y794619D01*
X-1174366Y795341D01*
X-1175124Y795918D01*
X-1175882Y796063D01*
X-1176640Y795918D01*
X-1177614Y795341D01*
X-1177289Y799094D01*
X-1174366D01*
G01X-1167329Y790144D02*
X-1167546Y790289D01*
Y790577D01*
X-1167329Y790722D01*
X-1167112Y790577D01*
Y790289D01*
X-1167329Y790144D01*
G01X-1158668Y799094D02*
X-1159534Y798805D01*
X-1160184Y798084D01*
X-1160617Y797218D01*
X-1160942Y796063D01*
X-1161050Y794763D01*
X-1160942Y793464D01*
X-1160617Y792309D01*
X-1160184Y791443D01*
X-1159534Y790722D01*
X-1158668Y790433D01*
X-1157802Y790722D01*
X-1157152Y791443D01*
X-1156719Y792309D01*
X-1156394Y793464D01*
X-1156286Y794763D01*
X-1156394Y796063D01*
X-1156719Y797218D01*
X-1157152Y798084D01*
X-1157802Y798805D01*
X-1158668Y799094D01*
G01X-1152389Y791732D02*
X-1151739Y791010D01*
X-1150981Y790577D01*
X-1150007Y790433D01*
X-1149033Y790722D01*
X-1148275Y791299D01*
X-1147733Y792309D01*
X-1147625Y793464D01*
X-1147842Y794619D01*
X-1148383Y795341D01*
X-1149141Y795918D01*
X-1149899Y796063D01*
X-1150657Y795918D01*
X-1151631Y795341D01*
X-1151306Y799094D01*
X-1148383D01*
G01X-1210719Y848544D02*
X-1209852Y847822D01*
X-1208878Y847389D01*
X-1208012D01*
X-1207146Y847822D01*
X-1206496Y848544D01*
X-1206171Y849554D01*
X-1206388Y850565D01*
X-1206929Y851431D01*
X-1207904Y852008D01*
X-1209203Y852297D01*
X-1209961Y852874D01*
X-1210286Y853885D01*
X-1210069Y854895D01*
X-1209528Y855617D01*
X-1208770Y856050D01*
X-1208012D01*
X-1207254Y855761D01*
X-1206604Y855040D01*
G01X-1197619Y847389D02*
X-1201949D01*
Y856050D01*
X-1197619D01*
G01X-1199351Y851864D02*
X-1201949D01*
G01X-1188958Y847389D02*
X-1193288D01*
Y856050D01*
X-1188958D01*
G01X-1190690Y851864D02*
X-1193288D01*
G01X-1176183Y847389D02*
Y856050D01*
X-1174018D01*
X-1173151Y855617D01*
X-1172502Y855040D01*
X-1171960Y854174D01*
X-1171527Y853163D01*
X-1171419Y851719D01*
X-1171527Y850276D01*
X-1171960Y849265D01*
X-1172502Y848399D01*
X-1173151Y847822D01*
X-1174018Y847389D01*
X-1176183D01*
G01X-1162975D02*
X-1167305D01*
Y856050D01*
X-1162975D01*
G01X-1164707Y851864D02*
X-1167305D01*
G01X-1156479Y856050D02*
Y847389D01*
G01X-1158969Y856050D02*
X-1153989D01*
G01X-1150525Y847389D02*
X-1147818Y856050D01*
X-1145111Y847389D01*
G01X-1146086Y850420D02*
X-1149550D01*
G01X-1140456Y856050D02*
X-1137858D01*
G01X-1139157D02*
Y847389D01*
G01X-1140456D02*
X-1137858D01*
G01X-1132661Y856050D02*
Y847389D01*
X-1128331D01*
G01X-1101959Y-743801D02*
X-1110620D01*
X-1108888Y-745100D01*
G01X-1101959D02*
Y-742502D01*
G01X-1105568Y-737197D02*
X-1106578Y-736439D01*
X-1107156Y-735790D01*
X-1107444Y-734923D01*
X-1107156Y-734166D01*
X-1106578Y-733624D01*
X-1105712Y-733191D01*
X-1104702Y-733083D01*
X-1103835Y-733191D01*
X-1102969Y-733624D01*
X-1102248Y-734274D01*
X-1101959Y-735032D01*
X-1102248Y-735898D01*
X-1103114Y-736656D01*
X-1104413Y-737089D01*
X-1105856Y-737197D01*
X-1107733Y-736981D01*
X-1108744Y-736656D01*
X-1109754Y-736114D01*
X-1110476Y-735357D01*
X-1110620Y-734599D01*
X-1110331Y-733841D01*
X-1109610Y-733299D01*
G01X-1110620Y-726479D02*
X-1110331Y-727345D01*
X-1109610Y-727995D01*
X-1108744Y-728428D01*
X-1107589Y-728753D01*
X-1106289Y-728861D01*
X-1104990Y-728753D01*
X-1103835Y-728428D01*
X-1102969Y-727995D01*
X-1102248Y-727345D01*
X-1101959Y-726479D01*
X-1102248Y-725613D01*
X-1102969Y-724963D01*
X-1103835Y-724530D01*
X-1104990Y-724205D01*
X-1106289Y-724097D01*
X-1107589Y-724205D01*
X-1108744Y-724530D01*
X-1109610Y-724963D01*
X-1110331Y-725613D01*
X-1110620Y-726479D01*
G01X-1101670Y-717818D02*
X-1101815Y-718035D01*
X-1102103D01*
X-1102248Y-717818D01*
X-1102103Y-717601D01*
X-1101815D01*
X-1101670Y-717818D01*
G01X-1110620Y-709157D02*
X-1110331Y-710023D01*
X-1109610Y-710673D01*
X-1108744Y-711106D01*
X-1107589Y-711431D01*
X-1106289Y-711539D01*
X-1104990Y-711431D01*
X-1103835Y-711106D01*
X-1102969Y-710673D01*
X-1102248Y-710023D01*
X-1101959Y-709157D01*
X-1102248Y-708291D01*
X-1102969Y-707641D01*
X-1103835Y-707208D01*
X-1104990Y-706883D01*
X-1106289Y-706775D01*
X-1107589Y-706883D01*
X-1108744Y-707208D01*
X-1109610Y-707641D01*
X-1110331Y-708291D01*
X-1110620Y-709157D01*
G01Y-700496D02*
X-1110331Y-701362D01*
X-1109610Y-702012D01*
X-1108744Y-702445D01*
X-1107589Y-702770D01*
X-1106289Y-702878D01*
X-1104990Y-702770D01*
X-1103835Y-702445D01*
X-1102969Y-702012D01*
X-1102248Y-701362D01*
X-1101959Y-700496D01*
X-1102248Y-699630D01*
X-1102969Y-698980D01*
X-1103835Y-698547D01*
X-1104990Y-698222D01*
X-1106289Y-698114D01*
X-1107589Y-698222D01*
X-1108744Y-698547D01*
X-1109610Y-698980D01*
X-1110331Y-699630D01*
X-1110620Y-700496D01*
G01X-1117608Y847389D02*
X-1114901Y856050D01*
X-1112194Y847389D01*
G01X-1113169Y850420D02*
X-1116633D01*
G01X-1094360Y1175237D02*
X-1103021D01*
X-1101289Y1173938D01*
G01X-1094360D02*
Y1176536D01*
G01Y1185197D02*
X-1103021D01*
X-1096814Y1181191D01*
Y1186605D01*
G01X-1094360Y1193858D02*
X-1103021D01*
X-1096814Y1189852D01*
Y1195266D01*
G01X-1094071Y1201220D02*
X-1094216Y1201003D01*
X-1094504D01*
X-1094649Y1201220D01*
X-1094504Y1201437D01*
X-1094216D01*
X-1094071Y1201220D01*
G01X-1096092Y1207499D02*
X-1095082Y1208149D01*
X-1094504Y1209015D01*
X-1094360Y1209989D01*
X-1094504Y1210855D01*
X-1095226Y1211722D01*
X-1096092Y1212263D01*
X-1096958Y1212371D01*
X-1097969Y1212155D01*
X-1098690Y1211397D01*
X-1098979Y1210639D01*
Y1209664D01*
G01Y1210639D02*
X-1099412Y1211288D01*
X-1100134Y1211830D01*
X-1101000Y1212046D01*
X-1101866Y1211830D01*
X-1102588Y1211288D01*
X-1103021Y1210314D01*
X-1102877Y1209340D01*
X-1102299Y1208365D01*
G01X-1103021Y1218542D02*
X-1102732Y1217676D01*
X-1102011Y1217026D01*
X-1101145Y1216593D01*
X-1099990Y1216268D01*
X-1098690Y1216160D01*
X-1097391Y1216268D01*
X-1096236Y1216593D01*
X-1095370Y1217026D01*
X-1094649Y1217676D01*
X-1094360Y1218542D01*
X-1094649Y1219408D01*
X-1095370Y1220058D01*
X-1096236Y1220491D01*
X-1097391Y1220816D01*
X-1098690Y1220924D01*
X-1099990Y1220816D01*
X-1101145Y1220491D01*
X-1102011Y1220058D01*
X-1102732Y1219408D01*
X-1103021Y1218542D01*
G01X-1052515Y-851142D02*
X-1051663Y-852089D01*
X-1050668Y-852657D01*
X-1049390Y-852846D01*
X-1048112Y-852467D01*
X-1047118Y-851710D01*
X-1046407Y-850384D01*
X-1046265Y-848869D01*
X-1046549Y-847354D01*
X-1047260Y-846408D01*
X-1048254Y-845650D01*
X-1049248Y-845461D01*
X-1050242Y-845650D01*
X-1051520Y-846408D01*
X-1051094Y-841484D01*
X-1047260D01*
G01X-1074402Y556850D02*
Y565511D01*
X-1078408Y559304D01*
X-1072994D01*
G01X-1069422Y558149D02*
X-1068772Y557427D01*
X-1068014Y556994D01*
X-1067040Y556850D01*
X-1066066Y557139D01*
X-1065308Y557716D01*
X-1064766Y558726D01*
X-1064658Y559881D01*
X-1064875Y561036D01*
X-1065416Y561758D01*
X-1066174Y562335D01*
X-1066932Y562480D01*
X-1067690Y562335D01*
X-1068664Y561758D01*
X-1068339Y565511D01*
X-1065416D01*
G01X-1058379Y556561D02*
X-1058596Y556706D01*
Y556994D01*
X-1058379Y557139D01*
X-1058162Y556994D01*
Y556706D01*
X-1058379Y556561D01*
G01X-1049935Y556850D02*
X-1049718Y558726D01*
X-1049393Y560314D01*
X-1048960Y561758D01*
X-1048419Y563346D01*
X-1047553Y565511D01*
X-1051883D01*
G01X-1043114Y564068D02*
X-1042464Y564933D01*
X-1041707Y565367D01*
X-1040840Y565511D01*
X-1039758Y565222D01*
X-1039000Y564501D01*
X-1038783Y563635D01*
X-1038892Y562768D01*
X-1039325Y562047D01*
X-1041490Y560603D01*
X-1042464Y559593D01*
X-1043114Y558149D01*
X-1043331Y556850D01*
X-1038783D01*
G01X-1050265Y841961D02*
X-1058926D01*
X-1057194Y840662D01*
G01X-1050265D02*
Y843260D01*
G01X-1051564Y848240D02*
X-1050842Y848890D01*
X-1050409Y849648D01*
X-1050265Y850622D01*
X-1050554Y851596D01*
X-1051131Y852354D01*
X-1052141Y852896D01*
X-1053296Y853004D01*
X-1054451Y852787D01*
X-1055173Y852246D01*
X-1055750Y851488D01*
X-1055895Y850730D01*
X-1055750Y849972D01*
X-1055173Y848998D01*
X-1058926Y849323D01*
Y852246D01*
G01X-1051564Y856901D02*
X-1050842Y857551D01*
X-1050409Y858309D01*
X-1050265Y859283D01*
X-1050554Y860257D01*
X-1051131Y861015D01*
X-1052141Y861557D01*
X-1053296Y861665D01*
X-1054451Y861448D01*
X-1055173Y860907D01*
X-1055750Y860149D01*
X-1055895Y859391D01*
X-1055750Y858633D01*
X-1055173Y857659D01*
X-1058926Y857984D01*
Y860907D01*
G01X-1049976Y867944D02*
X-1050121Y867727D01*
X-1050409D01*
X-1050554Y867944D01*
X-1050409Y868161D01*
X-1050121D01*
X-1049976Y867944D01*
G01X-1051564Y874223D02*
X-1050842Y874873D01*
X-1050409Y875631D01*
X-1050265Y876605D01*
X-1050554Y877579D01*
X-1051131Y878337D01*
X-1052141Y878879D01*
X-1053296Y878987D01*
X-1054451Y878770D01*
X-1055173Y878229D01*
X-1055750Y877471D01*
X-1055895Y876713D01*
X-1055750Y875955D01*
X-1055173Y874981D01*
X-1058926Y875306D01*
Y878229D01*
G01Y885266D02*
X-1058637Y884400D01*
X-1057916Y883750D01*
X-1057050Y883317D01*
X-1055895Y882992D01*
X-1054595Y882884D01*
X-1053296Y882992D01*
X-1052141Y883317D01*
X-1051275Y883750D01*
X-1050554Y884400D01*
X-1050265Y885266D01*
X-1050554Y886132D01*
X-1051275Y886782D01*
X-1052141Y887215D01*
X-1053296Y887540D01*
X-1054595Y887648D01*
X-1055895Y887540D01*
X-1057050Y887215D01*
X-1057916Y886782D01*
X-1058637Y886132D01*
X-1058926Y885266D01*
G01X-1050265Y1175237D02*
X-1058926D01*
X-1057194Y1173938D01*
G01X-1050265D02*
Y1176536D01*
G01X-1051564Y1181516D02*
X-1050842Y1182166D01*
X-1050409Y1182924D01*
X-1050265Y1183898D01*
X-1050554Y1184872D01*
X-1051131Y1185630D01*
X-1052141Y1186172D01*
X-1053296Y1186280D01*
X-1054451Y1186063D01*
X-1055173Y1185522D01*
X-1055750Y1184764D01*
X-1055895Y1184006D01*
X-1055750Y1183248D01*
X-1055173Y1182274D01*
X-1058926Y1182599D01*
Y1185522D01*
G01X-1051564Y1190177D02*
X-1050842Y1190827D01*
X-1050409Y1191585D01*
X-1050265Y1192559D01*
X-1050554Y1193533D01*
X-1051131Y1194291D01*
X-1052141Y1194833D01*
X-1053296Y1194941D01*
X-1054451Y1194724D01*
X-1055173Y1194183D01*
X-1055750Y1193425D01*
X-1055895Y1192667D01*
X-1055750Y1191909D01*
X-1055173Y1190935D01*
X-1058926Y1191260D01*
Y1194183D01*
G01X-1049976Y1201220D02*
X-1050121Y1201003D01*
X-1050409D01*
X-1050554Y1201220D01*
X-1050409Y1201437D01*
X-1050121D01*
X-1049976Y1201220D01*
G01X-1051564Y1207499D02*
X-1050842Y1208149D01*
X-1050409Y1208907D01*
X-1050265Y1209881D01*
X-1050554Y1210855D01*
X-1051131Y1211613D01*
X-1052141Y1212155D01*
X-1053296Y1212263D01*
X-1054451Y1212046D01*
X-1055173Y1211505D01*
X-1055750Y1210747D01*
X-1055895Y1209989D01*
X-1055750Y1209231D01*
X-1055173Y1208257D01*
X-1058926Y1208582D01*
Y1211505D01*
G01Y1218542D02*
X-1058637Y1217676D01*
X-1057916Y1217026D01*
X-1057050Y1216593D01*
X-1055895Y1216268D01*
X-1054595Y1216160D01*
X-1053296Y1216268D01*
X-1052141Y1216593D01*
X-1051275Y1217026D01*
X-1050554Y1217676D01*
X-1050265Y1218542D01*
X-1050554Y1219408D01*
X-1051275Y1220058D01*
X-1052141Y1220491D01*
X-1053296Y1220816D01*
X-1054595Y1220924D01*
X-1055895Y1220816D01*
X-1057050Y1220491D01*
X-1057916Y1220058D01*
X-1058637Y1219408D01*
X-1058926Y1218542D01*
G01X-1052515Y1326614D02*
X-1051663Y1325667D01*
X-1050668Y1325099D01*
X-1049390Y1324910D01*
X-1048112Y1325289D01*
X-1047118Y1326046D01*
X-1046407Y1327372D01*
X-1046265Y1328887D01*
X-1046549Y1330402D01*
X-1047260Y1331348D01*
X-1048254Y1332106D01*
X-1049248Y1332295D01*
X-1050242Y1332106D01*
X-1051520Y1331348D01*
X-1051094Y1336272D01*
X-1047260D01*
G01X-1022476Y-805446D02*
X-1023559Y-804002D01*
X-1024100Y-802559D01*
Y-796785D01*
X-1023559Y-795341D01*
X-1022476Y-793898D01*
G01X-1015764Y-802559D02*
Y-793898D01*
X-1010784Y-802559D01*
Y-793898D01*
G01X-1004613Y-802559D02*
X-1005479Y-802415D01*
X-1006237Y-801837D01*
X-1006887Y-800971D01*
X-1007320Y-799961D01*
X-1007536Y-798806D01*
Y-797651D01*
X-1007320Y-796496D01*
X-1006887Y-795486D01*
X-1006237Y-794620D01*
X-1005479Y-794042D01*
X-1004613Y-793898D01*
X-1003747Y-794042D01*
X-1002989Y-794620D01*
X-1002339Y-795486D01*
X-1001906Y-796496D01*
X-1001690Y-797651D01*
Y-798806D01*
X-1001906Y-799961D01*
X-1002339Y-800971D01*
X-1002989Y-801837D01*
X-1003747Y-802415D01*
X-1004613Y-802559D01*
G01X-987291Y-793898D02*
Y-802559D01*
G01X-989781Y-793898D02*
X-984801D01*
G01X-980795Y-802559D02*
Y-793898D01*
X-978089D01*
X-977223Y-794331D01*
X-976681Y-794908D01*
X-976465Y-796063D01*
X-976681Y-797218D01*
X-977331Y-797940D01*
X-978089Y-798373D01*
X-980795D01*
G01X-978089D02*
X-976465Y-802559D01*
G01X-972676D02*
X-969969Y-793898D01*
X-967262Y-802559D01*
G01X-968237Y-799528D02*
X-971701D01*
G01X-958926Y-794620D02*
X-959576Y-794187D01*
X-960334Y-793898D01*
X-961200D01*
X-962174Y-794331D01*
X-962932Y-795053D01*
X-963473Y-795919D01*
X-963907Y-797362D01*
X-964015Y-798662D01*
X-963798Y-799961D01*
X-963473Y-800827D01*
X-962824Y-801693D01*
X-962066Y-802270D01*
X-961308Y-802559D01*
X-960550D01*
X-959792Y-802270D01*
X-959143Y-801837D01*
X-958601Y-801260D01*
G01X-950482Y-802559D02*
X-954812D01*
Y-793898D01*
X-950482D01*
G01X-952214Y-798084D02*
X-954812D01*
G01X-938032Y-802559D02*
X-935325Y-793898D01*
X-932618Y-802559D01*
G01X-933593Y-799528D02*
X-937057D01*
G01X-926664Y-793898D02*
Y-802559D01*
G01X-929154Y-793898D02*
X-924174D01*
G01X-912049Y-802559D02*
X-909342Y-793898D01*
X-906635Y-802559D01*
G01X-907610Y-799528D02*
X-911074D01*
G01X-902846Y-793898D02*
Y-802559D01*
X-898516D01*
G01X-894185Y-793898D02*
Y-802559D01*
X-889855D01*
G01X-876863Y-793898D02*
Y-802559D01*
X-872533D01*
G01X-868744D02*
X-866037Y-793898D01*
X-863330Y-802559D01*
G01X-864305Y-799528D02*
X-867769D01*
G01X-857376Y-802559D02*
Y-798662D01*
X-859541Y-793898D01*
G01X-855211D02*
X-857376Y-798662D01*
G01X-846550Y-802559D02*
X-850880D01*
Y-793898D01*
X-846550D01*
G01X-848282Y-798084D02*
X-850880D01*
G01X-842219Y-802559D02*
Y-793898D01*
X-839513D01*
X-838647Y-794331D01*
X-838105Y-794908D01*
X-837889Y-796063D01*
X-838105Y-797218D01*
X-838755Y-797940D01*
X-839513Y-798373D01*
X-842219D01*
G01X-839513D02*
X-837889Y-802559D01*
G01X-833667Y-801404D02*
X-832800Y-802126D01*
X-831826Y-802559D01*
X-830960D01*
X-830094Y-802126D01*
X-829444Y-801404D01*
X-829119Y-800394D01*
X-829336Y-799383D01*
X-829877Y-798517D01*
X-830852Y-797940D01*
X-832151Y-797651D01*
X-832909Y-797074D01*
X-833234Y-796063D01*
X-833017Y-795053D01*
X-832476Y-794331D01*
X-831718Y-793898D01*
X-830960D01*
X-830202Y-794187D01*
X-829552Y-794908D01*
G01X-811906Y-802559D02*
X-816236D01*
Y-793898D01*
X-811906D01*
G01X-813638Y-798084D02*
X-816236D01*
G01X-807684Y-802559D02*
X-803136Y-793898D01*
G01X-807684D02*
X-803136Y-802559D01*
G01X-794367Y-794620D02*
X-795017Y-794187D01*
X-795775Y-793898D01*
X-796641D01*
X-797615Y-794331D01*
X-798373Y-795053D01*
X-798914Y-795919D01*
X-799348Y-797362D01*
X-799456Y-798662D01*
X-799239Y-799961D01*
X-798914Y-800827D01*
X-798265Y-801693D01*
X-797507Y-802270D01*
X-796749Y-802559D01*
X-795991D01*
X-795233Y-802270D01*
X-794584Y-801837D01*
X-794042Y-801260D01*
G01X-785923Y-802559D02*
X-790253D01*
Y-793898D01*
X-785923D01*
G01X-787655Y-798084D02*
X-790253D01*
G01X-781592Y-802559D02*
Y-793898D01*
X-778994D01*
X-778128Y-794331D01*
X-777478Y-795341D01*
X-777262Y-796496D01*
X-777478Y-797651D01*
X-778020Y-798517D01*
X-778994Y-798950D01*
X-781592D01*
G01X-770766Y-793898D02*
Y-802559D01*
G01X-773256Y-793898D02*
X-768276D01*
G01X-752794Y-798229D02*
X-750629D01*
Y-800827D01*
X-751279Y-801693D01*
X-752037Y-802270D01*
X-753119Y-802559D01*
X-754202Y-802270D01*
X-754960Y-801693D01*
X-755609Y-800827D01*
X-756043Y-799816D01*
X-756259Y-798662D01*
Y-797651D01*
X-756043Y-796785D01*
X-755609Y-795774D01*
X-754960Y-794908D01*
X-754310Y-794331D01*
X-753444Y-793898D01*
X-752686D01*
X-751820Y-794187D01*
X-751170Y-794764D01*
G01X-747273Y-802559D02*
Y-793898D01*
X-742293Y-802559D01*
Y-793898D01*
G01X-738504Y-802559D02*
Y-793898D01*
X-736339D01*
X-735472Y-794331D01*
X-734823Y-794908D01*
X-734281Y-795774D01*
X-733848Y-796785D01*
X-733740Y-798229D01*
X-733848Y-799672D01*
X-734281Y-800683D01*
X-734823Y-801549D01*
X-735472Y-802126D01*
X-736339Y-802559D01*
X-738504D01*
G01X-726920Y-805446D02*
X-725837Y-804002D01*
X-725296Y-802559D01*
Y-796785D01*
X-725837Y-795341D01*
X-726920Y-793898D01*
G01X-1003085Y-772205D02*
X-1004168Y-770761D01*
X-1004709Y-769318D01*
Y-763544D01*
X-1004168Y-762100D01*
X-1003085Y-760657D01*
G01X-996048Y-769318D02*
Y-760657D01*
X-993450D01*
X-992584Y-761090D01*
X-991934Y-762100D01*
X-991718Y-763255D01*
X-991934Y-764410D01*
X-992476Y-765276D01*
X-993450Y-765709D01*
X-996048D01*
G01X-985222Y-760657D02*
Y-769318D01*
G01X-987712Y-760657D02*
X-982732D01*
G01X-978835Y-769318D02*
Y-760657D01*
G01X-974287D02*
Y-769318D01*
G01Y-764988D02*
X-978835D01*
G01X-967359Y-772205D02*
X-966276Y-770761D01*
X-965735Y-769318D01*
Y-763544D01*
X-966276Y-762100D01*
X-967359Y-760657D01*
G01X-1023219Y-743801D02*
X-1031880D01*
X-1030148Y-745100D01*
G01X-1023219D02*
Y-742502D01*
G01Y-735140D02*
X-1023363Y-734382D01*
X-1023796Y-733516D01*
X-1024518Y-732975D01*
X-1025529Y-732758D01*
X-1026539Y-732975D01*
X-1027405Y-733624D01*
X-1027838Y-734599D01*
Y-735681D01*
X-1028127Y-736331D01*
X-1028849Y-736872D01*
X-1029859Y-737089D01*
X-1030870Y-736764D01*
X-1031591Y-736006D01*
X-1031880Y-735140D01*
X-1031591Y-734274D01*
X-1030870Y-733516D01*
X-1029859Y-733191D01*
X-1028849Y-733408D01*
X-1028127Y-733949D01*
X-1027838Y-734599D01*
Y-735681D01*
X-1027405Y-736656D01*
X-1026539Y-737305D01*
X-1025529Y-737522D01*
X-1024518Y-737305D01*
X-1023796Y-736764D01*
X-1023363Y-735898D01*
X-1023219Y-735140D01*
G01X-1031880Y-726479D02*
X-1031591Y-727345D01*
X-1030870Y-727995D01*
X-1030004Y-728428D01*
X-1028849Y-728753D01*
X-1027549Y-728861D01*
X-1026250Y-728753D01*
X-1025095Y-728428D01*
X-1024229Y-727995D01*
X-1023508Y-727345D01*
X-1023219Y-726479D01*
X-1023508Y-725613D01*
X-1024229Y-724963D01*
X-1025095Y-724530D01*
X-1026250Y-724205D01*
X-1027549Y-724097D01*
X-1028849Y-724205D01*
X-1030004Y-724530D01*
X-1030870Y-724963D01*
X-1031591Y-725613D01*
X-1031880Y-726479D01*
G01X-1022930Y-717818D02*
X-1023075Y-718035D01*
X-1023363D01*
X-1023508Y-717818D01*
X-1023363Y-717601D01*
X-1023075D01*
X-1022930Y-717818D01*
G01X-1031880Y-709157D02*
X-1031591Y-710023D01*
X-1030870Y-710673D01*
X-1030004Y-711106D01*
X-1028849Y-711431D01*
X-1027549Y-711539D01*
X-1026250Y-711431D01*
X-1025095Y-711106D01*
X-1024229Y-710673D01*
X-1023508Y-710023D01*
X-1023219Y-709157D01*
X-1023508Y-708291D01*
X-1024229Y-707641D01*
X-1025095Y-707208D01*
X-1026250Y-706883D01*
X-1027549Y-706775D01*
X-1028849Y-706883D01*
X-1030004Y-707208D01*
X-1030870Y-707641D01*
X-1031591Y-708291D01*
X-1031880Y-709157D01*
G01Y-700496D02*
X-1031591Y-701362D01*
X-1030870Y-702012D01*
X-1030004Y-702445D01*
X-1028849Y-702770D01*
X-1027549Y-702878D01*
X-1026250Y-702770D01*
X-1025095Y-702445D01*
X-1024229Y-702012D01*
X-1023508Y-701362D01*
X-1023219Y-700496D01*
X-1023508Y-699630D01*
X-1024229Y-698980D01*
X-1025095Y-698547D01*
X-1026250Y-698222D01*
X-1027549Y-698114D01*
X-1028849Y-698222D01*
X-1030004Y-698547D01*
X-1030870Y-698980D01*
X-1031591Y-699630D01*
X-1031880Y-700496D01*
G01X-991393Y-769318D02*
Y-763544D01*
G01Y-764988D02*
X-990959Y-764266D01*
X-990310Y-763688D01*
X-989444Y-763544D01*
X-988686Y-763688D01*
X-988036Y-764266D01*
X-987711Y-765276D01*
Y-769318D01*
G01X-1004601Y-762100D02*
X-1003951Y-761235D01*
X-1003194Y-760801D01*
X-1002327Y-760657D01*
X-1001245Y-760946D01*
X-1000487Y-761667D01*
X-1000270Y-762533D01*
X-1000379Y-763400D01*
X-1000812Y-764121D01*
X-1002977Y-765565D01*
X-1003951Y-766575D01*
X-1004601Y-768019D01*
X-1004818Y-769318D01*
X-1000270D01*
G01X-993883Y-769607D02*
X-994100Y-769462D01*
Y-769174D01*
X-993883Y-769029D01*
X-993666Y-769174D01*
Y-769462D01*
X-993883Y-769607D01*
G01X-987279Y-762100D02*
X-986629Y-761235D01*
X-985872Y-760801D01*
X-985005Y-760657D01*
X-983923Y-760946D01*
X-983165Y-761667D01*
X-982948Y-762533D01*
X-983057Y-763400D01*
X-983490Y-764121D01*
X-985655Y-765565D01*
X-986629Y-766575D01*
X-987279Y-768019D01*
X-987496Y-769318D01*
X-982948D01*
G01X-976561Y-760657D02*
X-977427Y-760946D01*
X-978077Y-761667D01*
X-978510Y-762533D01*
X-978835Y-763688D01*
X-978943Y-764988D01*
X-978835Y-766287D01*
X-978510Y-767442D01*
X-978077Y-768308D01*
X-977427Y-769029D01*
X-976561Y-769318D01*
X-975695Y-769029D01*
X-975045Y-768308D01*
X-974612Y-767442D01*
X-974287Y-766287D01*
X-974179Y-764988D01*
X-974287Y-763688D01*
X-974612Y-762533D01*
X-975045Y-761667D01*
X-975695Y-760946D01*
X-976561Y-760657D01*
G01X-1009714Y608295D02*
X-1018375D01*
X-1016643Y606996D01*
G01X-1009714D02*
Y609594D01*
G01X-1013323Y614899D02*
X-1014333Y615657D01*
X-1014911Y616306D01*
X-1015199Y617173D01*
X-1014911Y617930D01*
X-1014333Y618472D01*
X-1013467Y618905D01*
X-1012457Y619013D01*
X-1011590Y618905D01*
X-1010724Y618472D01*
X-1010003Y617822D01*
X-1009714Y617064D01*
X-1010003Y616198D01*
X-1010869Y615440D01*
X-1012168Y615007D01*
X-1013611Y614899D01*
X-1015488Y615115D01*
X-1016499Y615440D01*
X-1017509Y615982D01*
X-1018231Y616739D01*
X-1018375Y617497D01*
X-1018086Y618255D01*
X-1017365Y618797D01*
G01X-1011013Y623235D02*
X-1010291Y623885D01*
X-1009858Y624643D01*
X-1009714Y625617D01*
X-1010003Y626591D01*
X-1010580Y627349D01*
X-1011590Y627891D01*
X-1012745Y627999D01*
X-1013900Y627782D01*
X-1014622Y627241D01*
X-1015199Y626483D01*
X-1015344Y625725D01*
X-1015199Y624967D01*
X-1014622Y623993D01*
X-1018375Y624318D01*
Y627241D01*
G01X-1009425Y634278D02*
X-1009570Y634061D01*
X-1009858D01*
X-1010003Y634278D01*
X-1009858Y634495D01*
X-1009570D01*
X-1009425Y634278D01*
G01X-1009714Y642939D02*
X-1009858Y643697D01*
X-1010291Y644563D01*
X-1011013Y645104D01*
X-1012024Y645321D01*
X-1013034Y645104D01*
X-1013900Y644455D01*
X-1014333Y643480D01*
Y642398D01*
X-1014622Y641748D01*
X-1015344Y641207D01*
X-1016354Y640990D01*
X-1017365Y641315D01*
X-1018086Y642073D01*
X-1018375Y642939D01*
X-1018086Y643805D01*
X-1017365Y644563D01*
X-1016354Y644888D01*
X-1015344Y644671D01*
X-1014622Y644130D01*
X-1014333Y643480D01*
Y642398D01*
X-1013900Y641423D01*
X-1013034Y640774D01*
X-1012024Y640557D01*
X-1011013Y640774D01*
X-1010291Y641315D01*
X-1009858Y642181D01*
X-1009714Y642939D01*
G01X-1018375Y651600D02*
X-1018086Y650734D01*
X-1017365Y650084D01*
X-1016499Y649651D01*
X-1015344Y649326D01*
X-1014044Y649218D01*
X-1012745Y649326D01*
X-1011590Y649651D01*
X-1010724Y650084D01*
X-1010003Y650734D01*
X-1009714Y651600D01*
X-1010003Y652466D01*
X-1010724Y653116D01*
X-1011590Y653549D01*
X-1012745Y653874D01*
X-1014044Y653982D01*
X-1015344Y653874D01*
X-1016499Y653549D01*
X-1017365Y653116D01*
X-1018086Y652466D01*
X-1018375Y651600D01*
G01X-994328Y809921D02*
Y818582D01*
X-995627Y816850D01*
G01Y809921D02*
X-993029D01*
G01X-985667D02*
Y818582D01*
X-986966Y816850D01*
G01Y809921D02*
X-984368D01*
G01X-977006Y818582D02*
X-977872Y818293D01*
X-978522Y817572D01*
X-978955Y816706D01*
X-979280Y815551D01*
X-979388Y814251D01*
X-979280Y812952D01*
X-978955Y811797D01*
X-978522Y810931D01*
X-977872Y810210D01*
X-977006Y809921D01*
X-976140Y810210D01*
X-975490Y810931D01*
X-975057Y811797D01*
X-974732Y812952D01*
X-974624Y814251D01*
X-974732Y815551D01*
X-975057Y816706D01*
X-975490Y817572D01*
X-976140Y818293D01*
X-977006Y818582D01*
G01X-968345Y809632D02*
X-968562Y809777D01*
Y810065D01*
X-968345Y810210D01*
X-968128Y810065D01*
Y809777D01*
X-968345Y809632D01*
G01X-959684Y818582D02*
X-960550Y818293D01*
X-961200Y817572D01*
X-961633Y816706D01*
X-961958Y815551D01*
X-962066Y814251D01*
X-961958Y812952D01*
X-961633Y811797D01*
X-961200Y810931D01*
X-960550Y810210D01*
X-959684Y809921D01*
X-958818Y810210D01*
X-958168Y810931D01*
X-957735Y811797D01*
X-957410Y812952D01*
X-957302Y814251D01*
X-957410Y815551D01*
X-957735Y816706D01*
X-958168Y817572D01*
X-958818Y818293D01*
X-959684Y818582D01*
G01X-951023D02*
X-951889Y818293D01*
X-952539Y817572D01*
X-952972Y816706D01*
X-953297Y815551D01*
X-953405Y814251D01*
X-953297Y812952D01*
X-952972Y811797D01*
X-952539Y810931D01*
X-951889Y810210D01*
X-951023Y809921D01*
X-950157Y810210D01*
X-949507Y810931D01*
X-949074Y811797D01*
X-948749Y812952D01*
X-948641Y814251D01*
X-948749Y815551D01*
X-949074Y816706D01*
X-949507Y817572D01*
X-950157Y818293D01*
X-951023Y818582D01*
G01X-944068Y520257D02*
Y526031D01*
G01Y524587D02*
X-943634Y525309D01*
X-942985Y525887D01*
X-942119Y526031D01*
X-941361Y525887D01*
X-940711Y525309D01*
X-940386Y524299D01*
Y520257D01*
G01X-957601Y521989D02*
X-956951Y520979D01*
X-956085Y520401D01*
X-955111Y520257D01*
X-954245Y520401D01*
X-953378Y521123D01*
X-952837Y521989D01*
X-952729Y522855D01*
X-952945Y523866D01*
X-953703Y524587D01*
X-954461Y524876D01*
X-955436D01*
G01X-954461D02*
X-953812Y525309D01*
X-953270Y526031D01*
X-953054Y526897D01*
X-953270Y527763D01*
X-953812Y528485D01*
X-954786Y528918D01*
X-955760Y528774D01*
X-956735Y528196D01*
G01X-946558Y519968D02*
X-946775Y520113D01*
Y520401D01*
X-946558Y520546D01*
X-946341Y520401D01*
Y520113D01*
X-946558Y519968D01*
G01X-937897Y528918D02*
X-938763Y528629D01*
X-939413Y527908D01*
X-939846Y527042D01*
X-940171Y525887D01*
X-940279Y524587D01*
X-940171Y523288D01*
X-939846Y522133D01*
X-939413Y521267D01*
X-938763Y520546D01*
X-937897Y520257D01*
X-937031Y520546D01*
X-936381Y521267D01*
X-935948Y522133D01*
X-935623Y523288D01*
X-935515Y524587D01*
X-935623Y525887D01*
X-935948Y527042D01*
X-936381Y527908D01*
X-937031Y528629D01*
X-937897Y528918D01*
G01X-929236D02*
X-930102Y528629D01*
X-930752Y527908D01*
X-931185Y527042D01*
X-931510Y525887D01*
X-931618Y524587D01*
X-931510Y523288D01*
X-931185Y522133D01*
X-930752Y521267D01*
X-930102Y520546D01*
X-929236Y520257D01*
X-928370Y520546D01*
X-927720Y521267D01*
X-927287Y522133D01*
X-926962Y523288D01*
X-926854Y524587D01*
X-926962Y525887D01*
X-927287Y527042D01*
X-927720Y527908D01*
X-928370Y528629D01*
X-929236Y528918D01*
G01X-964421Y517370D02*
X-965504Y518814D01*
X-966045Y520257D01*
Y526031D01*
X-965504Y527475D01*
X-964421Y528918D01*
G01X-957709Y520257D02*
Y528918D01*
X-952729Y520257D01*
Y528918D01*
G01X-948723Y520257D02*
Y528918D01*
X-946125D01*
X-945259Y528485D01*
X-944609Y527475D01*
X-944393Y526320D01*
X-944609Y525165D01*
X-945151Y524299D01*
X-946125Y523866D01*
X-948723D01*
G01X-937897Y528918D02*
Y520257D01*
G01X-940387Y528918D02*
X-935407D01*
G01X-931510Y520257D02*
Y528918D01*
G01X-926962D02*
Y520257D01*
G01Y524587D02*
X-931510D01*
G01X-920034Y517370D02*
X-918951Y518814D01*
X-918410Y520257D01*
Y526031D01*
X-918951Y527475D01*
X-920034Y528918D01*
G01X-958118Y538012D02*
X-959201Y539456D01*
X-959742Y540899D01*
Y546673D01*
X-959201Y548117D01*
X-958118Y549560D01*
G01X-951406Y540899D02*
Y549560D01*
X-946426Y540899D01*
Y549560D01*
G01X-940255Y540899D02*
X-941121Y541043D01*
X-941879Y541621D01*
X-942529Y542487D01*
X-942962Y543497D01*
X-943178Y544652D01*
Y545807D01*
X-942962Y546962D01*
X-942529Y547972D01*
X-941879Y548838D01*
X-941121Y549416D01*
X-940255Y549560D01*
X-939389Y549416D01*
X-938631Y548838D01*
X-937981Y547972D01*
X-937548Y546962D01*
X-937332Y545807D01*
Y544652D01*
X-937548Y543497D01*
X-937981Y542487D01*
X-938631Y541621D01*
X-939389Y541043D01*
X-940255Y540899D01*
G01X-922933Y549560D02*
Y540899D01*
G01X-925423Y549560D02*
X-920443D01*
G01X-916437Y540899D02*
Y549560D01*
X-913731D01*
X-912865Y549127D01*
X-912323Y548550D01*
X-912107Y547395D01*
X-912323Y546240D01*
X-912973Y545518D01*
X-913731Y545085D01*
X-916437D01*
G01X-913731D02*
X-912107Y540899D01*
G01X-908318D02*
X-905611Y549560D01*
X-902904Y540899D01*
G01X-903879Y543930D02*
X-907343D01*
G01X-894568Y548838D02*
X-895218Y549271D01*
X-895976Y549560D01*
X-896842D01*
X-897816Y549127D01*
X-898574Y548405D01*
X-899115Y547539D01*
X-899549Y546096D01*
X-899657Y544796D01*
X-899440Y543497D01*
X-899115Y542631D01*
X-898466Y541765D01*
X-897708Y541188D01*
X-896950Y540899D01*
X-896192D01*
X-895434Y541188D01*
X-894785Y541621D01*
X-894243Y542198D01*
G01X-886124Y540899D02*
X-890454D01*
Y549560D01*
X-886124D01*
G01X-887856Y545374D02*
X-890454D01*
G01X-873674Y540899D02*
X-870967Y549560D01*
X-868260Y540899D01*
G01X-869235Y543930D02*
X-872699D01*
G01X-862306Y549560D02*
Y540899D01*
G01X-864796Y549560D02*
X-859816D01*
G01X-847691Y540899D02*
X-844984Y549560D01*
X-842277Y540899D01*
G01X-843252Y543930D02*
X-846716D01*
G01X-838488Y549560D02*
Y540899D01*
X-834158D01*
G01X-829827Y549560D02*
Y540899D01*
X-825497D01*
G01X-812505Y549560D02*
Y540899D01*
X-808175D01*
G01X-804386D02*
X-801679Y549560D01*
X-798972Y540899D01*
G01X-799947Y543930D02*
X-803411D01*
G01X-793018Y540899D02*
Y544796D01*
X-795183Y549560D01*
G01X-790853D02*
X-793018Y544796D01*
G01X-782192Y540899D02*
X-786522D01*
Y549560D01*
X-782192D01*
G01X-783924Y545374D02*
X-786522D01*
G01X-777861Y540899D02*
Y549560D01*
X-775155D01*
X-774289Y549127D01*
X-773747Y548550D01*
X-773531Y547395D01*
X-773747Y546240D01*
X-774397Y545518D01*
X-775155Y545085D01*
X-777861D01*
G01X-775155D02*
X-773531Y540899D01*
G01X-769309Y542054D02*
X-768442Y541332D01*
X-767468Y540899D01*
X-766602D01*
X-765736Y541332D01*
X-765086Y542054D01*
X-764761Y543064D01*
X-764978Y544075D01*
X-765519Y544941D01*
X-766494Y545518D01*
X-767793Y545807D01*
X-768551Y546384D01*
X-768876Y547395D01*
X-768659Y548405D01*
X-768118Y549127D01*
X-767360Y549560D01*
X-766602D01*
X-765844Y549271D01*
X-765194Y548550D01*
G01X-757833Y538012D02*
X-756750Y539456D01*
X-756209Y540899D01*
Y546673D01*
X-756750Y548117D01*
X-757833Y549560D01*
G01X-894402Y-801260D02*
X-893752Y-801982D01*
X-892994Y-802415D01*
X-892020Y-802559D01*
X-891046Y-802270D01*
X-890288Y-801693D01*
X-889746Y-800683D01*
X-889638Y-799528D01*
X-889855Y-798373D01*
X-890396Y-797651D01*
X-891154Y-797074D01*
X-891912Y-796929D01*
X-892670Y-797074D01*
X-893644Y-797651D01*
X-893319Y-793898D01*
X-890396D01*
G01X-883359Y-802848D02*
X-883576Y-802703D01*
Y-802415D01*
X-883359Y-802270D01*
X-883142Y-802415D01*
Y-802703D01*
X-883359Y-802848D01*
G01X-874698Y-793898D02*
X-875564Y-794187D01*
X-876214Y-794908D01*
X-876647Y-795774D01*
X-876972Y-796929D01*
X-877080Y-798229D01*
X-876972Y-799528D01*
X-876647Y-800683D01*
X-876214Y-801549D01*
X-875564Y-802270D01*
X-874698Y-802559D01*
X-873832Y-802270D01*
X-873182Y-801549D01*
X-872749Y-800683D01*
X-872424Y-799528D01*
X-872316Y-798229D01*
X-872424Y-796929D01*
X-872749Y-795774D01*
X-873182Y-794908D01*
X-873832Y-794187D01*
X-874698Y-793898D01*
G01X-866037D02*
X-866903Y-794187D01*
X-867553Y-794908D01*
X-867986Y-795774D01*
X-868311Y-796929D01*
X-868419Y-798229D01*
X-868311Y-799528D01*
X-867986Y-800683D01*
X-867553Y-801549D01*
X-866903Y-802270D01*
X-866037Y-802559D01*
X-865171Y-802270D01*
X-864521Y-801549D01*
X-864088Y-800683D01*
X-863763Y-799528D01*
X-863655Y-798229D01*
X-863763Y-796929D01*
X-864088Y-795774D01*
X-864521Y-794908D01*
X-865171Y-794187D01*
X-866037Y-793898D01*
G01X-880869Y-802559D02*
Y-796785D01*
G01Y-798229D02*
X-880435Y-797507D01*
X-879786Y-796929D01*
X-878920Y-796785D01*
X-878162Y-796929D01*
X-877512Y-797507D01*
X-877187Y-798517D01*
Y-802559D01*
G01X-864868Y-734523D02*
X-865951Y-733079D01*
X-866492Y-731636D01*
Y-725862D01*
X-865951Y-724418D01*
X-864868Y-722975D01*
G01X-858156Y-731636D02*
Y-722975D01*
X-853176Y-731636D01*
Y-722975D01*
G01X-847005Y-731636D02*
X-847871Y-731492D01*
X-848629Y-730914D01*
X-849279Y-730048D01*
X-849712Y-729038D01*
X-849928Y-727883D01*
Y-726728D01*
X-849712Y-725573D01*
X-849279Y-724563D01*
X-848629Y-723697D01*
X-847871Y-723119D01*
X-847005Y-722975D01*
X-846139Y-723119D01*
X-845381Y-723697D01*
X-844731Y-724563D01*
X-844298Y-725573D01*
X-844082Y-726728D01*
Y-727883D01*
X-844298Y-729038D01*
X-844731Y-730048D01*
X-845381Y-730914D01*
X-846139Y-731492D01*
X-847005Y-731636D01*
G01X-829683Y-722975D02*
Y-731636D01*
G01X-832173Y-722975D02*
X-827193D01*
G01X-823187Y-731636D02*
Y-722975D01*
X-820481D01*
X-819615Y-723408D01*
X-819073Y-723985D01*
X-818857Y-725140D01*
X-819073Y-726295D01*
X-819723Y-727017D01*
X-820481Y-727450D01*
X-823187D01*
G01X-820481D02*
X-818857Y-731636D01*
G01X-815068D02*
X-812361Y-722975D01*
X-809654Y-731636D01*
G01X-810629Y-728605D02*
X-814093D01*
G01X-801318Y-723697D02*
X-801968Y-723264D01*
X-802726Y-722975D01*
X-803592D01*
X-804566Y-723408D01*
X-805324Y-724130D01*
X-805865Y-724996D01*
X-806299Y-726439D01*
X-806407Y-727739D01*
X-806190Y-729038D01*
X-805865Y-729904D01*
X-805216Y-730770D01*
X-804458Y-731347D01*
X-803700Y-731636D01*
X-802942D01*
X-802184Y-731347D01*
X-801535Y-730914D01*
X-800993Y-730337D01*
G01X-792874Y-731636D02*
X-797204D01*
Y-722975D01*
X-792874D01*
G01X-794606Y-727161D02*
X-797204D01*
G01X-780424Y-731636D02*
X-777717Y-722975D01*
X-775010Y-731636D01*
G01X-775985Y-728605D02*
X-779449D01*
G01X-769056Y-722975D02*
Y-731636D01*
G01X-771546Y-722975D02*
X-766566D01*
G01X-754441Y-731636D02*
X-751734Y-722975D01*
X-749027Y-731636D01*
G01X-750002Y-728605D02*
X-753466D01*
G01X-745238Y-722975D02*
Y-731636D01*
X-740908D01*
G01X-736577Y-722975D02*
Y-731636D01*
X-732247D01*
G01X-719255Y-722975D02*
Y-731636D01*
X-714925D01*
G01X-711136D02*
X-708429Y-722975D01*
X-705722Y-731636D01*
G01X-706697Y-728605D02*
X-710161D01*
G01X-699768Y-731636D02*
Y-727739D01*
X-701933Y-722975D01*
G01X-697603D02*
X-699768Y-727739D01*
G01X-688942Y-731636D02*
X-693272D01*
Y-722975D01*
X-688942D01*
G01X-690674Y-727161D02*
X-693272D01*
G01X-684611Y-731636D02*
Y-722975D01*
X-681905D01*
X-681039Y-723408D01*
X-680497Y-723985D01*
X-680281Y-725140D01*
X-680497Y-726295D01*
X-681147Y-727017D01*
X-681905Y-727450D01*
X-684611D01*
G01X-681905D02*
X-680281Y-731636D01*
G01X-676059Y-730481D02*
X-675192Y-731203D01*
X-674218Y-731636D01*
X-673352D01*
X-672486Y-731203D01*
X-671836Y-730481D01*
X-671511Y-729471D01*
X-671728Y-728460D01*
X-672269Y-727594D01*
X-673244Y-727017D01*
X-674543Y-726728D01*
X-675301Y-726151D01*
X-675626Y-725140D01*
X-675409Y-724130D01*
X-674868Y-723408D01*
X-674110Y-722975D01*
X-673352D01*
X-672594Y-723264D01*
X-671944Y-723985D01*
G01X-654298Y-731636D02*
X-658628D01*
Y-722975D01*
X-654298D01*
G01X-656030Y-727161D02*
X-658628D01*
G01X-650076Y-731636D02*
X-645528Y-722975D01*
G01X-650076D02*
X-645528Y-731636D01*
G01X-636759Y-723697D02*
X-637409Y-723264D01*
X-638167Y-722975D01*
X-639033D01*
X-640007Y-723408D01*
X-640765Y-724130D01*
X-641306Y-724996D01*
X-641740Y-726439D01*
X-641848Y-727739D01*
X-641631Y-729038D01*
X-641306Y-729904D01*
X-640657Y-730770D01*
X-639899Y-731347D01*
X-639141Y-731636D01*
X-638383D01*
X-637625Y-731347D01*
X-636976Y-730914D01*
X-636434Y-730337D01*
G01X-628315Y-731636D02*
X-632645D01*
Y-722975D01*
X-628315D01*
G01X-630047Y-727161D02*
X-632645D01*
G01X-623984Y-731636D02*
Y-722975D01*
X-621386D01*
X-620520Y-723408D01*
X-619870Y-724418D01*
X-619654Y-725573D01*
X-619870Y-726728D01*
X-620412Y-727594D01*
X-621386Y-728027D01*
X-623984D01*
G01X-613158Y-722975D02*
Y-731636D01*
G01X-615648Y-722975D02*
X-610668D01*
G01X-595186Y-727306D02*
X-593021D01*
Y-729904D01*
X-593671Y-730770D01*
X-594429Y-731347D01*
X-595511Y-731636D01*
X-596594Y-731347D01*
X-597352Y-730770D01*
X-598001Y-729904D01*
X-598435Y-728893D01*
X-598651Y-727739D01*
Y-726728D01*
X-598435Y-725862D01*
X-598001Y-724851D01*
X-597352Y-723985D01*
X-596702Y-723408D01*
X-595836Y-722975D01*
X-595078D01*
X-594212Y-723264D01*
X-593562Y-723841D01*
G01X-589665Y-731636D02*
Y-722975D01*
X-584685Y-731636D01*
Y-722975D01*
G01X-580896Y-731636D02*
Y-722975D01*
X-578731D01*
X-577864Y-723408D01*
X-577215Y-723985D01*
X-576673Y-724851D01*
X-576240Y-725862D01*
X-576132Y-727306D01*
X-576240Y-728749D01*
X-576673Y-729760D01*
X-577215Y-730626D01*
X-577864Y-731203D01*
X-578731Y-731636D01*
X-580896D01*
G01X-569312Y-734523D02*
X-568229Y-733079D01*
X-567688Y-731636D01*
Y-725862D01*
X-568229Y-724418D01*
X-569312Y-722975D01*
G01X-844837Y-685048D02*
X-844187Y-684183D01*
X-843430Y-683749D01*
X-842563Y-683605D01*
X-841481Y-683894D01*
X-840723Y-684615D01*
X-840506Y-685481D01*
X-840615Y-686348D01*
X-841048Y-687069D01*
X-843213Y-688513D01*
X-844187Y-689523D01*
X-844837Y-690967D01*
X-845054Y-692266D01*
X-840506D01*
G01X-834119Y-692555D02*
X-834336Y-692410D01*
Y-692122D01*
X-834119Y-691977D01*
X-833902Y-692122D01*
Y-692410D01*
X-834119Y-692555D01*
G01X-827515Y-685048D02*
X-826865Y-684183D01*
X-826108Y-683749D01*
X-825241Y-683605D01*
X-824159Y-683894D01*
X-823401Y-684615D01*
X-823184Y-685481D01*
X-823293Y-686348D01*
X-823726Y-687069D01*
X-825891Y-688513D01*
X-826865Y-689523D01*
X-827515Y-690967D01*
X-827732Y-692266D01*
X-823184D01*
G01X-816797Y-683605D02*
X-817663Y-683894D01*
X-818313Y-684615D01*
X-818746Y-685481D01*
X-819071Y-686636D01*
X-819179Y-687936D01*
X-819071Y-689235D01*
X-818746Y-690390D01*
X-818313Y-691256D01*
X-817663Y-691977D01*
X-816797Y-692266D01*
X-815931Y-691977D01*
X-815281Y-691256D01*
X-814848Y-690390D01*
X-814523Y-689235D01*
X-814415Y-687936D01*
X-814523Y-686636D01*
X-814848Y-685481D01*
X-815281Y-684615D01*
X-815931Y-683894D01*
X-816797Y-683605D01*
G01X-843321Y-695153D02*
X-844404Y-693709D01*
X-844945Y-692266D01*
Y-686492D01*
X-844404Y-685048D01*
X-843321Y-683605D01*
G01X-836284Y-692266D02*
Y-683605D01*
X-833686D01*
X-832820Y-684038D01*
X-832170Y-685048D01*
X-831954Y-686203D01*
X-832170Y-687358D01*
X-832712Y-688224D01*
X-833686Y-688657D01*
X-836284D01*
G01X-825458Y-683605D02*
Y-692266D01*
G01X-827948Y-683605D02*
X-822968D01*
G01X-819071Y-692266D02*
Y-683605D01*
G01X-814523D02*
Y-692266D01*
G01Y-687936D02*
X-819071D01*
G01X-807595Y-695153D02*
X-806512Y-693709D01*
X-805971Y-692266D01*
Y-686492D01*
X-806512Y-685048D01*
X-807595Y-683605D01*
G01X-859816Y540899D02*
Y546673D01*
G01Y545229D02*
X-859382Y545951D01*
X-858733Y546529D01*
X-857867Y546673D01*
X-857109Y546529D01*
X-856459Y545951D01*
X-856134Y544941D01*
Y540899D01*
G01X-873024Y544508D02*
X-872266Y545518D01*
X-871617Y546096D01*
X-870750Y546384D01*
X-869993Y546096D01*
X-869451Y545518D01*
X-869018Y544652D01*
X-868910Y543642D01*
X-869018Y542775D01*
X-869451Y541909D01*
X-870101Y541188D01*
X-870859Y540899D01*
X-871725Y541188D01*
X-872483Y542054D01*
X-872916Y543353D01*
X-873024Y544796D01*
X-872808Y546673D01*
X-872483Y547684D01*
X-871941Y548694D01*
X-871184Y549416D01*
X-870426Y549560D01*
X-869668Y549271D01*
X-869126Y548550D01*
G01X-862306Y540610D02*
X-862523Y540755D01*
Y541043D01*
X-862306Y541188D01*
X-862089Y541043D01*
Y540755D01*
X-862306Y540610D01*
G01X-853645Y549560D02*
X-854511Y549271D01*
X-855161Y548550D01*
X-855594Y547684D01*
X-855919Y546529D01*
X-856027Y545229D01*
X-855919Y543930D01*
X-855594Y542775D01*
X-855161Y541909D01*
X-854511Y541188D01*
X-853645Y540899D01*
X-852779Y541188D01*
X-852129Y541909D01*
X-851696Y542775D01*
X-851371Y543930D01*
X-851263Y545229D01*
X-851371Y546529D01*
X-851696Y547684D01*
X-852129Y548550D01*
X-852779Y549271D01*
X-853645Y549560D01*
G01X-844984D02*
X-845850Y549271D01*
X-846500Y548550D01*
X-846933Y547684D01*
X-847258Y546529D01*
X-847366Y545229D01*
X-847258Y543930D01*
X-846933Y542775D01*
X-846500Y541909D01*
X-845850Y541188D01*
X-844984Y540899D01*
X-844118Y541188D01*
X-843468Y541909D01*
X-843035Y542775D01*
X-842710Y543930D01*
X-842602Y545229D01*
X-842710Y546529D01*
X-843035Y547684D01*
X-843468Y548550D01*
X-844118Y549271D01*
X-844984Y549560D01*
G01X-832420Y-848112D02*
X-831425Y-846786D01*
X-830573Y-846029D01*
X-829437Y-845650D01*
X-828443Y-846029D01*
X-827733Y-846786D01*
X-827164Y-847922D01*
X-827022Y-849248D01*
X-827164Y-850384D01*
X-827733Y-851521D01*
X-828585Y-852467D01*
X-829579Y-852846D01*
X-830715Y-852467D01*
X-831709Y-851331D01*
X-832278Y-849627D01*
X-832420Y-847733D01*
X-832136Y-845272D01*
X-831709Y-843946D01*
X-830999Y-842620D01*
X-830005Y-841673D01*
X-829011Y-841484D01*
X-828017Y-841863D01*
X-827306Y-842810D01*
G01X-831629Y-692266D02*
Y-686492D01*
G01Y-687936D02*
X-831195Y-687214D01*
X-830546Y-686636D01*
X-829680Y-686492D01*
X-828922Y-686636D01*
X-828272Y-687214D01*
X-827947Y-688224D01*
Y-692266D01*
G01X-792893Y186737D02*
X-793976Y188181D01*
X-794517Y189624D01*
Y195398D01*
X-793976Y196842D01*
X-792893Y198285D01*
G01X-785856Y189624D02*
Y198285D01*
X-783258D01*
X-782392Y197852D01*
X-781742Y196842D01*
X-781526Y195687D01*
X-781742Y194532D01*
X-782284Y193666D01*
X-783258Y193233D01*
X-785856D01*
G01X-777737Y189624D02*
X-775030Y198285D01*
X-772323Y189624D01*
G01X-773298Y192655D02*
X-776762D01*
G01X-768751Y189624D02*
Y198285D01*
X-766586D01*
X-765719Y197852D01*
X-765070Y197275D01*
X-764528Y196409D01*
X-764095Y195398D01*
X-763987Y193954D01*
X-764095Y192511D01*
X-764528Y191500D01*
X-765070Y190634D01*
X-765719Y190057D01*
X-766586Y189624D01*
X-768751D01*
G01X-757167Y186737D02*
X-756084Y188181D01*
X-755543Y189624D01*
Y195398D01*
X-756084Y196842D01*
X-757167Y198285D01*
G01X-749588Y186737D02*
X-750671Y188181D01*
X-751212Y189624D01*
Y195398D01*
X-750671Y196842D01*
X-749588Y198285D01*
G01X-742876Y189624D02*
Y198285D01*
X-737896Y189624D01*
Y198285D01*
G01X-731725Y189624D02*
X-732591Y189768D01*
X-733349Y190346D01*
X-733999Y191212D01*
X-734432Y192222D01*
X-734648Y193377D01*
Y194532D01*
X-734432Y195687D01*
X-733999Y196697D01*
X-733349Y197563D01*
X-732591Y198141D01*
X-731725Y198285D01*
X-730859Y198141D01*
X-730101Y197563D01*
X-729451Y196697D01*
X-729018Y195687D01*
X-728802Y194532D01*
Y193377D01*
X-729018Y192222D01*
X-729451Y191212D01*
X-730101Y190346D01*
X-730859Y189768D01*
X-731725Y189624D01*
G01X-714403Y198285D02*
Y189624D01*
G01X-716893Y198285D02*
X-711913D01*
G01X-707907Y189624D02*
Y198285D01*
X-705201D01*
X-704335Y197852D01*
X-703793Y197275D01*
X-703577Y196120D01*
X-703793Y194965D01*
X-704443Y194243D01*
X-705201Y193810D01*
X-707907D01*
G01X-705201D02*
X-703577Y189624D01*
G01X-699788D02*
X-697081Y198285D01*
X-694374Y189624D01*
G01X-695349Y192655D02*
X-698813D01*
G01X-686038Y197563D02*
X-686688Y197996D01*
X-687446Y198285D01*
X-688312D01*
X-689286Y197852D01*
X-690044Y197130D01*
X-690585Y196264D01*
X-691019Y194821D01*
X-691127Y193521D01*
X-690910Y192222D01*
X-690585Y191356D01*
X-689936Y190490D01*
X-689178Y189913D01*
X-688420Y189624D01*
X-687662D01*
X-686904Y189913D01*
X-686255Y190346D01*
X-685713Y190923D01*
G01X-677594Y189624D02*
X-681924D01*
Y198285D01*
X-677594D01*
G01X-679326Y194099D02*
X-681924D01*
G01X-665144Y189624D02*
X-662437Y198285D01*
X-659730Y189624D01*
G01X-660705Y192655D02*
X-664169D01*
G01X-653776Y198285D02*
Y189624D01*
G01X-656266Y198285D02*
X-651286D01*
G01X-639161Y189624D02*
X-636454Y198285D01*
X-633747Y189624D01*
G01X-634722Y192655D02*
X-638186D01*
G01X-629958Y198285D02*
Y189624D01*
X-625628D01*
G01X-621297Y198285D02*
Y189624D01*
X-616967D01*
G01X-603975Y198285D02*
Y189624D01*
X-599645D01*
G01X-595856D02*
X-593149Y198285D01*
X-590442Y189624D01*
G01X-591417Y192655D02*
X-594881D01*
G01X-584488Y189624D02*
Y193521D01*
X-586653Y198285D01*
G01X-582323D02*
X-584488Y193521D01*
G01X-573662Y189624D02*
X-577992D01*
Y198285D01*
X-573662D01*
G01X-575394Y194099D02*
X-577992D01*
G01X-569331Y189624D02*
Y198285D01*
X-566625D01*
X-565759Y197852D01*
X-565217Y197275D01*
X-565001Y196120D01*
X-565217Y194965D01*
X-565867Y194243D01*
X-566625Y193810D01*
X-569331D01*
G01X-566625D02*
X-565001Y189624D01*
G01X-560779Y190779D02*
X-559912Y190057D01*
X-558938Y189624D01*
X-558072D01*
X-557206Y190057D01*
X-556556Y190779D01*
X-556231Y191789D01*
X-556448Y192800D01*
X-556989Y193666D01*
X-557964Y194243D01*
X-559263Y194532D01*
X-560021Y195109D01*
X-560346Y196120D01*
X-560129Y197130D01*
X-559588Y197852D01*
X-558830Y198285D01*
X-558072D01*
X-557314Y197996D01*
X-556664Y197275D01*
G01X-549303Y186737D02*
X-548220Y188181D01*
X-547679Y189624D01*
Y195398D01*
X-548220Y196842D01*
X-549303Y198285D01*
G01X-793704Y261605D02*
X-794569Y262255D01*
X-795003Y263012D01*
X-795147Y263879D01*
X-794858Y264961D01*
X-794137Y265719D01*
X-793271Y265936D01*
X-792404Y265827D01*
X-791683Y265394D01*
X-790239Y263229D01*
X-789229Y262255D01*
X-787785Y261605D01*
X-786486Y261388D01*
Y265936D01*
G01X-793704Y270266D02*
X-794569Y270916D01*
X-795003Y271673D01*
X-795147Y272540D01*
X-794858Y273622D01*
X-794137Y274380D01*
X-793271Y274597D01*
X-792404Y274488D01*
X-791683Y274055D01*
X-790239Y271890D01*
X-789229Y270916D01*
X-787785Y270266D01*
X-786486Y270049D01*
Y274597D01*
G01X-793704Y278927D02*
X-794569Y279577D01*
X-795003Y280334D01*
X-795147Y281201D01*
X-794858Y282283D01*
X-794137Y283041D01*
X-793271Y283258D01*
X-792404Y283149D01*
X-791683Y282716D01*
X-790239Y280551D01*
X-789229Y279577D01*
X-787785Y278927D01*
X-786486Y278710D01*
Y283258D01*
G01X-786197Y289645D02*
X-786342Y289428D01*
X-786630D01*
X-786775Y289645D01*
X-786630Y289862D01*
X-786342D01*
X-786197Y289645D01*
G01X-787785Y295924D02*
X-787063Y296574D01*
X-786630Y297332D01*
X-786486Y298306D01*
X-786775Y299280D01*
X-787352Y300038D01*
X-788362Y300580D01*
X-789517Y300688D01*
X-790672Y300471D01*
X-791394Y299930D01*
X-791971Y299172D01*
X-792116Y298414D01*
X-791971Y297656D01*
X-791394Y296682D01*
X-795147Y297007D01*
Y299930D01*
G01Y306967D02*
X-794858Y306101D01*
X-794137Y305451D01*
X-793271Y305018D01*
X-792116Y304693D01*
X-790816Y304585D01*
X-789517Y304693D01*
X-788362Y305018D01*
X-787496Y305451D01*
X-786775Y306101D01*
X-786486Y306967D01*
X-786775Y307833D01*
X-787496Y308483D01*
X-788362Y308916D01*
X-789517Y309241D01*
X-790816Y309349D01*
X-792116Y309241D01*
X-793271Y308916D01*
X-794137Y308483D01*
X-794858Y307833D01*
X-795147Y306967D01*
G01X-804334Y610505D02*
X-805199Y611155D01*
X-805633Y611912D01*
X-805777Y612779D01*
X-805488Y613861D01*
X-804767Y614619D01*
X-803901Y614836D01*
X-803034Y614727D01*
X-802313Y614294D01*
X-800869Y612129D01*
X-799859Y611155D01*
X-798415Y610505D01*
X-797116Y610288D01*
Y614836D01*
G01Y621223D02*
X-805777D01*
X-804045Y619924D01*
G01X-797116D02*
Y622522D01*
G01X-798126Y628043D02*
X-797405Y628801D01*
X-797116Y629667D01*
X-797405Y630534D01*
X-798271Y631291D01*
X-799570Y631833D01*
X-800869Y632049D01*
X-802457D01*
X-803756Y631833D01*
X-804911Y631291D01*
X-805488Y630642D01*
X-805777Y629884D01*
X-805488Y629018D01*
X-804911Y628368D01*
X-804045Y627935D01*
X-802890Y627719D01*
X-801880Y627935D01*
X-800869Y628477D01*
X-800292Y629126D01*
X-800147Y629884D01*
X-800436Y630750D01*
X-801158Y631400D01*
X-802457Y632049D01*
G01X-796827Y638545D02*
X-796972Y638328D01*
X-797260D01*
X-797405Y638545D01*
X-797260Y638762D01*
X-796972D01*
X-796827Y638545D01*
G01X-797116Y647206D02*
X-797260Y647964D01*
X-797693Y648830D01*
X-798415Y649371D01*
X-799426Y649588D01*
X-800436Y649371D01*
X-801302Y648722D01*
X-801735Y647747D01*
Y646665D01*
X-802024Y646015D01*
X-802746Y645474D01*
X-803756Y645257D01*
X-804767Y645582D01*
X-805488Y646340D01*
X-805777Y647206D01*
X-805488Y648072D01*
X-804767Y648830D01*
X-803756Y649155D01*
X-802746Y648938D01*
X-802024Y648397D01*
X-801735Y647747D01*
Y646665D01*
X-801302Y645690D01*
X-800436Y645041D01*
X-799426Y644824D01*
X-798415Y645041D01*
X-797693Y645582D01*
X-797260Y646448D01*
X-797116Y647206D01*
G01X-805777Y655867D02*
X-805488Y655001D01*
X-804767Y654351D01*
X-803901Y653918D01*
X-802746Y653593D01*
X-801446Y653485D01*
X-800147Y653593D01*
X-798992Y653918D01*
X-798126Y654351D01*
X-797405Y655001D01*
X-797116Y655867D01*
X-797405Y656733D01*
X-798126Y657383D01*
X-798992Y657816D01*
X-800147Y658141D01*
X-801446Y658249D01*
X-802746Y658141D01*
X-803901Y657816D01*
X-804767Y657383D01*
X-805488Y656733D01*
X-805777Y655867D01*
G01X-793704Y839277D02*
X-794569Y839927D01*
X-795003Y840684D01*
X-795147Y841551D01*
X-794858Y842633D01*
X-794137Y843391D01*
X-793271Y843608D01*
X-792404Y843499D01*
X-791683Y843066D01*
X-790239Y840901D01*
X-789229Y839927D01*
X-787785Y839277D01*
X-786486Y839060D01*
Y843608D01*
G01X-793704Y847938D02*
X-794569Y848588D01*
X-795003Y849345D01*
X-795147Y850212D01*
X-794858Y851294D01*
X-794137Y852052D01*
X-793271Y852269D01*
X-792404Y852160D01*
X-791683Y851727D01*
X-790239Y849562D01*
X-789229Y848588D01*
X-787785Y847938D01*
X-786486Y847721D01*
Y852269D01*
G01X-793704Y856599D02*
X-794569Y857249D01*
X-795003Y858006D01*
X-795147Y858873D01*
X-794858Y859955D01*
X-794137Y860713D01*
X-793271Y860930D01*
X-792404Y860821D01*
X-791683Y860388D01*
X-790239Y858223D01*
X-789229Y857249D01*
X-787785Y856599D01*
X-786486Y856382D01*
Y860930D01*
G01X-786197Y867317D02*
X-786342Y867100D01*
X-786630D01*
X-786775Y867317D01*
X-786630Y867534D01*
X-786342D01*
X-786197Y867317D01*
G01X-787785Y873596D02*
X-787063Y874246D01*
X-786630Y875004D01*
X-786486Y875978D01*
X-786775Y876952D01*
X-787352Y877710D01*
X-788362Y878252D01*
X-789517Y878360D01*
X-790672Y878143D01*
X-791394Y877602D01*
X-791971Y876844D01*
X-792116Y876086D01*
X-791971Y875328D01*
X-791394Y874354D01*
X-795147Y874679D01*
Y877602D01*
G01Y884639D02*
X-794858Y883773D01*
X-794137Y883123D01*
X-793271Y882690D01*
X-792116Y882365D01*
X-790816Y882257D01*
X-789517Y882365D01*
X-788362Y882690D01*
X-787496Y883123D01*
X-786775Y883773D01*
X-786486Y884639D01*
X-786775Y885505D01*
X-787496Y886155D01*
X-788362Y886588D01*
X-789517Y886913D01*
X-790816Y887021D01*
X-792116Y886913D01*
X-793271Y886588D01*
X-794137Y886155D01*
X-794858Y885505D01*
X-795147Y884639D01*
G01X-793704Y1173180D02*
X-794569Y1173830D01*
X-795003Y1174587D01*
X-795147Y1175454D01*
X-794858Y1176536D01*
X-794137Y1177294D01*
X-793271Y1177511D01*
X-792404Y1177402D01*
X-791683Y1176969D01*
X-790239Y1174804D01*
X-789229Y1173830D01*
X-787785Y1173180D01*
X-786486Y1172963D01*
Y1177511D01*
G01X-793704Y1181841D02*
X-794569Y1182491D01*
X-795003Y1183248D01*
X-795147Y1184115D01*
X-794858Y1185197D01*
X-794137Y1185955D01*
X-793271Y1186172D01*
X-792404Y1186063D01*
X-791683Y1185630D01*
X-790239Y1183465D01*
X-789229Y1182491D01*
X-787785Y1181841D01*
X-786486Y1181624D01*
Y1186172D01*
G01X-793704Y1190502D02*
X-794569Y1191152D01*
X-795003Y1191909D01*
X-795147Y1192776D01*
X-794858Y1193858D01*
X-794137Y1194616D01*
X-793271Y1194833D01*
X-792404Y1194724D01*
X-791683Y1194291D01*
X-790239Y1192126D01*
X-789229Y1191152D01*
X-787785Y1190502D01*
X-786486Y1190285D01*
Y1194833D01*
G01X-786197Y1201220D02*
X-786342Y1201003D01*
X-786630D01*
X-786775Y1201220D01*
X-786630Y1201437D01*
X-786342D01*
X-786197Y1201220D01*
G01X-787785Y1207499D02*
X-787063Y1208149D01*
X-786630Y1208907D01*
X-786486Y1209881D01*
X-786775Y1210855D01*
X-787352Y1211613D01*
X-788362Y1212155D01*
X-789517Y1212263D01*
X-790672Y1212046D01*
X-791394Y1211505D01*
X-791971Y1210747D01*
X-792116Y1209989D01*
X-791971Y1209231D01*
X-791394Y1208257D01*
X-795147Y1208582D01*
Y1211505D01*
G01Y1218542D02*
X-794858Y1217676D01*
X-794137Y1217026D01*
X-793271Y1216593D01*
X-792116Y1216268D01*
X-790816Y1216160D01*
X-789517Y1216268D01*
X-788362Y1216593D01*
X-787496Y1217026D01*
X-786775Y1217676D01*
X-786486Y1218542D01*
X-786775Y1219408D01*
X-787496Y1220058D01*
X-788362Y1220491D01*
X-789517Y1220816D01*
X-790816Y1220924D01*
X-792116Y1220816D01*
X-793271Y1220491D01*
X-794137Y1220058D01*
X-794858Y1219408D01*
X-795147Y1218542D01*
G01X-832420Y1329644D02*
X-831425Y1330970D01*
X-830573Y1331727D01*
X-829437Y1332106D01*
X-828443Y1331727D01*
X-827733Y1330970D01*
X-827164Y1329834D01*
X-827022Y1328508D01*
X-827164Y1327372D01*
X-827733Y1326235D01*
X-828585Y1325289D01*
X-829579Y1324910D01*
X-830715Y1325289D01*
X-831709Y1326425D01*
X-832278Y1328129D01*
X-832420Y1330023D01*
X-832136Y1332484D01*
X-831709Y1333810D01*
X-830999Y1335136D01*
X-830005Y1336083D01*
X-829011Y1336272D01*
X-828017Y1335893D01*
X-827306Y1334946D01*
G01X-718931Y-731636D02*
Y-725862D01*
G01Y-727306D02*
X-718497Y-726584D01*
X-717848Y-726006D01*
X-716982Y-725862D01*
X-716224Y-726006D01*
X-715574Y-726584D01*
X-715249Y-727594D01*
Y-731636D01*
G01X-732464Y-730337D02*
X-731814Y-731059D01*
X-731056Y-731492D01*
X-730082Y-731636D01*
X-729108Y-731347D01*
X-728350Y-730770D01*
X-727808Y-729760D01*
X-727700Y-728605D01*
X-727917Y-727450D01*
X-728458Y-726728D01*
X-729216Y-726151D01*
X-729974Y-726006D01*
X-730732Y-726151D01*
X-731706Y-726728D01*
X-731381Y-722975D01*
X-728458D01*
G01X-721421Y-731925D02*
X-721638Y-731780D01*
Y-731492D01*
X-721421Y-731347D01*
X-721204Y-731492D01*
Y-731780D01*
X-721421Y-731925D01*
G01X-712760Y-722975D02*
X-713626Y-723264D01*
X-714276Y-723985D01*
X-714709Y-724851D01*
X-715034Y-726006D01*
X-715142Y-727306D01*
X-715034Y-728605D01*
X-714709Y-729760D01*
X-714276Y-730626D01*
X-713626Y-731347D01*
X-712760Y-731636D01*
X-711894Y-731347D01*
X-711244Y-730626D01*
X-710811Y-729760D01*
X-710486Y-728605D01*
X-710378Y-727306D01*
X-710486Y-726006D01*
X-710811Y-724851D01*
X-711244Y-723985D01*
X-711894Y-723264D01*
X-712760Y-722975D01*
G01X-704099D02*
X-704965Y-723264D01*
X-705615Y-723985D01*
X-706048Y-724851D01*
X-706373Y-726006D01*
X-706481Y-727306D01*
X-706373Y-728605D01*
X-706048Y-729760D01*
X-705615Y-730626D01*
X-704965Y-731347D01*
X-704099Y-731636D01*
X-703233Y-731347D01*
X-702583Y-730626D01*
X-702150Y-729760D01*
X-701825Y-728605D01*
X-701717Y-727306D01*
X-701825Y-726006D01*
X-702150Y-724851D01*
X-702583Y-723985D01*
X-703233Y-723264D01*
X-704099Y-722975D01*
G01X-750856Y-595022D02*
Y-586361D01*
X-752155Y-588093D01*
G01Y-595022D02*
X-749557D01*
G01X-740896D02*
Y-586361D01*
X-744902Y-592568D01*
X-739488D01*
G01X-733534Y-595311D02*
X-733751Y-595166D01*
Y-594878D01*
X-733534Y-594733D01*
X-733317Y-594878D01*
Y-595166D01*
X-733534Y-595311D01*
G01X-725090Y-595022D02*
X-724873Y-593146D01*
X-724548Y-591558D01*
X-724115Y-590114D01*
X-723574Y-588526D01*
X-722708Y-586361D01*
X-727038D01*
G01X-716212D02*
X-717078Y-586650D01*
X-717728Y-587371D01*
X-718161Y-588237D01*
X-718486Y-589392D01*
X-718594Y-590692D01*
X-718486Y-591991D01*
X-718161Y-593146D01*
X-717728Y-594012D01*
X-717078Y-594733D01*
X-716212Y-595022D01*
X-715346Y-594733D01*
X-714696Y-594012D01*
X-714263Y-593146D01*
X-713938Y-591991D01*
X-713830Y-590692D01*
X-713938Y-589392D01*
X-714263Y-588237D01*
X-714696Y-587371D01*
X-715346Y-586650D01*
X-716212Y-586361D01*
G01X-739922Y-587804D02*
X-739272Y-586939D01*
X-738515Y-586505D01*
X-737648Y-586361D01*
X-736566Y-586650D01*
X-735808Y-587371D01*
X-735591Y-588237D01*
X-735700Y-589104D01*
X-736133Y-589825D01*
X-738298Y-591269D01*
X-739272Y-592279D01*
X-739922Y-593723D01*
X-740139Y-595022D01*
X-735591D01*
G01X-730611Y-592135D02*
X-727797D01*
G01X-763971Y-515387D02*
X-765054Y-513943D01*
X-765595Y-512500D01*
Y-506726D01*
X-765054Y-505282D01*
X-763971Y-503839D01*
G01X-756934Y-512500D02*
Y-503839D01*
X-754336D01*
X-753470Y-504272D01*
X-752820Y-505282D01*
X-752604Y-506437D01*
X-752820Y-507592D01*
X-753362Y-508458D01*
X-754336Y-508891D01*
X-756934D01*
G01X-748815Y-512500D02*
X-746108Y-503839D01*
X-743401Y-512500D01*
G01X-744376Y-509469D02*
X-747840D01*
G01X-739829Y-512500D02*
Y-503839D01*
X-737664D01*
X-736797Y-504272D01*
X-736148Y-504849D01*
X-735606Y-505715D01*
X-735173Y-506726D01*
X-735065Y-508170D01*
X-735173Y-509613D01*
X-735606Y-510624D01*
X-736148Y-511490D01*
X-736797Y-512067D01*
X-737664Y-512500D01*
X-739829D01*
G01X-728245Y-515387D02*
X-727162Y-513943D01*
X-726621Y-512500D01*
Y-506726D01*
X-727162Y-505282D01*
X-728245Y-503839D01*
G01X-720666Y-515387D02*
X-721749Y-513943D01*
X-722290Y-512500D01*
Y-506726D01*
X-721749Y-505282D01*
X-720666Y-503839D01*
G01X-713954Y-512500D02*
Y-503839D01*
X-708974Y-512500D01*
Y-503839D01*
G01X-702803Y-512500D02*
X-703669Y-512356D01*
X-704427Y-511778D01*
X-705077Y-510912D01*
X-705510Y-509902D01*
X-705726Y-508747D01*
Y-507592D01*
X-705510Y-506437D01*
X-705077Y-505427D01*
X-704427Y-504561D01*
X-703669Y-503983D01*
X-702803Y-503839D01*
X-701937Y-503983D01*
X-701179Y-504561D01*
X-700529Y-505427D01*
X-700096Y-506437D01*
X-699880Y-507592D01*
Y-508747D01*
X-700096Y-509902D01*
X-700529Y-510912D01*
X-701179Y-511778D01*
X-701937Y-512356D01*
X-702803Y-512500D01*
G01X-685481Y-503839D02*
Y-512500D01*
G01X-687971Y-503839D02*
X-682991D01*
G01X-678985Y-512500D02*
Y-503839D01*
X-676279D01*
X-675413Y-504272D01*
X-674871Y-504849D01*
X-674655Y-506004D01*
X-674871Y-507159D01*
X-675521Y-507881D01*
X-676279Y-508314D01*
X-678985D01*
G01X-676279D02*
X-674655Y-512500D01*
G01X-670866D02*
X-668159Y-503839D01*
X-665452Y-512500D01*
G01X-666427Y-509469D02*
X-669891D01*
G01X-657116Y-504561D02*
X-657766Y-504128D01*
X-658524Y-503839D01*
X-659390D01*
X-660364Y-504272D01*
X-661122Y-504994D01*
X-661663Y-505860D01*
X-662097Y-507303D01*
X-662205Y-508603D01*
X-661988Y-509902D01*
X-661663Y-510768D01*
X-661014Y-511634D01*
X-660256Y-512211D01*
X-659498Y-512500D01*
X-658740D01*
X-657982Y-512211D01*
X-657333Y-511778D01*
X-656791Y-511201D01*
G01X-648672Y-512500D02*
X-653002D01*
Y-503839D01*
X-648672D01*
G01X-650404Y-508025D02*
X-653002D01*
G01X-636222Y-512500D02*
X-633515Y-503839D01*
X-630808Y-512500D01*
G01X-631783Y-509469D02*
X-635247D01*
G01X-624854Y-503839D02*
Y-512500D01*
G01X-627344Y-503839D02*
X-622364D01*
G01X-610239Y-512500D02*
X-607532Y-503839D01*
X-604825Y-512500D01*
G01X-605800Y-509469D02*
X-609264D01*
G01X-601036Y-503839D02*
Y-512500D01*
X-596706D01*
G01X-592375Y-503839D02*
Y-512500D01*
X-588045D01*
G01X-575053Y-503839D02*
Y-512500D01*
X-570723D01*
G01X-566934D02*
X-564227Y-503839D01*
X-561520Y-512500D01*
G01X-562495Y-509469D02*
X-565959D01*
G01X-555566Y-512500D02*
Y-508603D01*
X-557731Y-503839D01*
G01X-553401D02*
X-555566Y-508603D01*
G01X-544740Y-512500D02*
X-549070D01*
Y-503839D01*
X-544740D01*
G01X-546472Y-508025D02*
X-549070D01*
G01X-540409Y-512500D02*
Y-503839D01*
X-537703D01*
X-536837Y-504272D01*
X-536295Y-504849D01*
X-536079Y-506004D01*
X-536295Y-507159D01*
X-536945Y-507881D01*
X-537703Y-508314D01*
X-540409D01*
G01X-537703D02*
X-536079Y-512500D01*
G01X-531857Y-511345D02*
X-530990Y-512067D01*
X-530016Y-512500D01*
X-529150D01*
X-528284Y-512067D01*
X-527634Y-511345D01*
X-527309Y-510335D01*
X-527526Y-509324D01*
X-528067Y-508458D01*
X-529042Y-507881D01*
X-530341Y-507592D01*
X-531099Y-507015D01*
X-531424Y-506004D01*
X-531207Y-504994D01*
X-530666Y-504272D01*
X-529908Y-503839D01*
X-529150D01*
X-528392Y-504128D01*
X-527742Y-504849D01*
G01X-520381Y-515387D02*
X-519298Y-513943D01*
X-518757Y-512500D01*
Y-506726D01*
X-519298Y-505282D01*
X-520381Y-503839D01*
G01X-707188Y312310D02*
X-708271Y313754D01*
X-708812Y315197D01*
Y320971D01*
X-708271Y322415D01*
X-707188Y323858D01*
G01X-700151Y315197D02*
Y323858D01*
X-697553D01*
X-696687Y323425D01*
X-696037Y322415D01*
X-695821Y321260D01*
X-696037Y320105D01*
X-696579Y319239D01*
X-697553Y318806D01*
X-700151D01*
G01X-692032Y315197D02*
X-689325Y323858D01*
X-686618Y315197D01*
G01X-687593Y318228D02*
X-691057D01*
G01X-683046Y315197D02*
Y323858D01*
X-680881D01*
X-680014Y323425D01*
X-679365Y322848D01*
X-678823Y321982D01*
X-678390Y320971D01*
X-678282Y319527D01*
X-678390Y318084D01*
X-678823Y317073D01*
X-679365Y316207D01*
X-680014Y315630D01*
X-680881Y315197D01*
X-683046D01*
G01X-671462Y312310D02*
X-670379Y313754D01*
X-669838Y315197D01*
Y320971D01*
X-670379Y322415D01*
X-671462Y323858D01*
G01X-663883Y312310D02*
X-664966Y313754D01*
X-665507Y315197D01*
Y320971D01*
X-664966Y322415D01*
X-663883Y323858D01*
G01X-657171Y315197D02*
Y323858D01*
X-652191Y315197D01*
Y323858D01*
G01X-646020Y315197D02*
X-646886Y315341D01*
X-647644Y315919D01*
X-648294Y316785D01*
X-648727Y317795D01*
X-648943Y318950D01*
Y320105D01*
X-648727Y321260D01*
X-648294Y322270D01*
X-647644Y323136D01*
X-646886Y323714D01*
X-646020Y323858D01*
X-645154Y323714D01*
X-644396Y323136D01*
X-643746Y322270D01*
X-643313Y321260D01*
X-643097Y320105D01*
Y318950D01*
X-643313Y317795D01*
X-643746Y316785D01*
X-644396Y315919D01*
X-645154Y315341D01*
X-646020Y315197D01*
G01X-628698Y323858D02*
Y315197D01*
G01X-631188Y323858D02*
X-626208D01*
G01X-622202Y315197D02*
Y323858D01*
X-619496D01*
X-618630Y323425D01*
X-618088Y322848D01*
X-617872Y321693D01*
X-618088Y320538D01*
X-618738Y319816D01*
X-619496Y319383D01*
X-622202D01*
G01X-619496D02*
X-617872Y315197D01*
G01X-614083D02*
X-611376Y323858D01*
X-608669Y315197D01*
G01X-609644Y318228D02*
X-613108D01*
G01X-600333Y323136D02*
X-600983Y323569D01*
X-601741Y323858D01*
X-602607D01*
X-603581Y323425D01*
X-604339Y322703D01*
X-604880Y321837D01*
X-605314Y320394D01*
X-605422Y319094D01*
X-605205Y317795D01*
X-604880Y316929D01*
X-604231Y316063D01*
X-603473Y315486D01*
X-602715Y315197D01*
X-601957D01*
X-601199Y315486D01*
X-600550Y315919D01*
X-600008Y316496D01*
G01X-591889Y315197D02*
X-596219D01*
Y323858D01*
X-591889D01*
G01X-593621Y319672D02*
X-596219D01*
G01X-579439Y315197D02*
X-576732Y323858D01*
X-574025Y315197D01*
G01X-575000Y318228D02*
X-578464D01*
G01X-568071Y323858D02*
Y315197D01*
G01X-570561Y323858D02*
X-565581D01*
G01X-553456Y315197D02*
X-550749Y323858D01*
X-548042Y315197D01*
G01X-549017Y318228D02*
X-552481D01*
G01X-544253Y323858D02*
Y315197D01*
X-539923D01*
G01X-535592Y323858D02*
Y315197D01*
X-531262D01*
G01X-518270Y323858D02*
Y315197D01*
X-513940D01*
G01X-510151D02*
X-507444Y323858D01*
X-504737Y315197D01*
G01X-505712Y318228D02*
X-509176D01*
G01X-498783Y315197D02*
Y319094D01*
X-500948Y323858D01*
G01X-496618D02*
X-498783Y319094D01*
G01X-487957Y315197D02*
X-492287D01*
Y323858D01*
X-487957D01*
G01X-489689Y319672D02*
X-492287D01*
G01X-483626Y315197D02*
Y323858D01*
X-480920D01*
X-480054Y323425D01*
X-479512Y322848D01*
X-479296Y321693D01*
X-479512Y320538D01*
X-480162Y319816D01*
X-480920Y319383D01*
X-483626D01*
G01X-480920D02*
X-479296Y315197D01*
G01X-475074Y316352D02*
X-474207Y315630D01*
X-473233Y315197D01*
X-472367D01*
X-471501Y315630D01*
X-470851Y316352D01*
X-470526Y317362D01*
X-470743Y318373D01*
X-471284Y319239D01*
X-472259Y319816D01*
X-473558Y320105D01*
X-474316Y320682D01*
X-474641Y321693D01*
X-474424Y322703D01*
X-473883Y323425D01*
X-473125Y323858D01*
X-472367D01*
X-471609Y323569D01*
X-470959Y322848D01*
G01X-463598Y312310D02*
X-462515Y313754D01*
X-461974Y315197D01*
Y320971D01*
X-462515Y322415D01*
X-463598Y323858D01*
G01X-711633Y1035578D02*
X-710875Y1034857D01*
X-710009Y1034568D01*
X-709142Y1034857D01*
X-708385Y1035723D01*
X-707843Y1037022D01*
X-707627Y1038321D01*
Y1039909D01*
X-707843Y1041208D01*
X-708385Y1042363D01*
X-709034Y1042940D01*
X-709792Y1043229D01*
X-710658Y1042940D01*
X-711308Y1042363D01*
X-711741Y1041497D01*
X-711957Y1040342D01*
X-711741Y1039332D01*
X-711199Y1038321D01*
X-710550Y1037744D01*
X-709792Y1037599D01*
X-708926Y1037888D01*
X-708276Y1038610D01*
X-707627Y1039909D01*
G01X-702538Y1037455D02*
X-699724D01*
G01X-694635Y1034568D02*
Y1043229D01*
X-692037D01*
X-691171Y1042796D01*
X-690521Y1041786D01*
X-690305Y1040631D01*
X-690521Y1039476D01*
X-691063Y1038610D01*
X-692037Y1038177D01*
X-694635D01*
G01X-686516Y1034568D02*
X-683809Y1043229D01*
X-681102Y1034568D01*
G01X-682077Y1037599D02*
X-685541D01*
G01X-677530Y1034568D02*
Y1043229D01*
X-675365D01*
X-674498Y1042796D01*
X-673849Y1042219D01*
X-673307Y1041353D01*
X-672874Y1040342D01*
X-672766Y1038898D01*
X-672874Y1037455D01*
X-673307Y1036444D01*
X-673849Y1035578D01*
X-674498Y1035001D01*
X-675365Y1034568D01*
X-677530D01*
G01X-667028Y1031681D02*
X-668111Y1033125D01*
X-668652Y1034568D01*
Y1040342D01*
X-668111Y1041786D01*
X-667028Y1043229D01*
G01X-659883D02*
X-655769D01*
X-659883Y1034568D01*
X-655769D01*
G01X-651222Y1043229D02*
X-647108D01*
X-651222Y1034568D01*
X-647108D01*
G01X-643752Y1031681D02*
X-637256D01*
G01X-634550Y1034568D02*
X-631843Y1043229D01*
X-629136Y1034568D01*
G01X-630111Y1037599D02*
X-633575D01*
G01X-625239Y1034568D02*
Y1043229D01*
X-621125D01*
G01X-622641Y1039043D02*
X-625239D01*
G01X-612356Y1034568D02*
X-616686D01*
Y1043229D01*
X-612356D01*
G01X-614088Y1039043D02*
X-616686D01*
G01X-608350Y1034568D02*
Y1043229D01*
X-603370Y1034568D01*
Y1043229D01*
G01X-597199Y1034568D02*
X-596441Y1034712D01*
X-595575Y1035145D01*
X-595034Y1035867D01*
X-594817Y1036878D01*
X-595034Y1037888D01*
X-595683Y1038754D01*
X-596658Y1039187D01*
X-597740D01*
X-598390Y1039476D01*
X-598931Y1040198D01*
X-599148Y1041208D01*
X-598823Y1042219D01*
X-598065Y1042940D01*
X-597199Y1043229D01*
X-596333Y1042940D01*
X-595575Y1042219D01*
X-595250Y1041208D01*
X-595467Y1040198D01*
X-596008Y1039476D01*
X-596658Y1039187D01*
X-597740D01*
X-598715Y1038754D01*
X-599364Y1037888D01*
X-599581Y1036878D01*
X-599364Y1035867D01*
X-598823Y1035145D01*
X-597957Y1034712D01*
X-597199Y1034568D01*
G01X-591786Y1031681D02*
X-585290D01*
G01X-579877Y1034568D02*
Y1043229D01*
X-581176Y1041497D01*
G01Y1034568D02*
X-578578D01*
G01X-573598Y1036300D02*
X-572948Y1035290D01*
X-572082Y1034712D01*
X-571108Y1034568D01*
X-570242Y1034712D01*
X-569375Y1035434D01*
X-568834Y1036300D01*
X-568726Y1037166D01*
X-568942Y1038177D01*
X-569700Y1038898D01*
X-570458Y1039187D01*
X-571433D01*
G01X-570458D02*
X-569809Y1039620D01*
X-569267Y1040342D01*
X-569051Y1041208D01*
X-569267Y1042074D01*
X-569809Y1042796D01*
X-570783Y1043229D01*
X-571757Y1043085D01*
X-572732Y1042507D01*
G01X-562555Y1034568D02*
X-561797Y1034712D01*
X-560931Y1035145D01*
X-560390Y1035867D01*
X-560173Y1036878D01*
X-560390Y1037888D01*
X-561039Y1038754D01*
X-562014Y1039187D01*
X-563096D01*
X-563746Y1039476D01*
X-564287Y1040198D01*
X-564504Y1041208D01*
X-564179Y1042219D01*
X-563421Y1042940D01*
X-562555Y1043229D01*
X-561689Y1042940D01*
X-560931Y1042219D01*
X-560606Y1041208D01*
X-560823Y1040198D01*
X-561364Y1039476D01*
X-562014Y1039187D01*
X-563096D01*
X-564071Y1038754D01*
X-564720Y1037888D01*
X-564937Y1036878D01*
X-564720Y1035867D01*
X-564179Y1035145D01*
X-563313Y1034712D01*
X-562555Y1034568D01*
G01X-553353Y1031681D02*
X-552270Y1033125D01*
X-551729Y1034568D01*
Y1040342D01*
X-552270Y1041786D01*
X-553353Y1043229D01*
G01X-744491Y1173180D02*
X-745356Y1173830D01*
X-745790Y1174587D01*
X-745934Y1175454D01*
X-745645Y1176536D01*
X-744924Y1177294D01*
X-744058Y1177511D01*
X-743191Y1177402D01*
X-742470Y1176969D01*
X-741026Y1174804D01*
X-740016Y1173830D01*
X-738572Y1173180D01*
X-737273Y1172963D01*
Y1177511D01*
G01X-739005Y1181516D02*
X-737995Y1182166D01*
X-737417Y1183032D01*
X-737273Y1184006D01*
X-737417Y1184872D01*
X-738139Y1185739D01*
X-739005Y1186280D01*
X-739871Y1186388D01*
X-740882Y1186172D01*
X-741603Y1185414D01*
X-741892Y1184656D01*
Y1183681D01*
G01Y1184656D02*
X-742325Y1185305D01*
X-743047Y1185847D01*
X-743913Y1186063D01*
X-744779Y1185847D01*
X-745501Y1185305D01*
X-745934Y1184331D01*
X-745790Y1183357D01*
X-745212Y1182382D01*
G01X-738572Y1190177D02*
X-737850Y1190827D01*
X-737417Y1191585D01*
X-737273Y1192559D01*
X-737562Y1193533D01*
X-738139Y1194291D01*
X-739149Y1194833D01*
X-740304Y1194941D01*
X-741459Y1194724D01*
X-742181Y1194183D01*
X-742758Y1193425D01*
X-742903Y1192667D01*
X-742758Y1191909D01*
X-742181Y1190935D01*
X-745934Y1191260D01*
Y1194183D01*
G01X-736984Y1201220D02*
X-737129Y1201003D01*
X-737417D01*
X-737562Y1201220D01*
X-737417Y1201437D01*
X-737129D01*
X-736984Y1201220D01*
G01X-745934Y1209881D02*
X-745645Y1209015D01*
X-744924Y1208365D01*
X-744058Y1207932D01*
X-742903Y1207607D01*
X-741603Y1207499D01*
X-740304Y1207607D01*
X-739149Y1207932D01*
X-738283Y1208365D01*
X-737562Y1209015D01*
X-737273Y1209881D01*
X-737562Y1210747D01*
X-738283Y1211397D01*
X-739149Y1211830D01*
X-740304Y1212155D01*
X-741603Y1212263D01*
X-742903Y1212155D01*
X-744058Y1211830D01*
X-744924Y1211397D01*
X-745645Y1210747D01*
X-745934Y1209881D01*
G01Y1218542D02*
X-745645Y1217676D01*
X-744924Y1217026D01*
X-744058Y1216593D01*
X-742903Y1216268D01*
X-741603Y1216160D01*
X-740304Y1216268D01*
X-739149Y1216593D01*
X-738283Y1217026D01*
X-737562Y1217676D01*
X-737273Y1218542D01*
X-737562Y1219408D01*
X-738283Y1220058D01*
X-739149Y1220491D01*
X-740304Y1220816D01*
X-741603Y1220924D01*
X-742903Y1220816D01*
X-744058Y1220491D01*
X-744924Y1220058D01*
X-745645Y1219408D01*
X-745934Y1218542D01*
G01X-721983Y1254457D02*
X-723066Y1255901D01*
X-723607Y1257344D01*
Y1263118D01*
X-723066Y1264562D01*
X-721983Y1266005D01*
G01X-714946Y1257344D02*
Y1266005D01*
X-712348D01*
X-711482Y1265572D01*
X-710832Y1264562D01*
X-710616Y1263407D01*
X-710832Y1262252D01*
X-711374Y1261386D01*
X-712348Y1260953D01*
X-714946D01*
G01X-706827Y1257344D02*
X-704120Y1266005D01*
X-701413Y1257344D01*
G01X-702388Y1260375D02*
X-705852D01*
G01X-697841Y1257344D02*
Y1266005D01*
X-695676D01*
X-694809Y1265572D01*
X-694160Y1264995D01*
X-693618Y1264129D01*
X-693185Y1263118D01*
X-693077Y1261674D01*
X-693185Y1260231D01*
X-693618Y1259220D01*
X-694160Y1258354D01*
X-694809Y1257777D01*
X-695676Y1257344D01*
X-697841D01*
G01X-686257Y1254457D02*
X-685174Y1255901D01*
X-684633Y1257344D01*
Y1263118D01*
X-685174Y1264562D01*
X-686257Y1266005D01*
G01X-678678Y1254457D02*
X-679761Y1255901D01*
X-680302Y1257344D01*
Y1263118D01*
X-679761Y1264562D01*
X-678678Y1266005D01*
G01X-671966Y1257344D02*
Y1266005D01*
X-666986Y1257344D01*
Y1266005D01*
G01X-660815Y1257344D02*
X-661681Y1257488D01*
X-662439Y1258066D01*
X-663089Y1258932D01*
X-663522Y1259942D01*
X-663738Y1261097D01*
Y1262252D01*
X-663522Y1263407D01*
X-663089Y1264417D01*
X-662439Y1265283D01*
X-661681Y1265861D01*
X-660815Y1266005D01*
X-659949Y1265861D01*
X-659191Y1265283D01*
X-658541Y1264417D01*
X-658108Y1263407D01*
X-657892Y1262252D01*
Y1261097D01*
X-658108Y1259942D01*
X-658541Y1258932D01*
X-659191Y1258066D01*
X-659949Y1257488D01*
X-660815Y1257344D01*
G01X-643493Y1266005D02*
Y1257344D01*
G01X-645983Y1266005D02*
X-641003D01*
G01X-636997Y1257344D02*
Y1266005D01*
X-634291D01*
X-633425Y1265572D01*
X-632883Y1264995D01*
X-632667Y1263840D01*
X-632883Y1262685D01*
X-633533Y1261963D01*
X-634291Y1261530D01*
X-636997D01*
G01X-634291D02*
X-632667Y1257344D01*
G01X-628878D02*
X-626171Y1266005D01*
X-623464Y1257344D01*
G01X-624439Y1260375D02*
X-627903D01*
G01X-615128Y1265283D02*
X-615778Y1265716D01*
X-616536Y1266005D01*
X-617402D01*
X-618376Y1265572D01*
X-619134Y1264850D01*
X-619675Y1263984D01*
X-620109Y1262541D01*
X-620217Y1261241D01*
X-620000Y1259942D01*
X-619675Y1259076D01*
X-619026Y1258210D01*
X-618268Y1257633D01*
X-617510Y1257344D01*
X-616752D01*
X-615994Y1257633D01*
X-615345Y1258066D01*
X-614803Y1258643D01*
G01X-606684Y1257344D02*
X-611014D01*
Y1266005D01*
X-606684D01*
G01X-608416Y1261819D02*
X-611014D01*
G01X-594234Y1257344D02*
X-591527Y1266005D01*
X-588820Y1257344D01*
G01X-589795Y1260375D02*
X-593259D01*
G01X-582866Y1266005D02*
Y1257344D01*
G01X-585356Y1266005D02*
X-580376D01*
G01X-568251Y1257344D02*
X-565544Y1266005D01*
X-562837Y1257344D01*
G01X-563812Y1260375D02*
X-567276D01*
G01X-559048Y1266005D02*
Y1257344D01*
X-554718D01*
G01X-550387Y1266005D02*
Y1257344D01*
X-546057D01*
G01X-533065Y1266005D02*
Y1257344D01*
X-528735D01*
G01X-524946D02*
X-522239Y1266005D01*
X-519532Y1257344D01*
G01X-520507Y1260375D02*
X-523971D01*
G01X-513578Y1257344D02*
Y1261241D01*
X-515743Y1266005D01*
G01X-511413D02*
X-513578Y1261241D01*
G01X-502752Y1257344D02*
X-507082D01*
Y1266005D01*
X-502752D01*
G01X-504484Y1261819D02*
X-507082D01*
G01X-498421Y1257344D02*
Y1266005D01*
X-495715D01*
X-494849Y1265572D01*
X-494307Y1264995D01*
X-494091Y1263840D01*
X-494307Y1262685D01*
X-494957Y1261963D01*
X-495715Y1261530D01*
X-498421D01*
G01X-495715D02*
X-494091Y1257344D01*
G01X-489869Y1258499D02*
X-489002Y1257777D01*
X-488028Y1257344D01*
X-487162D01*
X-486296Y1257777D01*
X-485646Y1258499D01*
X-485321Y1259509D01*
X-485538Y1260520D01*
X-486079Y1261386D01*
X-487054Y1261963D01*
X-488353Y1262252D01*
X-489111Y1262829D01*
X-489436Y1263840D01*
X-489219Y1264850D01*
X-488678Y1265572D01*
X-487920Y1266005D01*
X-487162D01*
X-486404Y1265716D01*
X-485754Y1264995D01*
G01X-478393Y1254457D02*
X-477310Y1255901D01*
X-476769Y1257344D01*
Y1263118D01*
X-477310Y1264562D01*
X-478393Y1266005D01*
G01X-657009Y-511490D02*
X-656251Y-512211D01*
X-655385Y-512500D01*
X-654518Y-512211D01*
X-653761Y-511345D01*
X-653219Y-510046D01*
X-653003Y-508747D01*
Y-507159D01*
X-653219Y-505860D01*
X-653761Y-504705D01*
X-654410Y-504128D01*
X-655168Y-503839D01*
X-656034Y-504128D01*
X-656684Y-504705D01*
X-657117Y-505571D01*
X-657333Y-506726D01*
X-657117Y-507736D01*
X-656575Y-508747D01*
X-655926Y-509324D01*
X-655168Y-509469D01*
X-654302Y-509180D01*
X-653652Y-508458D01*
X-653003Y-507159D01*
G01X-646507Y-512789D02*
X-646724Y-512644D01*
Y-512356D01*
X-646507Y-512211D01*
X-646290Y-512356D01*
Y-512644D01*
X-646507Y-512789D01*
G01X-640228Y-511201D02*
X-639578Y-511923D01*
X-638820Y-512356D01*
X-637846Y-512500D01*
X-636872Y-512211D01*
X-636114Y-511634D01*
X-635572Y-510624D01*
X-635464Y-509469D01*
X-635681Y-508314D01*
X-636222Y-507592D01*
X-636980Y-507015D01*
X-637738Y-506870D01*
X-638496Y-507015D01*
X-639470Y-507592D01*
X-639145Y-503839D01*
X-636222D01*
G01X-629185D02*
X-630051Y-504128D01*
X-630701Y-504849D01*
X-631134Y-505715D01*
X-631459Y-506870D01*
X-631567Y-508170D01*
X-631459Y-509469D01*
X-631134Y-510624D01*
X-630701Y-511490D01*
X-630051Y-512211D01*
X-629185Y-512500D01*
X-628319Y-512211D01*
X-627669Y-511490D01*
X-627236Y-510624D01*
X-626911Y-509469D01*
X-626803Y-508170D01*
X-626911Y-506870D01*
X-627236Y-505715D01*
X-627669Y-504849D01*
X-628319Y-504128D01*
X-629185Y-503839D01*
G01X-644017Y-512500D02*
Y-506726D01*
G01Y-508170D02*
X-643583Y-507448D01*
X-642934Y-506870D01*
X-642068Y-506726D01*
X-641310Y-506870D01*
X-640660Y-507448D01*
X-640335Y-508458D01*
Y-512500D01*
G01X-685931Y190634D02*
X-685173Y189913D01*
X-684307Y189624D01*
X-683440Y189913D01*
X-682683Y190779D01*
X-682141Y192078D01*
X-681925Y193377D01*
Y194965D01*
X-682141Y196264D01*
X-682683Y197419D01*
X-683332Y197996D01*
X-684090Y198285D01*
X-684956Y197996D01*
X-685606Y197419D01*
X-686039Y196553D01*
X-686255Y195398D01*
X-686039Y194388D01*
X-685497Y193377D01*
X-684848Y192800D01*
X-684090Y192655D01*
X-683224Y192944D01*
X-682574Y193666D01*
X-681925Y194965D01*
G01X-675429Y189335D02*
X-675646Y189480D01*
Y189768D01*
X-675429Y189913D01*
X-675212Y189768D01*
Y189480D01*
X-675429Y189335D01*
G01X-669150Y190923D02*
X-668500Y190201D01*
X-667742Y189768D01*
X-666768Y189624D01*
X-665794Y189913D01*
X-665036Y190490D01*
X-664494Y191500D01*
X-664386Y192655D01*
X-664603Y193810D01*
X-665144Y194532D01*
X-665902Y195109D01*
X-666660Y195254D01*
X-667418Y195109D01*
X-668392Y194532D01*
X-668067Y198285D01*
X-665144D01*
G01X-658107D02*
X-658973Y197996D01*
X-659623Y197275D01*
X-660056Y196409D01*
X-660381Y195254D01*
X-660489Y193954D01*
X-660381Y192655D01*
X-660056Y191500D01*
X-659623Y190634D01*
X-658973Y189913D01*
X-658107Y189624D01*
X-657241Y189913D01*
X-656591Y190634D01*
X-656158Y191500D01*
X-655833Y192655D01*
X-655725Y193954D01*
X-655833Y195254D01*
X-656158Y196409D01*
X-656591Y197275D01*
X-657241Y197996D01*
X-658107Y198285D01*
G01X-677270Y190634D02*
X-676512Y189913D01*
X-675646Y189624D01*
X-674779Y189913D01*
X-674022Y190779D01*
X-673480Y192078D01*
X-673264Y193377D01*
Y194965D01*
X-673480Y196264D01*
X-674022Y197419D01*
X-674671Y197996D01*
X-675429Y198285D01*
X-676295Y197996D01*
X-676945Y197419D01*
X-677378Y196553D01*
X-677594Y195398D01*
X-677378Y194388D01*
X-676836Y193377D01*
X-676187Y192800D01*
X-675429Y192655D01*
X-674563Y192944D01*
X-673913Y193666D01*
X-673264Y194965D01*
G01X-668175Y192511D02*
X-665361D01*
G01X-672939Y189624D02*
Y195398D01*
G01Y193954D02*
X-672505Y194676D01*
X-671856Y195254D01*
X-670990Y195398D01*
X-670232Y195254D01*
X-669582Y194676D01*
X-669257Y193666D01*
Y189624D01*
G01X-689241Y435905D02*
Y444566D01*
X-690540Y442834D01*
G01Y435905D02*
X-687942D01*
G01X-682962Y437204D02*
X-682312Y436482D01*
X-681554Y436049D01*
X-680580Y435905D01*
X-679606Y436194D01*
X-678848Y436771D01*
X-678306Y437781D01*
X-678198Y438936D01*
X-678415Y440091D01*
X-678956Y440813D01*
X-679714Y441390D01*
X-680472Y441535D01*
X-681230Y441390D01*
X-682204Y440813D01*
X-681879Y444566D01*
X-678956D01*
G01X-671919Y435616D02*
X-672136Y435761D01*
Y436049D01*
X-671919Y436194D01*
X-671702Y436049D01*
Y435761D01*
X-671919Y435616D01*
G01X-663258Y444566D02*
X-664124Y444277D01*
X-664774Y443556D01*
X-665207Y442690D01*
X-665532Y441535D01*
X-665640Y440235D01*
X-665532Y438936D01*
X-665207Y437781D01*
X-664774Y436915D01*
X-664124Y436194D01*
X-663258Y435905D01*
X-662392Y436194D01*
X-661742Y436915D01*
X-661309Y437781D01*
X-660984Y438936D01*
X-660876Y440235D01*
X-660984Y441535D01*
X-661309Y442690D01*
X-661742Y443556D01*
X-662392Y444277D01*
X-663258Y444566D01*
G01X-654597D02*
X-655463Y444277D01*
X-656113Y443556D01*
X-656546Y442690D01*
X-656871Y441535D01*
X-656979Y440235D01*
X-656871Y438936D01*
X-656546Y437781D01*
X-656113Y436915D01*
X-655463Y436194D01*
X-654597Y435905D01*
X-653731Y436194D01*
X-653081Y436915D01*
X-652648Y437781D01*
X-652323Y438936D01*
X-652215Y440235D01*
X-652323Y441535D01*
X-652648Y442690D01*
X-653081Y443556D01*
X-653731Y444277D01*
X-654597Y444566D01*
G01X-644210Y521286D02*
Y527060D01*
G01Y525616D02*
X-643776Y526338D01*
X-643127Y526916D01*
X-642261Y527060D01*
X-641503Y526916D01*
X-640853Y526338D01*
X-640528Y525328D01*
Y521286D01*
G01X-654062D02*
Y529947D01*
X-658068Y523740D01*
X-652654D01*
G01X-646700Y520997D02*
X-646917Y521142D01*
Y521430D01*
X-646700Y521575D01*
X-646483Y521430D01*
Y521142D01*
X-646700Y520997D01*
G01X-638039Y529947D02*
X-638905Y529658D01*
X-639555Y528937D01*
X-639988Y528071D01*
X-640313Y526916D01*
X-640421Y525616D01*
X-640313Y524317D01*
X-639988Y523162D01*
X-639555Y522296D01*
X-638905Y521575D01*
X-638039Y521286D01*
X-637173Y521575D01*
X-636523Y522296D01*
X-636090Y523162D01*
X-635765Y524317D01*
X-635657Y525616D01*
X-635765Y526916D01*
X-636090Y528071D01*
X-636523Y528937D01*
X-637173Y529658D01*
X-638039Y529947D01*
G01X-629378D02*
X-630244Y529658D01*
X-630894Y528937D01*
X-631327Y528071D01*
X-631652Y526916D01*
X-631760Y525616D01*
X-631652Y524317D01*
X-631327Y523162D01*
X-630894Y522296D01*
X-630244Y521575D01*
X-629378Y521286D01*
X-628512Y521575D01*
X-627862Y522296D01*
X-627429Y523162D01*
X-627104Y524317D01*
X-626996Y525616D01*
X-627104Y526916D01*
X-627429Y528071D01*
X-627862Y528937D01*
X-628512Y529658D01*
X-629378Y529947D01*
G01X-655902Y518399D02*
X-656985Y519843D01*
X-657526Y521286D01*
Y527060D01*
X-656985Y528504D01*
X-655902Y529947D01*
G01X-648865Y521286D02*
Y529947D01*
X-646267D01*
X-645401Y529514D01*
X-644751Y528504D01*
X-644535Y527349D01*
X-644751Y526194D01*
X-645293Y525328D01*
X-646267Y524895D01*
X-648865D01*
G01X-638039Y529947D02*
Y521286D01*
G01X-640529Y529947D02*
X-635549D01*
G01X-631652Y521286D02*
Y529947D01*
G01X-627104D02*
Y521286D01*
G01Y525616D02*
X-631652D01*
G01X-620176Y518399D02*
X-619093Y519843D01*
X-618552Y521286D01*
Y527060D01*
X-619093Y528504D01*
X-620176Y529947D01*
G01X-683867Y685577D02*
X-683217Y684567D01*
X-682351Y683989D01*
X-681377Y683845D01*
X-680511Y683989D01*
X-679644Y684711D01*
X-679103Y685577D01*
X-678995Y686443D01*
X-679211Y687454D01*
X-679969Y688175D01*
X-680727Y688464D01*
X-681702D01*
G01X-680727D02*
X-680078Y688897D01*
X-679536Y689619D01*
X-679320Y690485D01*
X-679536Y691351D01*
X-680078Y692073D01*
X-681052Y692506D01*
X-682026Y692362D01*
X-683001Y691784D01*
G01X-672824Y683556D02*
X-673041Y683701D01*
Y683989D01*
X-672824Y684134D01*
X-672607Y683989D01*
Y683701D01*
X-672824Y683556D01*
G01X-664163Y692506D02*
X-665029Y692217D01*
X-665679Y691496D01*
X-666112Y690630D01*
X-666437Y689475D01*
X-666545Y688175D01*
X-666437Y686876D01*
X-666112Y685721D01*
X-665679Y684855D01*
X-665029Y684134D01*
X-664163Y683845D01*
X-663297Y684134D01*
X-662647Y684855D01*
X-662214Y685721D01*
X-661889Y686876D01*
X-661781Y688175D01*
X-661889Y689475D01*
X-662214Y690630D01*
X-662647Y691496D01*
X-663297Y692217D01*
X-664163Y692506D01*
G01X-655502D02*
X-656368Y692217D01*
X-657018Y691496D01*
X-657451Y690630D01*
X-657776Y689475D01*
X-657884Y688175D01*
X-657776Y686876D01*
X-657451Y685721D01*
X-657018Y684855D01*
X-656368Y684134D01*
X-655502Y683845D01*
X-654636Y684134D01*
X-653986Y684855D01*
X-653553Y685721D01*
X-653228Y686876D01*
X-653120Y688175D01*
X-653228Y689475D01*
X-653553Y690630D01*
X-653986Y691496D01*
X-654636Y692217D01*
X-655502Y692506D01*
G01X-690687Y680958D02*
X-691770Y682402D01*
X-692311Y683845D01*
Y689619D01*
X-691770Y691063D01*
X-690687Y692506D01*
G01X-683975Y683845D02*
Y692506D01*
X-678995Y683845D01*
Y692506D01*
G01X-674989Y683845D02*
Y692506D01*
X-672391D01*
X-671525Y692073D01*
X-670875Y691063D01*
X-670659Y689908D01*
X-670875Y688753D01*
X-671417Y687887D01*
X-672391Y687454D01*
X-674989D01*
G01X-664163Y692506D02*
Y683845D01*
G01X-666653Y692506D02*
X-661673D01*
G01X-657776Y683845D02*
Y692506D01*
G01X-653228D02*
Y683845D01*
G01Y688175D02*
X-657776D01*
G01X-646300Y680958D02*
X-645217Y682402D01*
X-644676Y683845D01*
Y689619D01*
X-645217Y691063D01*
X-646300Y692506D01*
G01X-689241Y709449D02*
X-688483Y709593D01*
X-687617Y710026D01*
X-687076Y710748D01*
X-686859Y711759D01*
X-687076Y712769D01*
X-687725Y713635D01*
X-688700Y714068D01*
X-689782D01*
X-690432Y714357D01*
X-690973Y715079D01*
X-691190Y716089D01*
X-690865Y717100D01*
X-690107Y717821D01*
X-689241Y718110D01*
X-688375Y717821D01*
X-687617Y717100D01*
X-687292Y716089D01*
X-687509Y715079D01*
X-688050Y714357D01*
X-688700Y714068D01*
X-689782D01*
X-690757Y713635D01*
X-691406Y712769D01*
X-691623Y711759D01*
X-691406Y710748D01*
X-690865Y710026D01*
X-689999Y709593D01*
X-689241Y709449D01*
G01X-679281D02*
Y718110D01*
X-683287Y711903D01*
X-677873D01*
G01X-671919Y709160D02*
X-672136Y709305D01*
Y709593D01*
X-671919Y709738D01*
X-671702Y709593D01*
Y709305D01*
X-671919Y709160D01*
G01X-661959Y709449D02*
Y718110D01*
X-665965Y711903D01*
X-660551D01*
G01X-654597Y709449D02*
X-653839Y709593D01*
X-652973Y710026D01*
X-652432Y710748D01*
X-652215Y711759D01*
X-652432Y712769D01*
X-653081Y713635D01*
X-654056Y714068D01*
X-655138D01*
X-655788Y714357D01*
X-656329Y715079D01*
X-656546Y716089D01*
X-656221Y717100D01*
X-655463Y717821D01*
X-654597Y718110D01*
X-653731Y717821D01*
X-652973Y717100D01*
X-652648Y716089D01*
X-652865Y715079D01*
X-653406Y714357D01*
X-654056Y714068D01*
X-655138D01*
X-656113Y713635D01*
X-656762Y712769D01*
X-656979Y711759D01*
X-656762Y710748D01*
X-656221Y710026D01*
X-655355Y709593D01*
X-654597Y709449D01*
G01X-670334Y683845D02*
Y689619D01*
G01Y688175D02*
X-669900Y688897D01*
X-669251Y689475D01*
X-668385Y689619D01*
X-667627Y689475D01*
X-666977Y688897D01*
X-666652Y687887D01*
Y683845D01*
G01X-696653Y768635D02*
X-697736Y770079D01*
X-698277Y771522D01*
Y777296D01*
X-697736Y778740D01*
X-696653Y780183D01*
G01X-689941Y771522D02*
Y780183D01*
X-684961Y771522D01*
Y780183D01*
G01X-678790Y771522D02*
X-679656Y771666D01*
X-680414Y772244D01*
X-681064Y773110D01*
X-681497Y774120D01*
X-681713Y775275D01*
Y776430D01*
X-681497Y777585D01*
X-681064Y778595D01*
X-680414Y779461D01*
X-679656Y780039D01*
X-678790Y780183D01*
X-677924Y780039D01*
X-677166Y779461D01*
X-676516Y778595D01*
X-676083Y777585D01*
X-675867Y776430D01*
Y775275D01*
X-676083Y774120D01*
X-676516Y773110D01*
X-677166Y772244D01*
X-677924Y771666D01*
X-678790Y771522D01*
G01X-661468Y780183D02*
Y771522D01*
G01X-663958Y780183D02*
X-658978D01*
G01X-654972Y771522D02*
Y780183D01*
X-652266D01*
X-651400Y779750D01*
X-650858Y779173D01*
X-650642Y778018D01*
X-650858Y776863D01*
X-651508Y776141D01*
X-652266Y775708D01*
X-654972D01*
G01X-652266D02*
X-650642Y771522D01*
G01X-646853D02*
X-644146Y780183D01*
X-641439Y771522D01*
G01X-642414Y774553D02*
X-645878D01*
G01X-633103Y779461D02*
X-633753Y779894D01*
X-634511Y780183D01*
X-635377D01*
X-636351Y779750D01*
X-637109Y779028D01*
X-637650Y778162D01*
X-638084Y776719D01*
X-638192Y775419D01*
X-637975Y774120D01*
X-637650Y773254D01*
X-637001Y772388D01*
X-636243Y771811D01*
X-635485Y771522D01*
X-634727D01*
X-633969Y771811D01*
X-633320Y772244D01*
X-632778Y772821D01*
G01X-624659Y771522D02*
X-628989D01*
Y780183D01*
X-624659D01*
G01X-626391Y775997D02*
X-628989D01*
G01X-612209Y771522D02*
X-609502Y780183D01*
X-606795Y771522D01*
G01X-607770Y774553D02*
X-611234D01*
G01X-600841Y780183D02*
Y771522D01*
G01X-603331Y780183D02*
X-598351D01*
G01X-586226Y771522D02*
X-583519Y780183D01*
X-580812Y771522D01*
G01X-581787Y774553D02*
X-585251D01*
G01X-577023Y780183D02*
Y771522D01*
X-572693D01*
G01X-568362Y780183D02*
Y771522D01*
X-564032D01*
G01X-551040Y780183D02*
Y771522D01*
X-546710D01*
G01X-542921D02*
X-540214Y780183D01*
X-537507Y771522D01*
G01X-538482Y774553D02*
X-541946D01*
G01X-531553Y771522D02*
Y775419D01*
X-533718Y780183D01*
G01X-529388D02*
X-531553Y775419D01*
G01X-520727Y771522D02*
X-525057D01*
Y780183D01*
X-520727D01*
G01X-522459Y775997D02*
X-525057D01*
G01X-516396Y771522D02*
Y780183D01*
X-513690D01*
X-512824Y779750D01*
X-512282Y779173D01*
X-512066Y778018D01*
X-512282Y776863D01*
X-512932Y776141D01*
X-513690Y775708D01*
X-516396D01*
G01X-513690D02*
X-512066Y771522D01*
G01X-507844Y772677D02*
X-506977Y771955D01*
X-506003Y771522D01*
X-505137D01*
X-504271Y771955D01*
X-503621Y772677D01*
X-503296Y773687D01*
X-503513Y774698D01*
X-504054Y775564D01*
X-505029Y776141D01*
X-506328Y776430D01*
X-507086Y777007D01*
X-507411Y778018D01*
X-507194Y779028D01*
X-506653Y779750D01*
X-505895Y780183D01*
X-505137D01*
X-504379Y779894D01*
X-503729Y779173D01*
G01X-496368Y768635D02*
X-495285Y770079D01*
X-494744Y771522D01*
Y777296D01*
X-495285Y778740D01*
X-496368Y780183D01*
G01X-700861Y809921D02*
Y818582D01*
X-702160Y816850D01*
G01Y809921D02*
X-699562D01*
G01X-692200D02*
Y818582D01*
X-693499Y816850D01*
G01Y809921D02*
X-690901D01*
G01X-683539Y818582D02*
X-684405Y818293D01*
X-685055Y817572D01*
X-685488Y816706D01*
X-685813Y815551D01*
X-685921Y814251D01*
X-685813Y812952D01*
X-685488Y811797D01*
X-685055Y810931D01*
X-684405Y810210D01*
X-683539Y809921D01*
X-682673Y810210D01*
X-682023Y810931D01*
X-681590Y811797D01*
X-681265Y812952D01*
X-681157Y814251D01*
X-681265Y815551D01*
X-681590Y816706D01*
X-682023Y817572D01*
X-682673Y818293D01*
X-683539Y818582D01*
G01X-674878Y809632D02*
X-675095Y809777D01*
Y810065D01*
X-674878Y810210D01*
X-674661Y810065D01*
Y809777D01*
X-674878Y809632D01*
G01X-666217Y818582D02*
X-667083Y818293D01*
X-667733Y817572D01*
X-668166Y816706D01*
X-668491Y815551D01*
X-668599Y814251D01*
X-668491Y812952D01*
X-668166Y811797D01*
X-667733Y810931D01*
X-667083Y810210D01*
X-666217Y809921D01*
X-665351Y810210D01*
X-664701Y810931D01*
X-664268Y811797D01*
X-663943Y812952D01*
X-663835Y814251D01*
X-663943Y815551D01*
X-664268Y816706D01*
X-664701Y817572D01*
X-665351Y818293D01*
X-666217Y818582D01*
G01X-657556D02*
X-658422Y818293D01*
X-659072Y817572D01*
X-659505Y816706D01*
X-659830Y815551D01*
X-659938Y814251D01*
X-659830Y812952D01*
X-659505Y811797D01*
X-659072Y810931D01*
X-658422Y810210D01*
X-657556Y809921D01*
X-656690Y810210D01*
X-656040Y810931D01*
X-655607Y811797D01*
X-655282Y812952D01*
X-655174Y814251D01*
X-655282Y815551D01*
X-655607Y816706D01*
X-656040Y817572D01*
X-656690Y818293D01*
X-657556Y818582D01*
G01X-651298Y1181732D02*
X-650648Y1180722D01*
X-649782Y1180144D01*
X-648808Y1180000D01*
X-647942Y1180144D01*
X-647075Y1180866D01*
X-646534Y1181732D01*
X-646426Y1182598D01*
X-646642Y1183609D01*
X-647400Y1184330D01*
X-648158Y1184619D01*
X-649133D01*
G01X-648158D02*
X-647509Y1185052D01*
X-646967Y1185774D01*
X-646751Y1186640D01*
X-646967Y1187506D01*
X-647509Y1188228D01*
X-648483Y1188661D01*
X-649457Y1188517D01*
X-650432Y1187939D01*
G01X-640255Y1179711D02*
X-640472Y1179856D01*
Y1180144D01*
X-640255Y1180289D01*
X-640038Y1180144D01*
Y1179856D01*
X-640255Y1179711D01*
G01X-633976Y1181299D02*
X-633326Y1180577D01*
X-632568Y1180144D01*
X-631594Y1180000D01*
X-630620Y1180289D01*
X-629862Y1180866D01*
X-629320Y1181876D01*
X-629212Y1183031D01*
X-629429Y1184186D01*
X-629970Y1184908D01*
X-630728Y1185485D01*
X-631486Y1185630D01*
X-632244Y1185485D01*
X-633218Y1184908D01*
X-632893Y1188661D01*
X-629970D01*
G01X-622933D02*
X-623799Y1188372D01*
X-624449Y1187651D01*
X-624882Y1186785D01*
X-625207Y1185630D01*
X-625315Y1184330D01*
X-625207Y1183031D01*
X-624882Y1181876D01*
X-624449Y1181010D01*
X-623799Y1180289D01*
X-622933Y1180000D01*
X-622067Y1180289D01*
X-621417Y1181010D01*
X-620984Y1181876D01*
X-620659Y1183031D01*
X-620551Y1184330D01*
X-620659Y1185630D01*
X-620984Y1186785D01*
X-621417Y1187651D01*
X-622067Y1188372D01*
X-622933Y1188661D01*
G01X-649457Y1177113D02*
X-650540Y1178557D01*
X-651081Y1180000D01*
Y1185774D01*
X-650540Y1187218D01*
X-649457Y1188661D01*
G01X-642420Y1180000D02*
Y1188661D01*
X-639822D01*
X-638956Y1188228D01*
X-638306Y1187218D01*
X-638090Y1186063D01*
X-638306Y1184908D01*
X-638848Y1184042D01*
X-639822Y1183609D01*
X-642420D01*
G01X-631594Y1188661D02*
Y1180000D01*
G01X-634084Y1188661D02*
X-629104D01*
G01X-625207Y1180000D02*
Y1188661D01*
G01X-620659D02*
Y1180000D01*
G01Y1184330D02*
X-625207D01*
G01X-613731Y1177113D02*
X-612648Y1178557D01*
X-612107Y1180000D01*
Y1185774D01*
X-612648Y1187218D01*
X-613731Y1188661D01*
G01X-642096Y1181010D02*
X-641338Y1180289D01*
X-640472Y1180000D01*
X-639605Y1180289D01*
X-638848Y1181155D01*
X-638306Y1182454D01*
X-638090Y1183753D01*
Y1185341D01*
X-638306Y1186640D01*
X-638848Y1187795D01*
X-639497Y1188372D01*
X-640255Y1188661D01*
X-641121Y1188372D01*
X-641771Y1187795D01*
X-642204Y1186929D01*
X-642420Y1185774D01*
X-642204Y1184764D01*
X-641662Y1183753D01*
X-641013Y1183176D01*
X-640255Y1183031D01*
X-639389Y1183320D01*
X-638739Y1184042D01*
X-638090Y1185341D01*
G01X-633001Y1182887D02*
X-630187D01*
G01X-610336Y-852846D02*
X-610052Y-850384D01*
X-609626Y-848301D01*
X-609058Y-846408D01*
X-608348Y-844325D01*
X-607211Y-841484D01*
X-612893D01*
G01X-587234Y315197D02*
Y320971D01*
G01Y319527D02*
X-586800Y320249D01*
X-586151Y320827D01*
X-585285Y320971D01*
X-584527Y320827D01*
X-583877Y320249D01*
X-583552Y319239D01*
Y315197D01*
G01X-600226Y316207D02*
X-599468Y315486D01*
X-598602Y315197D01*
X-597735Y315486D01*
X-596978Y316352D01*
X-596436Y317651D01*
X-596220Y318950D01*
Y320538D01*
X-596436Y321837D01*
X-596978Y322992D01*
X-597627Y323569D01*
X-598385Y323858D01*
X-599251Y323569D01*
X-599901Y322992D01*
X-600334Y322126D01*
X-600550Y320971D01*
X-600334Y319961D01*
X-599792Y318950D01*
X-599143Y318373D01*
X-598385Y318228D01*
X-597519Y318517D01*
X-596869Y319239D01*
X-596220Y320538D01*
G01X-589724Y314908D02*
X-589941Y315053D01*
Y315341D01*
X-589724Y315486D01*
X-589507Y315341D01*
Y315053D01*
X-589724Y314908D01*
G01X-583445Y316496D02*
X-582795Y315774D01*
X-582037Y315341D01*
X-581063Y315197D01*
X-580089Y315486D01*
X-579331Y316063D01*
X-578789Y317073D01*
X-578681Y318228D01*
X-578898Y319383D01*
X-579439Y320105D01*
X-580197Y320682D01*
X-580955Y320827D01*
X-581713Y320682D01*
X-582687Y320105D01*
X-582362Y323858D01*
X-579439D01*
G01X-572402D02*
X-573268Y323569D01*
X-573918Y322848D01*
X-574351Y321982D01*
X-574676Y320827D01*
X-574784Y319527D01*
X-574676Y318228D01*
X-574351Y317073D01*
X-573918Y316207D01*
X-573268Y315486D01*
X-572402Y315197D01*
X-571536Y315486D01*
X-570886Y316207D01*
X-570453Y317073D01*
X-570128Y318228D01*
X-570020Y319527D01*
X-570128Y320827D01*
X-570453Y321982D01*
X-570886Y322848D01*
X-571536Y323569D01*
X-572402Y323858D01*
G01X-598351Y771522D02*
Y777296D01*
G01Y775852D02*
X-597917Y776574D01*
X-597268Y777152D01*
X-596402Y777296D01*
X-595644Y777152D01*
X-594994Y776574D01*
X-594669Y775564D01*
Y771522D01*
G01X-611559Y775131D02*
X-610801Y776141D01*
X-610152Y776719D01*
X-609285Y777007D01*
X-608528Y776719D01*
X-607986Y776141D01*
X-607553Y775275D01*
X-607445Y774265D01*
X-607553Y773398D01*
X-607986Y772532D01*
X-608636Y771811D01*
X-609394Y771522D01*
X-610260Y771811D01*
X-611018Y772677D01*
X-611451Y773976D01*
X-611559Y775419D01*
X-611343Y777296D01*
X-611018Y778307D01*
X-610476Y779317D01*
X-609719Y780039D01*
X-608961Y780183D01*
X-608203Y779894D01*
X-607661Y779173D01*
G01X-600841Y771233D02*
X-601058Y771378D01*
Y771666D01*
X-600841Y771811D01*
X-600624Y771666D01*
Y771378D01*
X-600841Y771233D01*
G01X-592180Y780183D02*
X-593046Y779894D01*
X-593696Y779173D01*
X-594129Y778307D01*
X-594454Y777152D01*
X-594562Y775852D01*
X-594454Y774553D01*
X-594129Y773398D01*
X-593696Y772532D01*
X-593046Y771811D01*
X-592180Y771522D01*
X-591314Y771811D01*
X-590664Y772532D01*
X-590231Y773398D01*
X-589906Y774553D01*
X-589798Y775852D01*
X-589906Y777152D01*
X-590231Y778307D01*
X-590664Y779173D01*
X-591314Y779894D01*
X-592180Y780183D01*
G01X-583519D02*
X-584385Y779894D01*
X-585035Y779173D01*
X-585468Y778307D01*
X-585793Y777152D01*
X-585901Y775852D01*
X-585793Y774553D01*
X-585468Y773398D01*
X-585035Y772532D01*
X-584385Y771811D01*
X-583519Y771522D01*
X-582653Y771811D01*
X-582003Y772532D01*
X-581570Y773398D01*
X-581245Y774553D01*
X-581137Y775852D01*
X-581245Y777152D01*
X-581570Y778307D01*
X-582003Y779173D01*
X-582653Y779894D01*
X-583519Y780183D01*
G01X-637765Y1180000D02*
Y1185774D01*
G01Y1184330D02*
X-637331Y1185052D01*
X-636682Y1185630D01*
X-635816Y1185774D01*
X-635058Y1185630D01*
X-634408Y1185052D01*
X-634083Y1184042D01*
Y1180000D01*
G01X-615021Y1258354D02*
X-614263Y1257633D01*
X-613397Y1257344D01*
X-612530Y1257633D01*
X-611773Y1258499D01*
X-611231Y1259798D01*
X-611015Y1261097D01*
Y1262685D01*
X-611231Y1263984D01*
X-611773Y1265139D01*
X-612422Y1265716D01*
X-613180Y1266005D01*
X-614046Y1265716D01*
X-614696Y1265139D01*
X-615129Y1264273D01*
X-615345Y1263118D01*
X-615129Y1262108D01*
X-614587Y1261097D01*
X-613938Y1260520D01*
X-613180Y1260375D01*
X-612314Y1260664D01*
X-611664Y1261386D01*
X-611015Y1262685D01*
G01X-604519Y1257055D02*
X-604736Y1257200D01*
Y1257488D01*
X-604519Y1257633D01*
X-604302Y1257488D01*
Y1257200D01*
X-604519Y1257055D01*
G01X-598240Y1258643D02*
X-597590Y1257921D01*
X-596832Y1257488D01*
X-595858Y1257344D01*
X-594884Y1257633D01*
X-594126Y1258210D01*
X-593584Y1259220D01*
X-593476Y1260375D01*
X-593693Y1261530D01*
X-594234Y1262252D01*
X-594992Y1262829D01*
X-595750Y1262974D01*
X-596508Y1262829D01*
X-597482Y1262252D01*
X-597157Y1266005D01*
X-594234D01*
G01X-587197D02*
X-588063Y1265716D01*
X-588713Y1264995D01*
X-589146Y1264129D01*
X-589471Y1262974D01*
X-589579Y1261674D01*
X-589471Y1260375D01*
X-589146Y1259220D01*
X-588713Y1258354D01*
X-588063Y1257633D01*
X-587197Y1257344D01*
X-586331Y1257633D01*
X-585681Y1258354D01*
X-585248Y1259220D01*
X-584923Y1260375D01*
X-584815Y1261674D01*
X-584923Y1262974D01*
X-585248Y1264129D01*
X-585681Y1264995D01*
X-586331Y1265716D01*
X-587197Y1266005D01*
G01X-606360Y1258354D02*
X-605602Y1257633D01*
X-604736Y1257344D01*
X-603869Y1257633D01*
X-603112Y1258499D01*
X-602570Y1259798D01*
X-602354Y1261097D01*
Y1262685D01*
X-602570Y1263984D01*
X-603112Y1265139D01*
X-603761Y1265716D01*
X-604519Y1266005D01*
X-605385Y1265716D01*
X-606035Y1265139D01*
X-606468Y1264273D01*
X-606684Y1263118D01*
X-606468Y1262108D01*
X-605926Y1261097D01*
X-605277Y1260520D01*
X-604519Y1260375D01*
X-603653Y1260664D01*
X-603003Y1261386D01*
X-602354Y1262685D01*
G01X-597265Y1260231D02*
X-594451D01*
G01X-602029Y1257344D02*
Y1263118D01*
G01Y1261674D02*
X-601595Y1262396D01*
X-600946Y1262974D01*
X-600080Y1263118D01*
X-599322Y1262974D01*
X-598672Y1262396D01*
X-598347Y1261386D01*
Y1257344D01*
G01X-610336Y1324910D02*
X-610052Y1327372D01*
X-609626Y1329455D01*
X-609058Y1331348D01*
X-608348Y1333431D01*
X-607211Y1336272D01*
X-612893D01*
G01X-390382Y-852846D02*
X-389388Y-852657D01*
X-388252Y-852089D01*
X-387541Y-851142D01*
X-387257Y-849816D01*
X-387541Y-848491D01*
X-388394Y-847354D01*
X-389672Y-846786D01*
X-391092D01*
X-391944Y-846408D01*
X-392655Y-845461D01*
X-392939Y-844135D01*
X-392512Y-842810D01*
X-391518Y-841863D01*
X-390382Y-841484D01*
X-389246Y-841863D01*
X-388252Y-842810D01*
X-387825Y-844135D01*
X-388110Y-845461D01*
X-388820Y-846408D01*
X-389672Y-846786D01*
X-391092D01*
X-392370Y-847354D01*
X-393223Y-848491D01*
X-393507Y-849816D01*
X-393223Y-851142D01*
X-392512Y-852089D01*
X-391376Y-852657D01*
X-390382Y-852846D01*
G01Y1324910D02*
X-389388Y1325099D01*
X-388252Y1325667D01*
X-387541Y1326614D01*
X-387257Y1327940D01*
X-387541Y1329265D01*
X-388394Y1330402D01*
X-389672Y1330970D01*
X-391092D01*
X-391944Y1331348D01*
X-392655Y1332295D01*
X-392939Y1333621D01*
X-392512Y1334946D01*
X-391518Y1335893D01*
X-390382Y1336272D01*
X-389246Y1335893D01*
X-388252Y1334946D01*
X-387825Y1333621D01*
X-388110Y1332295D01*
X-388820Y1331348D01*
X-389672Y1330970D01*
X-391092D01*
X-392370Y1330402D01*
X-393223Y1329265D01*
X-393507Y1327940D01*
X-393223Y1326614D01*
X-392512Y1325667D01*
X-391376Y1325099D01*
X-390382Y1324910D01*
G01X-173128Y-851521D02*
X-172133Y-852467D01*
X-170997Y-852846D01*
X-169861Y-852467D01*
X-168867Y-851331D01*
X-168156Y-849627D01*
X-167872Y-847922D01*
Y-845840D01*
X-168156Y-844135D01*
X-168867Y-842620D01*
X-169719Y-841863D01*
X-170713Y-841484D01*
X-171849Y-841863D01*
X-172701Y-842620D01*
X-173270Y-843756D01*
X-173554Y-845272D01*
X-173270Y-846597D01*
X-172559Y-847922D01*
X-171707Y-848680D01*
X-170713Y-848869D01*
X-169577Y-848491D01*
X-168725Y-847544D01*
X-167872Y-845840D01*
G01X-173128Y1326235D02*
X-172133Y1325289D01*
X-170997Y1324910D01*
X-169861Y1325289D01*
X-168867Y1326425D01*
X-168156Y1328129D01*
X-167872Y1329834D01*
Y1331916D01*
X-168156Y1333621D01*
X-168867Y1335136D01*
X-169719Y1335893D01*
X-170713Y1336272D01*
X-171849Y1335893D01*
X-172701Y1335136D01*
X-173270Y1334000D01*
X-173554Y1332484D01*
X-173270Y1331159D01*
X-172559Y1329834D01*
X-171707Y1329076D01*
X-170713Y1328887D01*
X-169577Y1329265D01*
X-168725Y1330212D01*
X-167872Y1331916D01*
G01X-62047Y3374D02*
X-62835Y3112D01*
X-63425Y2455D01*
X-63819Y1668D01*
X-64114Y618D01*
X-64213Y-563D01*
X-64114Y-1744D01*
X-63819Y-2794D01*
X-63425Y-3582D01*
X-62835Y-4238D01*
X-62047Y-4500D01*
X-61260Y-4238D01*
X-60669Y-3582D01*
X-60275Y-2794D01*
X-59980Y-1744D01*
X-59881Y-563D01*
X-59980Y618D01*
X-60275Y1668D01*
X-60669Y2455D01*
X-61260Y3112D01*
X-62047Y3374D01*
G01X-54172Y-4762D02*
X-54369Y-4631D01*
Y-4369D01*
X-54172Y-4238D01*
X-53975Y-4369D01*
Y-4631D01*
X-54172Y-4762D01*
G01X-46297Y3374D02*
X-47085Y3112D01*
X-47675Y2455D01*
X-48069Y1668D01*
X-48364Y618D01*
X-48463Y-563D01*
X-48364Y-1744D01*
X-48069Y-2794D01*
X-47675Y-3582D01*
X-47085Y-4238D01*
X-46297Y-4500D01*
X-45510Y-4238D01*
X-44919Y-3582D01*
X-44525Y-2794D01*
X-44230Y-1744D01*
X-44131Y-563D01*
X-44230Y618D01*
X-44525Y1668D01*
X-44919Y2455D01*
X-45510Y3112D01*
X-46297Y3374D01*
G01X-38422D02*
X-39210Y3112D01*
X-39800Y2455D01*
X-40194Y1668D01*
X-40489Y618D01*
X-40588Y-563D01*
X-40489Y-1744D01*
X-40194Y-2794D01*
X-39800Y-3582D01*
X-39210Y-4238D01*
X-38422Y-4500D01*
X-37635Y-4238D01*
X-37044Y-3582D01*
X-36650Y-2794D01*
X-36355Y-1744D01*
X-36256Y-563D01*
X-36355Y618D01*
X-36650Y1668D01*
X-37044Y2455D01*
X-37635Y3112D01*
X-38422Y3374D01*
G01X-78047Y760000D02*
Y767874D01*
X-79228Y766299D01*
G01Y760000D02*
X-76866D01*
G01X-71845Y760918D02*
X-71156Y760262D01*
X-70369Y760000D01*
X-69581Y760262D01*
X-68892Y761050D01*
X-68400Y762231D01*
X-68203Y763412D01*
Y764856D01*
X-68400Y766037D01*
X-68892Y767087D01*
X-69483Y767612D01*
X-70172Y767874D01*
X-70960Y767612D01*
X-71550Y767087D01*
X-71944Y766299D01*
X-72141Y765249D01*
X-71944Y764331D01*
X-71452Y763412D01*
X-70861Y762887D01*
X-70172Y762756D01*
X-69385Y763018D01*
X-68794Y763674D01*
X-68203Y764856D01*
G01X-61116Y760000D02*
Y767874D01*
X-64758Y762231D01*
X-59836D01*
G01X-54422Y759738D02*
X-54619Y759869D01*
Y760131D01*
X-54422Y760262D01*
X-54225Y760131D01*
Y759869D01*
X-54422Y759738D01*
G01X-46547Y767874D02*
X-47335Y767612D01*
X-47925Y766955D01*
X-48319Y766168D01*
X-48614Y765118D01*
X-48713Y763937D01*
X-48614Y762756D01*
X-48319Y761706D01*
X-47925Y760918D01*
X-47335Y760262D01*
X-46547Y760000D01*
X-45760Y760262D01*
X-45169Y760918D01*
X-44775Y761706D01*
X-44480Y762756D01*
X-44381Y763937D01*
X-44480Y765118D01*
X-44775Y766168D01*
X-45169Y766955D01*
X-45760Y767612D01*
X-46547Y767874D01*
G01X-38672D02*
X-39460Y767612D01*
X-40050Y766955D01*
X-40444Y766168D01*
X-40739Y765118D01*
X-40838Y763937D01*
X-40739Y762756D01*
X-40444Y761706D01*
X-40050Y760918D01*
X-39460Y760262D01*
X-38672Y760000D01*
X-37885Y760262D01*
X-37294Y760918D01*
X-36900Y761706D01*
X-36605Y762756D01*
X-36506Y763937D01*
X-36605Y765118D01*
X-36900Y766168D01*
X-37294Y766955D01*
X-37885Y767612D01*
X-38672Y767874D01*
G01X-3937Y796555D02*
X-3675Y795767D01*
X-3018Y795177D01*
X-2231Y794783D01*
X-1181Y794488D01*
X0Y794389D01*
X1181Y794488D01*
X2231Y794783D01*
X3019Y795177D01*
X3675Y795767D01*
X3937Y796555D01*
X3675Y797342D01*
X3019Y797933D01*
X2231Y798327D01*
X1181Y798622D01*
X0Y798721D01*
X-1181Y798622D01*
X-2231Y798327D01*
X-3018Y797933D01*
X-3675Y797342D01*
X-3937Y796555D01*
G01X4199Y804430D02*
X4068Y804233D01*
X3806D01*
X3675Y804430D01*
X3806Y804627D01*
X4068D01*
X4199Y804430D01*
G01X-3937Y812305D02*
X-3675Y811517D01*
X-3018Y810927D01*
X-2231Y810533D01*
X-1181Y810238D01*
X0Y810139D01*
X1181Y810238D01*
X2231Y810533D01*
X3019Y810927D01*
X3675Y811517D01*
X3937Y812305D01*
X3675Y813092D01*
X3019Y813683D01*
X2231Y814077D01*
X1181Y814372D01*
X0Y814471D01*
X-1181Y814372D01*
X-2231Y814077D01*
X-3018Y813683D01*
X-3675Y813092D01*
X-3937Y812305D01*
G01Y820180D02*
X-3675Y819392D01*
X-3018Y818802D01*
X-2231Y818408D01*
X-1181Y818113D01*
X0Y818014D01*
X1181Y818113D01*
X2231Y818408D01*
X3019Y818802D01*
X3675Y819392D01*
X3937Y820180D01*
X3675Y820967D01*
X3019Y821558D01*
X2231Y821952D01*
X1181Y822247D01*
X0Y822346D01*
X-1181Y822247D01*
X-2231Y821952D01*
X-3018Y821558D01*
X-3675Y820967D01*
X-3937Y820180D01*
G01X46305Y-852846D02*
Y-841484D01*
X44601Y-843756D01*
G01Y-852846D02*
X48009D01*
G01X57668Y-841484D02*
X56532Y-841863D01*
X55680Y-842810D01*
X55111Y-843946D01*
X54685Y-845461D01*
X54543Y-847165D01*
X54685Y-848869D01*
X55111Y-850384D01*
X55680Y-851521D01*
X56532Y-852467D01*
X57668Y-852846D01*
X58804Y-852467D01*
X59656Y-851521D01*
X60225Y-850384D01*
X60651Y-848869D01*
X60793Y-847165D01*
X60651Y-845461D01*
X60225Y-843946D01*
X59656Y-842810D01*
X58804Y-841863D01*
X57668Y-841484D01*
G01X87595Y-710665D02*
X86095Y-709665D01*
X84345Y-708998D01*
X82345D01*
X80095Y-709998D01*
X78345Y-711665D01*
X77095Y-713665D01*
X76095Y-716998D01*
X75845Y-719998D01*
X76345Y-722998D01*
X77095Y-724998D01*
X78595Y-726998D01*
X80345Y-728331D01*
X82095Y-728998D01*
X83845D01*
X85595Y-728331D01*
X87095Y-727332D01*
X88345Y-725999D01*
G01X98595Y-728998D02*
Y-715665D01*
G01Y-718331D02*
X99845Y-716998D01*
X101095Y-715998D01*
X102845Y-715665D01*
X104095Y-715998D01*
X105595Y-716998D01*
G01X118345Y-719998D02*
X126345D01*
X125595Y-717665D01*
X124345Y-716332D01*
X122595Y-715665D01*
X120845Y-715998D01*
X119345Y-716998D01*
X118345Y-719332D01*
X117845Y-721332D01*
Y-723331D01*
X118345Y-725332D01*
X119595Y-727332D01*
X121095Y-728665D01*
X122845Y-728998D01*
X124595Y-728331D01*
X126345Y-726332D01*
G01X146595Y-728998D02*
Y-715665D01*
G01Y-717998D02*
X145595Y-716665D01*
X144095Y-715998D01*
X142345Y-715665D01*
X140595Y-716332D01*
X139095Y-717665D01*
X138095Y-719665D01*
X137595Y-722332D01*
X138095Y-724998D01*
X139095Y-726998D01*
X140595Y-728331D01*
X142345Y-728998D01*
X144095Y-728665D01*
X145595Y-727665D01*
X146595Y-726332D01*
G01X162095Y-708998D02*
Y-728998D01*
G01X158595Y-715665D02*
X165595D01*
G01X178345Y-719998D02*
X186345D01*
X185595Y-717665D01*
X184345Y-716332D01*
X182595Y-715665D01*
X180845Y-715998D01*
X179345Y-716998D01*
X178345Y-719332D01*
X177845Y-721332D01*
Y-723331D01*
X178345Y-725332D01*
X179595Y-727332D01*
X181095Y-728665D01*
X182845Y-728998D01*
X184595Y-728331D01*
X186345Y-726332D01*
G01X206595Y-708998D02*
Y-728998D01*
G01Y-725999D02*
X205595Y-727665D01*
X204095Y-728665D01*
X202345Y-728998D01*
X200345Y-728331D01*
X198845Y-726665D01*
X197845Y-724665D01*
X197595Y-722332D01*
X197845Y-719998D01*
X198845Y-717998D01*
X200345Y-716332D01*
X202345Y-715665D01*
X204095Y-715998D01*
X205345Y-716665D01*
X206595Y-717998D01*
G01X73143Y-660090D02*
X79393Y-680090D01*
X85643Y-660090D01*
G01X95643Y-671090D02*
X103643D01*
X102893Y-668757D01*
X101643Y-667424D01*
X99893Y-666757D01*
X98143Y-667090D01*
X96643Y-668090D01*
X95643Y-670424D01*
X95143Y-672424D01*
Y-674423D01*
X95643Y-676424D01*
X96893Y-678424D01*
X98393Y-679757D01*
X100143Y-680090D01*
X101893Y-679423D01*
X103643Y-677424D01*
G01X115893Y-680090D02*
Y-666757D01*
G01Y-669423D02*
X117143Y-668090D01*
X118393Y-667090D01*
X120143Y-666757D01*
X121393Y-667090D01*
X122893Y-668090D01*
G01X135643Y-677757D02*
X136893Y-679090D01*
X138643Y-680090D01*
X140143D01*
X141643Y-679423D01*
X142643Y-678424D01*
X143143Y-677091D01*
X142893Y-675090D01*
X141893Y-674090D01*
X137393Y-672090D01*
X136393Y-669756D01*
X136893Y-668090D01*
X137893Y-667090D01*
X139393Y-666757D01*
X140893Y-667090D01*
X142393Y-668090D01*
G01X159393Y-666757D02*
Y-680090D01*
G01Y-661424D02*
X158893Y-661090D01*
Y-660423D01*
X159393Y-660090D01*
X159893Y-660423D01*
Y-661090D01*
X159393Y-661424D01*
G01X179393Y-680090D02*
X177893Y-679757D01*
X176393Y-678424D01*
X175393Y-676090D01*
X174893Y-673424D01*
X175393Y-670757D01*
X176393Y-668423D01*
X177893Y-667090D01*
X179393Y-666757D01*
X180893Y-667090D01*
X182393Y-668423D01*
X183393Y-670757D01*
X183643Y-673424D01*
X183393Y-676090D01*
X182393Y-678424D01*
X180893Y-679757D01*
X179393Y-680090D01*
G01X195143D02*
Y-666757D01*
G01Y-670090D02*
X196143Y-668423D01*
X197643Y-667090D01*
X199643Y-666757D01*
X201393Y-667090D01*
X202893Y-668423D01*
X203643Y-670757D01*
Y-680090D01*
G01X77095Y-636077D02*
Y-616077D01*
X83095D01*
X85095Y-617077D01*
X86595Y-619410D01*
X87095Y-622077D01*
X86595Y-624744D01*
X85345Y-626744D01*
X83095Y-627744D01*
X77095D01*
G01X107595Y-617744D02*
X106095Y-616744D01*
X104345Y-616077D01*
X102345D01*
X100095Y-617077D01*
X98345Y-618744D01*
X97095Y-620744D01*
X96095Y-624077D01*
X95845Y-627077D01*
X96345Y-630077D01*
X97095Y-632077D01*
X98595Y-634077D01*
X100345Y-635410D01*
X102095Y-636077D01*
X103845D01*
X105595Y-635410D01*
X107095Y-634411D01*
X108345Y-633078D01*
G01X124095Y-625410D02*
X125095Y-624410D01*
X125845Y-622744D01*
X126345Y-620410D01*
X125845Y-618410D01*
X124845Y-617077D01*
X123095Y-616077D01*
X116345D01*
Y-636077D01*
X124595D01*
X126345Y-634744D01*
X127345Y-632744D01*
X127845Y-630410D01*
X127345Y-628077D01*
X125845Y-626077D01*
X124095Y-625410D01*
X116345D01*
G01X156345Y-636077D02*
Y-616077D01*
X167845Y-636077D01*
Y-616077D01*
G01X182095Y-636077D02*
X180595Y-635744D01*
X179095Y-634411D01*
X178095Y-632077D01*
X177595Y-629411D01*
X178095Y-626744D01*
X179095Y-624410D01*
X180595Y-623077D01*
X182095Y-622744D01*
X183595Y-623077D01*
X185095Y-624410D01*
X186095Y-626744D01*
X186345Y-629411D01*
X186095Y-632077D01*
X185095Y-634411D01*
X183595Y-635744D01*
X182095Y-636077D01*
G01X202095Y-636744D02*
X201595Y-636410D01*
Y-635744D01*
X202095Y-635410D01*
X202595Y-635744D01*
Y-636410D01*
X202095Y-636744D01*
G01X46305Y1324910D02*
Y1336272D01*
X44601Y1334000D01*
G01Y1324910D02*
X48009D01*
G01X57668Y1336272D02*
X56532Y1335893D01*
X55680Y1334946D01*
X55111Y1333810D01*
X54685Y1332295D01*
X54543Y1330591D01*
X54685Y1328887D01*
X55111Y1327372D01*
X55680Y1326235D01*
X56532Y1325289D01*
X57668Y1324910D01*
X58804Y1325289D01*
X59656Y1326235D01*
X60225Y1327372D01*
X60651Y1328887D01*
X60793Y1330591D01*
X60651Y1332295D01*
X60225Y1333810D01*
X59656Y1334946D01*
X58804Y1335893D01*
X57668Y1336272D01*
G01X85540Y-591863D02*
Y-566863D01*
X93730Y-587696D01*
X101920Y-566863D01*
Y-591863D01*
G01X118930D02*
X117040Y-591446D01*
X115150Y-589780D01*
X113890Y-586863D01*
X113260Y-583530D01*
X113890Y-580197D01*
X115150Y-577280D01*
X117040Y-575613D01*
X118930Y-575197D01*
X120820Y-575613D01*
X122710Y-577280D01*
X123970Y-580197D01*
X124285Y-583530D01*
X123970Y-586863D01*
X122710Y-589780D01*
X120820Y-591446D01*
X118930Y-591863D01*
G01X149800Y-566863D02*
Y-591863D01*
G01Y-588114D02*
X148540Y-590197D01*
X146650Y-591446D01*
X144445Y-591863D01*
X141925Y-591030D01*
X140035Y-588947D01*
X138775Y-586447D01*
X138460Y-583530D01*
X138775Y-580613D01*
X140035Y-578113D01*
X141925Y-576030D01*
X144445Y-575197D01*
X146650Y-575613D01*
X148225Y-576447D01*
X149800Y-578113D01*
G01X164605Y-580613D02*
X174685D01*
X173740Y-577696D01*
X172165Y-576030D01*
X169960Y-575197D01*
X167755Y-575613D01*
X165865Y-576863D01*
X164605Y-579780D01*
X163975Y-582280D01*
Y-584780D01*
X164605Y-587280D01*
X166180Y-589780D01*
X168070Y-591446D01*
X170275Y-591863D01*
X172480Y-591030D01*
X174685Y-588530D01*
G01X194530Y-591863D02*
Y-566863D01*
G01X266732Y-852846D02*
Y-841484D01*
X265028Y-843756D01*
G01Y-852846D02*
X268436D01*
G01X278095D02*
Y-841484D01*
X276391Y-843756D01*
G01Y-852846D02*
X279799D01*
G01X255274Y-760533D02*
X259684Y-785533D01*
X264724Y-760533D01*
X269764Y-785533D01*
X274174Y-760533D01*
G01X289924Y-768867D02*
Y-785533D01*
G01Y-762200D02*
X289294Y-761783D01*
Y-760950D01*
X289924Y-760533D01*
X290554Y-760950D01*
Y-761783D01*
X289924Y-762200D01*
G01X310399Y-782617D02*
X311974Y-784283D01*
X314179Y-785533D01*
X316069D01*
X317959Y-784700D01*
X319219Y-783450D01*
X319849Y-781784D01*
X319534Y-779283D01*
X318274Y-778033D01*
X312604Y-775534D01*
X311344Y-772616D01*
X311974Y-770533D01*
X313234Y-769283D01*
X315124Y-768867D01*
X317014Y-769283D01*
X318904Y-770533D01*
G01X340324Y-760533D02*
Y-785533D01*
G01X335914Y-768867D02*
X344734D01*
G01X361114Y-785533D02*
Y-768867D01*
G01Y-772199D02*
X362689Y-770533D01*
X364264Y-769283D01*
X366469Y-768867D01*
X368044Y-769283D01*
X369934Y-770533D01*
G01X390724Y-785533D02*
X388834Y-785116D01*
X386944Y-783450D01*
X385684Y-780533D01*
X385054Y-777200D01*
X385684Y-773867D01*
X386944Y-770950D01*
X388834Y-769283D01*
X390724Y-768867D01*
X392614Y-769283D01*
X394504Y-770950D01*
X395764Y-773867D01*
X396079Y-777200D01*
X395764Y-780533D01*
X394504Y-783450D01*
X392614Y-785116D01*
X390724Y-785533D01*
G01X410569D02*
Y-768867D01*
G01Y-773033D02*
X411829Y-770950D01*
X413719Y-769283D01*
X416239Y-768867D01*
X418444Y-769283D01*
X420334Y-770950D01*
X421279Y-773867D01*
Y-785533D01*
G01X473254Y-762617D02*
X471364Y-761366D01*
X469159Y-760533D01*
X466639D01*
X463804Y-761783D01*
X461599Y-763866D01*
X460024Y-766367D01*
X458764Y-770533D01*
X458449Y-774283D01*
X459079Y-778033D01*
X460024Y-780533D01*
X461914Y-783034D01*
X464119Y-784700D01*
X466324Y-785533D01*
X468529D01*
X470734Y-784700D01*
X472624Y-783450D01*
X474199Y-781784D01*
G01X491524Y-785533D02*
X489634Y-785116D01*
X487744Y-783450D01*
X486484Y-780533D01*
X485854Y-777200D01*
X486484Y-773867D01*
X487744Y-770950D01*
X489634Y-769283D01*
X491524Y-768867D01*
X493414Y-769283D01*
X495304Y-770950D01*
X496564Y-773867D01*
X496879Y-777200D01*
X496564Y-780533D01*
X495304Y-783450D01*
X493414Y-785116D01*
X491524Y-785533D01*
G01X512314D02*
Y-768867D01*
G01Y-772199D02*
X513889Y-770533D01*
X515464Y-769283D01*
X517669Y-768867D01*
X519244Y-769283D01*
X521134Y-770533D01*
G01X536254Y-793866D02*
Y-768867D01*
G01Y-772616D02*
X537829Y-770533D01*
X539404Y-769283D01*
X541924Y-768867D01*
X544129Y-769283D01*
X546334Y-771366D01*
X547279Y-774283D01*
X547594Y-777200D01*
X547279Y-780117D01*
X546334Y-783034D01*
X544444Y-784700D01*
X541924Y-785533D01*
X539719Y-785116D01*
X537514Y-783867D01*
X536254Y-782200D01*
G01X567124Y-785533D02*
X565234Y-785116D01*
X563344Y-783450D01*
X562084Y-780533D01*
X561454Y-777200D01*
X562084Y-773867D01*
X563344Y-770950D01*
X565234Y-769283D01*
X567124Y-768867D01*
X569014Y-769283D01*
X570904Y-770950D01*
X572164Y-773867D01*
X572479Y-777200D01*
X572164Y-780533D01*
X570904Y-783450D01*
X569014Y-785116D01*
X567124Y-785533D01*
G01X587914D02*
Y-768867D01*
G01Y-772199D02*
X589489Y-770533D01*
X591064Y-769283D01*
X593269Y-768867D01*
X594844Y-769283D01*
X596734Y-770533D01*
G01X623194Y-785533D02*
Y-768867D01*
G01Y-771783D02*
X621934Y-770117D01*
X620044Y-769283D01*
X617839Y-768867D01*
X615634Y-769700D01*
X613744Y-771366D01*
X612484Y-773867D01*
X611854Y-777200D01*
X612484Y-780533D01*
X613744Y-783034D01*
X615634Y-784700D01*
X617839Y-785533D01*
X620044Y-785116D01*
X621934Y-783867D01*
X623194Y-782200D01*
G01X642724Y-760533D02*
Y-785533D01*
G01X638314Y-768867D02*
X647134D01*
G01X667924D02*
Y-785533D01*
G01Y-762200D02*
X667294Y-761783D01*
Y-760950D01*
X667924Y-760533D01*
X668554Y-760950D01*
Y-761783D01*
X667924Y-762200D01*
G01X693124Y-785533D02*
X691234Y-785116D01*
X689344Y-783450D01*
X688084Y-780533D01*
X687454Y-777200D01*
X688084Y-773867D01*
X689344Y-770950D01*
X691234Y-769283D01*
X693124Y-768867D01*
X695014Y-769283D01*
X696904Y-770950D01*
X698164Y-773867D01*
X698479Y-777200D01*
X698164Y-780533D01*
X696904Y-783450D01*
X695014Y-785116D01*
X693124Y-785533D01*
G01X712969D02*
Y-768867D01*
G01Y-773033D02*
X714229Y-770950D01*
X716119Y-769283D01*
X718639Y-768867D01*
X720844Y-769283D01*
X722734Y-770950D01*
X723679Y-773867D01*
Y-785533D01*
G01X282615Y-574823D02*
X283875Y-573574D01*
X284820Y-571491D01*
X285450Y-568573D01*
X284820Y-566074D01*
X283560Y-564407D01*
X281355Y-563157D01*
X272850D01*
Y-588157D01*
X283245D01*
X285450Y-586491D01*
X286710Y-583990D01*
X287340Y-581074D01*
X286710Y-578158D01*
X284820Y-575657D01*
X282615Y-574823D01*
X272850D01*
G01X300885Y-588157D02*
Y-571491D01*
G01Y-574823D02*
X302460Y-573157D01*
X304035Y-571907D01*
X306240Y-571491D01*
X307815Y-571907D01*
X309705Y-573157D01*
G01X323880Y-595657D02*
X325770Y-596490D01*
X328290Y-595657D01*
X329865Y-593991D01*
X331125Y-591907D01*
X333015Y-585241D01*
X337110Y-571491D01*
G01X327030D02*
X333015Y-585241D01*
G01X360735Y-573574D02*
X358530Y-571907D01*
X356640Y-571491D01*
X354120Y-572324D01*
X352230Y-573990D01*
X350970Y-576907D01*
X350655Y-579824D01*
X350970Y-582741D01*
X352230Y-585241D01*
X354120Y-587324D01*
X356640Y-588157D01*
X358845Y-587324D01*
X360735Y-585658D01*
G01X376170Y-576907D02*
X386250D01*
X385305Y-573990D01*
X383730Y-572324D01*
X381525Y-571491D01*
X379320Y-571907D01*
X377430Y-573157D01*
X376170Y-576074D01*
X375540Y-578574D01*
Y-581074D01*
X376170Y-583574D01*
X377745Y-586074D01*
X379635Y-587740D01*
X381840Y-588157D01*
X384045Y-587324D01*
X386250Y-584824D01*
G01X438225Y-565241D02*
X436335Y-563990D01*
X434130Y-563157D01*
X431610D01*
X428775Y-564407D01*
X426570Y-566490D01*
X424995Y-568991D01*
X423735Y-573157D01*
X423420Y-576907D01*
X424050Y-580657D01*
X424995Y-583157D01*
X426885Y-585658D01*
X429090Y-587324D01*
X431295Y-588157D01*
X433500D01*
X435705Y-587324D01*
X437595Y-586074D01*
X439170Y-584408D01*
G01X462165Y-588157D02*
Y-571491D01*
G01Y-574407D02*
X460905Y-572741D01*
X459015Y-571907D01*
X456810Y-571491D01*
X454605Y-572324D01*
X452715Y-573990D01*
X451455Y-576491D01*
X450825Y-579824D01*
X451455Y-583157D01*
X452715Y-585658D01*
X454605Y-587324D01*
X456810Y-588157D01*
X459015Y-587740D01*
X460905Y-586491D01*
X462165Y-584824D01*
G01X476340Y-588157D02*
Y-571491D01*
G01Y-575657D02*
X477600Y-573574D01*
X479490Y-571907D01*
X482010Y-571491D01*
X484215Y-571907D01*
X486105Y-573574D01*
X487050Y-576491D01*
Y-588157D01*
G01X500280Y-595657D02*
X502170Y-596490D01*
X504690Y-595657D01*
X506265Y-593991D01*
X507525Y-591907D01*
X509415Y-585241D01*
X513510Y-571491D01*
G01X503430D02*
X509415Y-585241D01*
G01X532095Y-588157D02*
X530205Y-587740D01*
X528315Y-586074D01*
X527055Y-583157D01*
X526425Y-579824D01*
X527055Y-576491D01*
X528315Y-573574D01*
X530205Y-571907D01*
X532095Y-571491D01*
X533985Y-571907D01*
X535875Y-573574D01*
X537135Y-576491D01*
X537450Y-579824D01*
X537135Y-583157D01*
X535875Y-586074D01*
X533985Y-587740D01*
X532095Y-588157D01*
G01X551940D02*
Y-571491D01*
G01Y-575657D02*
X553200Y-573574D01*
X555090Y-571907D01*
X557610Y-571491D01*
X559815Y-571907D01*
X561705Y-573574D01*
X562650Y-576491D01*
Y-588157D01*
G01X603915Y-563157D02*
X611474D01*
G01X607695D02*
Y-588157D01*
G01X603915D02*
X611474D01*
G01X632895D02*
X630375Y-587740D01*
X628170Y-586074D01*
X626280Y-583574D01*
X625020Y-580657D01*
X624390Y-577324D01*
Y-573990D01*
X625020Y-570657D01*
X626280Y-567740D01*
X628170Y-565241D01*
X630375Y-563574D01*
X632895Y-563157D01*
X635415Y-563574D01*
X637620Y-565241D01*
X639510Y-567740D01*
X640770Y-570657D01*
X641400Y-573990D01*
Y-577324D01*
X640770Y-580657D01*
X639510Y-583574D01*
X637620Y-586074D01*
X635415Y-587740D01*
X632895Y-588157D01*
G01X649905D02*
Y-563157D01*
X658095Y-583990D01*
X666285Y-563157D01*
Y-588157D01*
G01X706920Y-596490D02*
X703770Y-592324D01*
X702195Y-588157D01*
Y-571491D01*
X703770Y-567324D01*
X706920Y-563157D01*
G01X725820Y-571491D02*
X729600Y-588157D01*
X733695Y-571491D01*
X737790Y-588157D01*
X741570Y-571491D01*
G01X753225Y-588990D02*
X764565Y-563157D01*
G01X805515D02*
X813074D01*
G01X809295D02*
Y-588157D01*
G01X805515D02*
X813074D01*
G01X834495D02*
X831975Y-587740D01*
X829770Y-586074D01*
X827880Y-583574D01*
X826620Y-580657D01*
X825990Y-577324D01*
Y-573990D01*
X826620Y-570657D01*
X827880Y-567740D01*
X829770Y-565241D01*
X831975Y-563574D01*
X834495Y-563157D01*
X837015Y-563574D01*
X839220Y-565241D01*
X841110Y-567740D01*
X842370Y-570657D01*
X843000Y-573990D01*
Y-577324D01*
X842370Y-580657D01*
X841110Y-583574D01*
X839220Y-586074D01*
X837015Y-587740D01*
X834495Y-588157D01*
G01X866625Y-565241D02*
X864735Y-563990D01*
X862530Y-563157D01*
X860010D01*
X857175Y-564407D01*
X854970Y-566490D01*
X853395Y-568991D01*
X852135Y-573157D01*
X851820Y-576907D01*
X852450Y-580657D01*
X853395Y-583157D01*
X855285Y-585658D01*
X857490Y-587324D01*
X859695Y-588157D01*
X861900D01*
X864105Y-587324D01*
X865995Y-586074D01*
X867570Y-584408D01*
G01X886470Y-596490D02*
X889620Y-592324D01*
X891195Y-588157D01*
Y-571491D01*
X889620Y-567324D01*
X886470Y-563157D01*
G01X266732Y1324910D02*
Y1336272D01*
X265028Y1334000D01*
G01Y1324910D02*
X268436D01*
G01X278095D02*
Y1336272D01*
X276391Y1334000D01*
G01Y1324910D02*
X279799D01*
G01X284549Y-727023D02*
X282549Y-726690D01*
X280799Y-725357D01*
X279299Y-723357D01*
X278299Y-721023D01*
X277799Y-718356D01*
Y-715690D01*
X278299Y-713023D01*
X279299Y-710689D01*
X280799Y-708690D01*
X282549Y-707356D01*
X284549Y-707023D01*
X286549Y-707356D01*
X288299Y-708690D01*
X289799Y-710689D01*
X290799Y-713023D01*
X291299Y-715690D01*
Y-718356D01*
X290799Y-721023D01*
X289799Y-723357D01*
X288299Y-725357D01*
X286549Y-726690D01*
X284549Y-727023D01*
G01X286549Y-721690D02*
X289549Y-727023D01*
G01X300299Y-713690D02*
Y-723023D01*
X301299Y-725357D01*
X302799Y-726690D01*
X304549Y-727023D01*
X306299Y-726690D01*
X307799Y-725357D01*
X308799Y-723023D01*
G01Y-727023D02*
Y-713690D01*
G01X324549D02*
Y-727023D01*
G01Y-708357D02*
X324049Y-708023D01*
Y-707356D01*
X324549Y-707023D01*
X325049Y-707356D01*
Y-708023D01*
X324549Y-708357D01*
G01X340299Y-727023D02*
Y-713690D01*
G01Y-717023D02*
X341299Y-715356D01*
X342799Y-714023D01*
X344799Y-713690D01*
X346549Y-714023D01*
X348049Y-715356D01*
X348799Y-717690D01*
Y-727023D01*
G01X368549Y-715356D02*
X366799Y-714023D01*
X365299Y-713690D01*
X363299Y-714357D01*
X361799Y-715690D01*
X360799Y-718023D01*
X360549Y-720357D01*
X360799Y-722690D01*
X361799Y-724690D01*
X363299Y-726356D01*
X365299Y-727023D01*
X367049Y-726356D01*
X368549Y-725023D01*
G01X379299Y-733023D02*
X380799Y-733689D01*
X382799Y-733023D01*
X384049Y-731690D01*
X385049Y-730023D01*
X386549Y-724690D01*
X389799Y-713690D01*
G01X381799D02*
X386549Y-724690D01*
G01X304326Y-684984D02*
Y-664984D01*
X301326Y-668984D01*
G01Y-684984D02*
X307326D01*
G01X290296Y-634102D02*
Y-614102D01*
X287296Y-618102D01*
G01Y-634102D02*
X293296D01*
G01X305546Y-625769D02*
X307296Y-623435D01*
X308796Y-622102D01*
X310796Y-621436D01*
X312546Y-622102D01*
X313796Y-623435D01*
X314796Y-625435D01*
X315046Y-627769D01*
X314796Y-629769D01*
X313796Y-631769D01*
X312296Y-633435D01*
X310546Y-634102D01*
X308546Y-633435D01*
X306796Y-631436D01*
X305796Y-628435D01*
X305546Y-625102D01*
X306046Y-620769D01*
X306796Y-618435D01*
X308046Y-616102D01*
X309796Y-614435D01*
X311546Y-614102D01*
X313296Y-614769D01*
X314546Y-616435D01*
G01X324796Y-630102D02*
X326296Y-632436D01*
X328296Y-633769D01*
X330546Y-634102D01*
X332546Y-633769D01*
X334546Y-632102D01*
X335796Y-630102D01*
X336046Y-628102D01*
X335546Y-625769D01*
X333796Y-624102D01*
X332046Y-623435D01*
X329796D01*
G01X332046D02*
X333546Y-622435D01*
X334796Y-620769D01*
X335296Y-618769D01*
X334796Y-616769D01*
X333546Y-615102D01*
X331296Y-614102D01*
X329046Y-614435D01*
X326796Y-615769D01*
G01X350296Y-634102D02*
Y-614102D01*
X347296Y-618102D01*
G01Y-634102D02*
X353296D01*
G01X370296D02*
X372046Y-633769D01*
X374046Y-632769D01*
X375296Y-631103D01*
X375796Y-628769D01*
X375296Y-626436D01*
X373796Y-624436D01*
X371546Y-623435D01*
X369046D01*
X367546Y-622769D01*
X366296Y-621102D01*
X365796Y-618769D01*
X366546Y-616435D01*
X368296Y-614769D01*
X370296Y-614102D01*
X372296Y-614769D01*
X374046Y-616435D01*
X374796Y-618769D01*
X374296Y-621102D01*
X373046Y-622769D01*
X371546Y-623435D01*
X369046D01*
X366796Y-624436D01*
X365296Y-626436D01*
X364796Y-628769D01*
X365296Y-631103D01*
X366546Y-632769D01*
X368546Y-633769D01*
X370296Y-634102D01*
G01X312509Y587316D02*
Y571716D01*
G01X308024Y587316D02*
X316994D01*
G01X484507Y-852846D02*
Y-841484D01*
X482803Y-843756D01*
G01Y-852846D02*
X486211D01*
G01X493171Y-843378D02*
X494024Y-842242D01*
X495018Y-841673D01*
X496154Y-841484D01*
X497574Y-841863D01*
X498569Y-842810D01*
X498853Y-843946D01*
X498711Y-845082D01*
X498142Y-846029D01*
X495302Y-847922D01*
X494024Y-849248D01*
X493171Y-851142D01*
X492887Y-852846D01*
X498853D01*
G01X484507Y1324910D02*
Y1336272D01*
X482803Y1334000D01*
G01Y1324910D02*
X486211D01*
G01X493171Y1334378D02*
X494024Y1335514D01*
X495018Y1336083D01*
X496154Y1336272D01*
X497574Y1335893D01*
X498569Y1334946D01*
X498853Y1333810D01*
X498711Y1332674D01*
X498142Y1331727D01*
X495302Y1329834D01*
X494024Y1328508D01*
X493171Y1326614D01*
X492887Y1324910D01*
X498853D01*
G01X602759Y-660290D02*
Y-680290D01*
G01X597009Y-660290D02*
X608509D01*
G01X618509Y-680290D02*
Y-660290D01*
G01Y-669956D02*
X619759Y-668290D01*
X621009Y-667290D01*
X623009Y-666957D01*
X624509Y-667290D01*
X626259Y-668623D01*
X627009Y-670624D01*
Y-680290D01*
G01X642759Y-666957D02*
Y-680290D01*
G01Y-661624D02*
X642259Y-661290D01*
Y-660623D01*
X642759Y-660290D01*
X643259Y-660623D01*
Y-661290D01*
X642759Y-661624D01*
G01X666759Y-668623D02*
X665009Y-667290D01*
X663509Y-666957D01*
X661509Y-667624D01*
X660009Y-668957D01*
X659009Y-671290D01*
X658759Y-673624D01*
X659009Y-675957D01*
X660009Y-677957D01*
X661509Y-679623D01*
X663509Y-680290D01*
X665259Y-679623D01*
X666759Y-678290D01*
G01X678509Y-680290D02*
Y-660290D01*
G01X686509Y-666957D02*
X678509Y-674623D01*
G01X681759Y-671623D02*
X687009Y-680290D01*
G01X698509D02*
Y-666957D01*
G01Y-670290D02*
X699509Y-668623D01*
X701009Y-667290D01*
X703009Y-666957D01*
X704759Y-667290D01*
X706259Y-668623D01*
X707009Y-670957D01*
Y-680290D01*
G01X719009Y-671290D02*
X727009D01*
X726259Y-668957D01*
X725009Y-667624D01*
X723259Y-666957D01*
X721509Y-667290D01*
X720009Y-668290D01*
X719009Y-670624D01*
X718509Y-672624D01*
Y-674623D01*
X719009Y-676624D01*
X720259Y-678624D01*
X721759Y-679957D01*
X723509Y-680290D01*
X725259Y-679623D01*
X727009Y-677624D01*
G01X739009Y-677957D02*
X740259Y-679290D01*
X742009Y-680290D01*
X743509D01*
X745009Y-679623D01*
X746009Y-678624D01*
X746509Y-677291D01*
X746259Y-675290D01*
X745259Y-674290D01*
X740759Y-672290D01*
X739759Y-669956D01*
X740259Y-668290D01*
X741259Y-667290D01*
X742759Y-666957D01*
X744259Y-667290D01*
X745759Y-668290D01*
G01X759009Y-677957D02*
X760259Y-679290D01*
X762009Y-680290D01*
X763509D01*
X765009Y-679623D01*
X766009Y-678624D01*
X766509Y-677291D01*
X766259Y-675290D01*
X765259Y-674290D01*
X760759Y-672290D01*
X759759Y-669956D01*
X760259Y-668290D01*
X761259Y-667290D01*
X762759Y-666957D01*
X764259Y-667290D01*
X765759Y-668290D01*
G01X639832Y-728998D02*
Y-708998D01*
X644832D01*
X646832Y-709998D01*
X648332Y-711331D01*
X649582Y-713331D01*
X650582Y-715665D01*
X650832Y-718998D01*
X650582Y-722332D01*
X649582Y-724665D01*
X648332Y-726665D01*
X646832Y-727998D01*
X644832Y-728998D01*
X639832D01*
G01X669832D02*
Y-715665D01*
G01Y-717998D02*
X668832Y-716665D01*
X667332Y-715998D01*
X665582Y-715665D01*
X663832Y-716332D01*
X662332Y-717665D01*
X661332Y-719665D01*
X660832Y-722332D01*
X661332Y-724998D01*
X662332Y-726998D01*
X663832Y-728331D01*
X665582Y-728998D01*
X667332Y-728665D01*
X668832Y-727665D01*
X669832Y-726332D01*
G01X685332Y-708998D02*
Y-728998D01*
G01X681832Y-715665D02*
X688832D01*
G01X701582Y-719998D02*
X709582D01*
X708832Y-717665D01*
X707582Y-716332D01*
X705832Y-715665D01*
X704082Y-715998D01*
X702582Y-716998D01*
X701582Y-719332D01*
X701082Y-721332D01*
Y-723331D01*
X701582Y-725332D01*
X702832Y-727332D01*
X704332Y-728665D01*
X706082Y-728998D01*
X707832Y-728331D01*
X709582Y-726332D01*
G01X704177Y-852846D02*
Y-841484D01*
X702473Y-843756D01*
G01Y-852846D02*
X705881D01*
G01X712415Y-850574D02*
X713267Y-851899D01*
X714404Y-852657D01*
X715682Y-852846D01*
X716818Y-852657D01*
X717955Y-851710D01*
X718665Y-850574D01*
X718807Y-849437D01*
X718523Y-848112D01*
X717528Y-847165D01*
X716534Y-846786D01*
X715256D01*
G01X716534D02*
X717386Y-846218D01*
X718097Y-845272D01*
X718381Y-844135D01*
X718097Y-842999D01*
X717386Y-842052D01*
X716108Y-841484D01*
X714830Y-841673D01*
X713552Y-842431D01*
G01X704177Y1324910D02*
Y1336272D01*
X702473Y1334000D01*
G01Y1324910D02*
X705881D01*
G01X712415Y1327182D02*
X713267Y1325857D01*
X714404Y1325099D01*
X715682Y1324910D01*
X716818Y1325099D01*
X717955Y1326046D01*
X718665Y1327182D01*
X718807Y1328319D01*
X718523Y1329644D01*
X717528Y1330591D01*
X716534Y1330970D01*
X715256D01*
G01X716534D02*
X717386Y1331538D01*
X718097Y1332484D01*
X718381Y1333621D01*
X718097Y1334757D01*
X717386Y1335704D01*
X716108Y1336272D01*
X714830Y1336083D01*
X713552Y1335325D01*
G01X786250Y-710833D02*
X787750Y-708834D01*
X789500Y-707833D01*
X791500Y-707500D01*
X794000Y-708167D01*
X795750Y-709833D01*
X796250Y-711833D01*
X796000Y-713834D01*
X795000Y-715500D01*
X790000Y-718833D01*
X787750Y-721167D01*
X786250Y-724501D01*
X785750Y-727500D01*
X796250D01*
G01X811000Y-707500D02*
X809000Y-708167D01*
X807500Y-709833D01*
X806500Y-711833D01*
X805750Y-714500D01*
X805500Y-717500D01*
X805750Y-720500D01*
X806500Y-723167D01*
X807500Y-725167D01*
X809000Y-726833D01*
X811000Y-727500D01*
X813000Y-726833D01*
X814500Y-725167D01*
X815500Y-723167D01*
X816250Y-720500D01*
X816500Y-717500D01*
X816250Y-714500D01*
X815500Y-711833D01*
X814500Y-709833D01*
X813000Y-708167D01*
X811000Y-707500D01*
G01X831000Y-727500D02*
Y-707500D01*
X828000Y-711500D01*
G01Y-727500D02*
X834000D01*
G01X850500D02*
X851000Y-723167D01*
X851750Y-719500D01*
X852750Y-716167D01*
X854000Y-712500D01*
X856000Y-707500D01*
X846000D01*
G01X866500Y-728167D02*
X875500Y-707500D01*
G01X891000D02*
X889000Y-708167D01*
X887500Y-709833D01*
X886500Y-711833D01*
X885750Y-714500D01*
X885500Y-717500D01*
X885750Y-720500D01*
X886500Y-723167D01*
X887500Y-725167D01*
X889000Y-726833D01*
X891000Y-727500D01*
X893000Y-726833D01*
X894500Y-725167D01*
X895500Y-723167D01*
X896250Y-720500D01*
X896500Y-717500D01*
X896250Y-714500D01*
X895500Y-711833D01*
X894500Y-709833D01*
X893000Y-708167D01*
X891000Y-707500D01*
G01X906250Y-719167D02*
X908000Y-716833D01*
X909500Y-715500D01*
X911500Y-714834D01*
X913250Y-715500D01*
X914500Y-716833D01*
X915500Y-718833D01*
X915750Y-721167D01*
X915500Y-723167D01*
X914500Y-725167D01*
X913000Y-726833D01*
X911250Y-727500D01*
X909250Y-726833D01*
X907500Y-724834D01*
X906500Y-721833D01*
X906250Y-718500D01*
X906750Y-714167D01*
X907500Y-711833D01*
X908750Y-709500D01*
X910500Y-707833D01*
X912250Y-707500D01*
X914000Y-708167D01*
X915250Y-709833D01*
G01X926500Y-728167D02*
X935500Y-707500D01*
G01X951000D02*
X949000Y-708167D01*
X947500Y-709833D01*
X946500Y-711833D01*
X945750Y-714500D01*
X945500Y-717500D01*
X945750Y-720500D01*
X946500Y-723167D01*
X947500Y-725167D01*
X949000Y-726833D01*
X951000Y-727500D01*
X953000Y-726833D01*
X954500Y-725167D01*
X955500Y-723167D01*
X956250Y-720500D01*
X956500Y-717500D01*
X956250Y-714500D01*
X955500Y-711833D01*
X954500Y-709833D01*
X953000Y-708167D01*
X951000Y-707500D01*
G01X966250Y-719167D02*
X968000Y-716833D01*
X969500Y-715500D01*
X971500Y-714834D01*
X973250Y-715500D01*
X974500Y-716833D01*
X975500Y-718833D01*
X975750Y-721167D01*
X975500Y-723167D01*
X974500Y-725167D01*
X973000Y-726833D01*
X971250Y-727500D01*
X969250Y-726833D01*
X967500Y-724834D01*
X966500Y-721833D01*
X966250Y-718500D01*
X966750Y-714167D01*
X967500Y-711833D01*
X968750Y-709500D01*
X970500Y-707833D01*
X972250Y-707500D01*
X974000Y-708167D01*
X975250Y-709833D01*
G01X820645Y-678315D02*
Y-658315D01*
X817645Y-662315D01*
G01Y-678315D02*
X823645D01*
G01X840645Y-678982D02*
X840145Y-678648D01*
Y-677982D01*
X840645Y-677648D01*
X841145Y-677982D01*
Y-678648D01*
X840645Y-678982D01*
G01X855895Y-669982D02*
X857645Y-667648D01*
X859145Y-666315D01*
X861145Y-665649D01*
X862895Y-666315D01*
X864145Y-667648D01*
X865145Y-669648D01*
X865395Y-671982D01*
X865145Y-673982D01*
X864145Y-675982D01*
X862645Y-677648D01*
X860895Y-678315D01*
X858895Y-677648D01*
X857145Y-675649D01*
X856145Y-672648D01*
X855895Y-669315D01*
X856395Y-664982D01*
X857145Y-662648D01*
X858395Y-660315D01*
X860145Y-658648D01*
X861895Y-658315D01*
X863645Y-658982D01*
X864895Y-660648D01*
G01X873145Y-678315D02*
Y-664982D01*
G01Y-668649D02*
X873895Y-666982D01*
X875145Y-665649D01*
X876895Y-664982D01*
X878645Y-665649D01*
X879895Y-666982D01*
X880645Y-668649D01*
Y-678315D01*
G01Y-668649D02*
X881395Y-666982D01*
X882645Y-665649D01*
X884395Y-664982D01*
X886145Y-665649D01*
X887395Y-666982D01*
X888145Y-668982D01*
Y-678315D01*
G01X893145D02*
Y-664982D01*
G01Y-668649D02*
X893895Y-666982D01*
X895145Y-665649D01*
X896895Y-664982D01*
X898645Y-665649D01*
X899895Y-666982D01*
X900645Y-668649D01*
Y-678315D01*
G01Y-668649D02*
X901395Y-666982D01*
X902645Y-665649D01*
X904395Y-664982D01*
X906145Y-665649D01*
X907395Y-666982D01*
X908145Y-668982D01*
Y-678315D01*
G01X923846Y-852846D02*
Y-841484D01*
X922142Y-843756D01*
G01Y-852846D02*
X925550D01*
G01X936913D02*
Y-841484D01*
X931658Y-849627D01*
X938760D01*
G01X922572Y794685D02*
X921785Y795275D01*
X921391Y795964D01*
X921260Y796752D01*
X921522Y797736D01*
X922179Y798425D01*
X922966Y798622D01*
X923754Y798524D01*
X924410Y798130D01*
X925722Y796161D01*
X926641Y795275D01*
X927953Y794685D01*
X929134Y794488D01*
Y798622D01*
G01X927559Y802264D02*
X928478Y802855D01*
X929003Y803642D01*
X929134Y804529D01*
X929003Y805316D01*
X928347Y806103D01*
X927559Y806596D01*
X926772Y806694D01*
X925853Y806497D01*
X925197Y805808D01*
X924934Y805119D01*
Y804233D01*
G01Y805119D02*
X924541Y805710D01*
X923885Y806202D01*
X923097Y806399D01*
X922310Y806202D01*
X921654Y805710D01*
X921260Y804824D01*
X921391Y803938D01*
X921916Y803052D01*
G01X927953Y810139D02*
X928609Y810730D01*
X929003Y811419D01*
X929134Y812305D01*
X928872Y813191D01*
X928347Y813880D01*
X927428Y814372D01*
X926378Y814471D01*
X925328Y814274D01*
X924672Y813781D01*
X924147Y813092D01*
X924016Y812404D01*
X924147Y811714D01*
X924672Y810829D01*
X921260Y811124D01*
Y813781D01*
G01X929396Y820180D02*
X929265Y819983D01*
X929003D01*
X928872Y820180D01*
X929003Y820377D01*
X929265D01*
X929396Y820180D01*
G01X921260Y828055D02*
X921522Y827267D01*
X922179Y826677D01*
X922966Y826283D01*
X924016Y825988D01*
X925197Y825889D01*
X926378Y825988D01*
X927428Y826283D01*
X928216Y826677D01*
X928872Y827267D01*
X929134Y828055D01*
X928872Y828842D01*
X928216Y829433D01*
X927428Y829827D01*
X926378Y830122D01*
X925197Y830221D01*
X924016Y830122D01*
X922966Y829827D01*
X922179Y829433D01*
X921522Y828842D01*
X921260Y828055D01*
G01Y835930D02*
X921522Y835142D01*
X922179Y834552D01*
X922966Y834158D01*
X924016Y833863D01*
X925197Y833764D01*
X926378Y833863D01*
X927428Y834158D01*
X928216Y834552D01*
X928872Y835142D01*
X929134Y835930D01*
X928872Y836717D01*
X928216Y837308D01*
X927428Y837702D01*
X926378Y837997D01*
X925197Y838096D01*
X924016Y837997D01*
X922966Y837702D01*
X922179Y837308D01*
X921522Y836717D01*
X921260Y835930D01*
G01X923846Y1324910D02*
Y1336272D01*
X922142Y1334000D01*
G01Y1324910D02*
X925550D01*
G01X936913D02*
Y1336272D01*
X931658Y1328129D01*
X938760D01*
G01X1049587Y-733164D02*
X1050298Y-734300D01*
X1051150Y-735057D01*
X1052144Y-735436D01*
X1053280Y-735057D01*
X1054132Y-734300D01*
X1054985Y-733164D01*
X1055269Y-731649D01*
Y-724074D01*
G01X1050724Y-508192D02*
X1054132D01*
G01X1052428D02*
Y-519554D01*
G01X1050724D02*
X1054132D01*
G01X1049445Y-303862D02*
Y-292500D01*
G01X1055411D02*
Y-303862D01*
G01Y-298181D02*
X1049445D01*
G01X1053280Y-82299D02*
X1056121D01*
Y-85708D01*
X1055269Y-86844D01*
X1054274Y-87601D01*
X1052854Y-87980D01*
X1051434Y-87601D01*
X1050440Y-86844D01*
X1049587Y-85708D01*
X1049019Y-84382D01*
X1048735Y-82867D01*
Y-81542D01*
X1049019Y-80406D01*
X1049587Y-79080D01*
X1050440Y-77944D01*
X1051292Y-77186D01*
X1052428Y-76618D01*
X1053422D01*
X1054558Y-76997D01*
X1055411Y-77754D01*
G01X1049350Y128092D02*
Y139454D01*
X1054748D01*
G01X1052759Y133962D02*
X1049350D01*
G01X1055269Y344163D02*
X1049587D01*
Y355525D01*
X1055269D01*
G01X1052996Y350033D02*
X1049587D01*
G01X1049303Y559855D02*
Y571217D01*
X1052144D01*
X1053280Y570649D01*
X1054132Y569891D01*
X1054843Y568755D01*
X1055411Y567429D01*
X1055553Y565536D01*
X1055411Y563642D01*
X1054843Y562317D01*
X1054132Y561180D01*
X1053280Y560423D01*
X1052144Y559855D01*
X1049303D01*
G01X1055553Y786342D02*
X1054700Y786910D01*
X1053706Y787289D01*
X1052570D01*
X1051292Y786721D01*
X1050298Y785774D01*
X1049587Y784638D01*
X1049019Y782744D01*
X1048877Y781040D01*
X1049161Y779336D01*
X1049587Y778199D01*
X1050440Y777063D01*
X1051434Y776306D01*
X1052428Y775927D01*
X1053422D01*
X1054416Y776306D01*
X1055269Y776874D01*
X1055979Y777631D01*
G01X1053564Y997679D02*
X1054132Y998247D01*
X1054558Y999193D01*
X1054843Y1000519D01*
X1054558Y1001655D01*
X1053990Y1002413D01*
X1052996Y1002981D01*
X1049161D01*
Y991619D01*
X1053848D01*
X1054843Y992376D01*
X1055411Y993513D01*
X1055695Y994838D01*
X1055411Y996164D01*
X1054558Y997300D01*
X1053564Y997679D01*
X1049161D01*
G01X1048877Y1207501D02*
X1052428Y1218863D01*
X1055979Y1207501D01*
G01X1054700Y1211478D02*
X1050155D01*
G01X-2062994Y-856633D02*
Y1340060D01*
G01X1061612Y-856633D02*
X-2062994D01*
G01X-2044057Y-837696D02*
Y1321123D01*
G01X1042675Y-837696D02*
X-2044057D01*
G01X-2062994Y-621814D02*
X-2044057D01*
G01X-2062994Y-405932D02*
X-2044057D01*
G01X-2062994D02*
X-2044057D01*
G01X-2062994Y-190050D02*
X-2044057D01*
G01X-2062994D02*
X-2044057D01*
G01X-2062994Y25832D02*
X-2044057D01*
G01X-2062994D02*
X-2044057D01*
G01X-2062994Y241714D02*
X-2044057D01*
G01X-2062994D02*
X-2044057D01*
G01X-2062994D02*
X-2044057D01*
G01X-2062994Y457595D02*
X-2044057D01*
G01X-2062994D02*
X-2044057D01*
G01X-2062994Y673477D02*
X-2044057D01*
G01X-2062994D02*
X-2044057D01*
G01X-2062994Y889359D02*
X-2044057D01*
G01X-2062994D02*
X-2044057D01*
G01X-2062994Y1105241D02*
X-2044057D01*
G01X-2062994Y1340060D02*
X1061612D01*
G01X-2044057Y1321123D02*
X1042675D01*
G01X-1659414Y976994D02*
X-1992301D01*
G01X-1722025Y1183136D02*
X-1996592D01*
G01X-1818706Y-837696D02*
Y-856633D01*
G01X-1725385Y-655061D02*
X-1760424D01*
G01X-1670915Y1029155D02*
X-1769944D01*
G01X-1681862Y1085494D02*
X-1780891D01*
G01X-1818706Y1340060D02*
Y1321123D01*
G01X-1725385Y-655061D02*
Y-690100D01*
G01X-1705700Y107877D02*
Y-655061D01*
G01X-1721448D02*
X-1609125D01*
G01X-1721448D02*
X-1705700D01*
G01X-1725385Y-651124D02*
G03X-1721448Y-655061I3937J0D01*
G01X-1725385Y-651124D02*
G03X-1721448Y-655061I3937J0D01*
G01X-1725385Y68419D02*
Y-651124D01*
G01Y68419D02*
Y-651124D01*
G01X-1717615Y-171357D02*
Y-172608D01*
G01Y-173859D02*
Y-174859D01*
G01Y-177861D02*
Y-178862D01*
G01Y-182615D02*
Y-183865D01*
G01Y-185116D02*
Y-186117D01*
G01Y-189119D02*
Y-190120D01*
G01X-1716593Y-189619D02*
Y-188869D01*
G01Y-185617D02*
Y-185116D01*
G01Y-178362D02*
Y-177611D01*
G01Y-174359D02*
Y-173859D01*
G01X-1709440Y-191871D02*
Y-190620D01*
G01Y-187868D02*
Y-186617D01*
G01Y-183865D02*
Y-182615D01*
G01Y-180613D02*
Y-179363D01*
G01Y-176611D02*
Y-175360D01*
G01Y-172608D02*
Y-171357D01*
G01X-1717360Y-173108D02*
X-1717615Y-173859D01*
G01X-1716593D02*
X-1716338Y-173108D01*
G01X-1717360Y-177111D02*
X-1717615Y-177861D01*
G01X-1717360Y-184366D02*
X-1717615Y-185116D01*
G01X-1716593D02*
X-1716338Y-184366D01*
G01X-1717360Y-188369D02*
X-1717615Y-189119D01*
G01X-1716593Y-177611D02*
X-1716338Y-177111D01*
G01X-1716593Y-188869D02*
X-1716338Y-188369D01*
G01X-1717615Y-190120D02*
X-1717360Y-190870D01*
G01X-1717615Y-186117D02*
X-1717360Y-186867D01*
G01X-1717615Y-178862D02*
X-1717360Y-179613D01*
G01X-1717615Y-174859D02*
X-1717360Y-175610D01*
G01X-1716849Y-172608D02*
X-1717360Y-173108D01*
G01X-1716338D02*
X-1715827Y-172608D01*
G01X-1716593Y-176361D02*
X-1717360Y-177111D01*
G01X-1716338D02*
X-1716082Y-176861D01*
G01X-1716849Y-183865D02*
X-1717360Y-184366D01*
G01X-1716338D02*
X-1715827Y-183865D01*
G01X-1716593Y-187618D02*
X-1717360Y-188369D01*
G01X-1716338D02*
X-1716082Y-188118D01*
G01X-1716338Y-190120D02*
X-1716593Y-189619D01*
G01X-1716338Y-186117D02*
X-1716593Y-185617D01*
G01X-1716338Y-178862D02*
X-1716593Y-178362D01*
G01X-1716338Y-174859D02*
X-1716593Y-174359D01*
G01X-1716082Y-176861D02*
X-1715571Y-176611D01*
G01X-1716082Y-188118D02*
X-1715571Y-187868D01*
G01X-1717360Y-190870D02*
X-1716849Y-191370D01*
G01X-1716082Y-190370D02*
X-1716338Y-190120D01*
G01X-1717360Y-186867D02*
X-1716593Y-187618D01*
G01X-1716082Y-186367D02*
X-1716338Y-186117D01*
G01X-1717360Y-179613D02*
X-1716849Y-180113D01*
G01X-1716082Y-179112D02*
X-1716338Y-178862D01*
G01X-1717360Y-175610D02*
X-1716593Y-176361D01*
G01X-1716082Y-175110D02*
X-1716338Y-174859D01*
G01X-1715571Y-190620D02*
X-1716082Y-190370D01*
G01X-1715571Y-186617D02*
X-1716082Y-186367D01*
G01X-1715571Y-179363D02*
X-1716082Y-179112D01*
G01X-1716849Y-191370D02*
X-1715571Y-191871D01*
G01X-1716849Y-180113D02*
X-1715571Y-180613D01*
G01Y-175360D02*
X-1716082Y-175110D01*
G01X-1715571Y-191871D02*
X-1709440D01*
G01Y-190620D02*
X-1715571D01*
G01Y-187868D02*
X-1709440D01*
G01Y-186617D02*
X-1715571D01*
G01X-1717615Y-183865D02*
X-1716849D01*
G01X-1715827D02*
X-1709440D01*
G01Y-182615D02*
X-1717615D01*
G01X-1715571Y-180613D02*
X-1709440D01*
G01Y-179363D02*
X-1715571D01*
G01Y-176611D02*
X-1709440D01*
G01Y-175360D02*
X-1715571D01*
G01X-1717615Y-172608D02*
X-1716849D01*
G01X-1715827D02*
X-1709440D01*
G01Y-171357D02*
X-1717615D01*
G01X-1721448Y-142338D02*
Y-143839D01*
G01Y-150844D02*
Y-152345D01*
G01X-1717615Y-154346D02*
Y-158349D01*
G01X-1716593Y-143839D02*
Y-150844D01*
G01Y-158349D02*
Y-154346D01*
G01X-1715060Y-150844D02*
Y-143839D01*
G01X-1714550Y-154346D02*
Y-158349D01*
G01X-1713528D02*
Y-154346D01*
G01X-1709440Y-152345D02*
Y-150844D01*
G01Y-143839D02*
Y-142338D01*
G01X-1721448Y-164853D02*
X-1721192Y-163352D01*
G01X-1709440Y-164853D02*
X-1709695Y-166354D01*
G01X-1720170Y-164853D02*
X-1719915Y-163602D01*
G01X-1710717Y-164853D02*
X-1710972Y-166104D01*
G01X-1721192Y-163352D02*
X-1720426Y-162101D01*
G01X-1709695Y-166354D02*
X-1710462Y-167605D01*
G01X-1719915Y-163602D02*
X-1719403Y-162852D01*
G01X-1710972Y-166104D02*
X-1711483Y-166854D01*
G01X-1720426Y-162101D02*
X-1719659Y-161351D01*
G01X-1719915Y-166104D02*
X-1720170Y-164853D01*
G01X-1710972Y-163602D02*
X-1710717Y-164853D01*
G01X-1721192Y-166354D02*
X-1721448Y-164853D01*
G01X-1709695Y-163352D02*
X-1709440Y-164853D01*
G01X-1710462Y-167605D02*
X-1711228Y-168355D01*
G01X-1719403Y-162852D02*
X-1717871Y-161851D01*
G01X-1711483Y-166854D02*
X-1713016Y-167855D01*
G01X-1719403Y-166854D02*
X-1719915Y-166104D01*
G01X-1720426Y-167605D02*
X-1721192Y-166354D01*
G01X-1710462Y-162101D02*
X-1709695Y-163352D01*
G01X-1719659Y-161351D02*
X-1718637Y-160850D01*
G01X-1711228Y-168355D02*
X-1712250Y-168856D01*
G01X-1711483Y-162852D02*
X-1710972Y-163602D01*
G01X-1718637Y-160850D02*
X-1717871Y-160600D01*
G01X-1712250Y-168856D02*
X-1713016Y-169106D01*
G01X-1719659Y-168355D02*
X-1720426Y-167605D01*
G01X-1711228Y-161351D02*
X-1710462Y-162101D01*
G01X-1717871Y-167855D02*
X-1719403Y-166854D01*
G01X-1713016Y-161851D02*
X-1711483Y-162852D01*
G01X-1718637Y-168856D02*
X-1719659Y-168355D01*
G01X-1712250Y-160850D02*
X-1711228Y-161351D01*
G01X-1717871Y-169106D02*
X-1718637Y-168856D01*
G01X-1713016Y-160600D02*
X-1712250Y-160850D01*
G01X-1716338Y-168105D02*
X-1717871Y-167855D01*
G01X-1714550Y-161601D02*
X-1713016Y-161851D01*
G01X-1716593Y-169356D02*
X-1717871Y-169106D01*
G01X-1714294Y-160350D02*
X-1713016Y-160600D01*
G01X-1714294Y-169356D02*
X-1716593D01*
G01X-1714550Y-168105D02*
X-1716338D01*
G01Y-161601D02*
X-1714550D01*
G01X-1716593Y-160350D02*
X-1714294D01*
G01X-1717615Y-158349D02*
X-1716593D01*
G01X-1714550D02*
X-1713528D01*
G01Y-154346D02*
X-1714550D01*
G01X-1716593D02*
X-1717615D01*
G01X-1721448Y-152345D02*
X-1709440D01*
G01Y-150844D02*
X-1715060D01*
G01X-1716593D02*
X-1721448D01*
G01Y-143839D02*
X-1716593D01*
G01X-1715060D02*
X-1709440D01*
G01Y-142338D02*
X-1721448D01*
G01X-1713016Y-169106D02*
X-1714294Y-169356D01*
G01X-1717871Y-160600D02*
X-1716593Y-160350D01*
G01X-1713016Y-167855D02*
X-1714550Y-168105D01*
G01X-1717871Y-161851D02*
X-1716338Y-161601D01*
G01X-1724969Y70180D02*
G03X-1725385Y68419I3521J-1761D01*
G01X-1724969Y70180D02*
G03X-1725385Y68419I3521J-1761D01*
G01X-1706788Y106542D02*
X-1724969Y70180D01*
G01X-1706788Y106542D02*
X-1724969Y70180D01*
G01X-1703266Y108719D02*
G03X-1706788Y106542I0J-3937D01*
G01X-1705700Y107877D02*
G03X-1706788Y106542I2434J-3095D01*
G01X-1657471Y85096D02*
G03I-18701J0D01*
G01X-1339235Y108719D02*
X-1703266D01*
G01X-1655974Y374685D02*
X-1702805D01*
G01X-1589045Y473110D02*
X-1702805D01*
G01X-1563454Y613071D02*
X-1702805D01*
G01X-1563061Y788268D02*
X-1702805D01*
G01X-1535777Y807953D02*
X-1702805D01*
G01X-1589045Y847126D02*
X-1702805D01*
G01X-1493883Y1035782D02*
X-1707136Y903197D01*
G01D02*
X-1718947D01*
G01X-1610698Y1114842D02*
X-1702805D01*
G01X-1637793Y1138465D02*
X-1702805D01*
G01X-1622733Y1124571D02*
X-1718876Y1183136D01*
G01D02*
X-1722025D01*
G01X-1301030Y-694431D02*
X-1641712D01*
G01X-1635818Y-556636D02*
G03I-18700J0D01*
G01X-1647629D02*
G03I-6889J0D01*
G01X-1616920Y-416675D02*
G03I-18701J0D01*
G01X-1642314Y-409982D02*
G03Y-423368I0J-6693D01*
G01X-1628928D02*
X-1642314D01*
G01X-1628928D02*
G03Y-409982I0J6693D01*
G01D02*
X-1642314D01*
G01X-1616526Y-241478D02*
G03I-18701J0D01*
G01X-1635818Y-182620D02*
G03I-18700J0D01*
G01X-1628731Y-241478D02*
G03I-6496J0D01*
G01X-1647629Y-182620D02*
G03I-6889J0D01*
G01X-1668298Y85096D02*
G03I-7874J0D01*
G01X-1669948Y102731D02*
X-1640043Y187459D01*
G01D02*
X-1636893D01*
G01D02*
X-1350778D01*
G01X-1655974Y374685D02*
Y300276D01*
G01Y1098165D02*
Y378622D01*
G01Y1098165D02*
Y378622D01*
G01X-1636289Y1137623D02*
Y374685D01*
G01X-1652037D02*
X-1539714D01*
G01X-1652037D02*
X-1539714D01*
G01X-1655974Y378622D02*
G03X-1652037Y374685I3937J0D01*
G01X-1655974Y378622D02*
G03X-1652037Y374685I3937J0D01*
G01X-1634320Y500669D02*
Y547913D01*
G01X-1539832Y500669D02*
X-1634320D01*
G01Y547913D02*
X-1539832D01*
G01X-1629596Y566024D02*
Y594370D01*
G01X-1535777Y566024D02*
X-1629596D01*
G01X-1566210Y594370D02*
X-1629596D01*
G01Y631772D02*
Y783346D01*
G01Y631772D02*
X-1566210D01*
G01X-1652037Y767604D02*
Y768662D01*
G01X-1645122Y769085D02*
X-1645337Y768450D01*
G01D02*
X-1645770Y768027D01*
G01X-1646850Y768662D02*
X-1646418Y768874D01*
G01X-1645770Y768027D02*
X-1646850Y767604D01*
G01D02*
X-1652037D01*
G01Y768662D02*
X-1646850D01*
G01X-1652037Y770990D02*
Y772048D01*
G01Y774376D02*
Y775434D01*
G01Y777127D02*
Y778185D01*
G01Y780513D02*
Y781570D01*
G01Y783898D02*
Y784956D01*
G01X-1645986Y769509D02*
Y770143D01*
G01Y772894D02*
Y773318D01*
G01Y779031D02*
Y779666D01*
G01Y782417D02*
Y782840D01*
G01X-1645122Y784956D02*
Y783898D01*
G01Y782840D02*
Y781994D01*
G01Y779454D02*
Y778608D01*
G01Y775434D02*
Y774376D01*
G01Y773318D02*
Y772471D01*
G01Y769932D02*
Y769085D01*
G01X-1642096Y789189D02*
X-1641880Y790458D01*
G01X-1652037D02*
X-1651821Y789189D01*
G01X-1645122Y781994D02*
X-1645337Y781359D01*
G01X-1645122Y778608D02*
X-1645337Y777973D01*
G01X-1645122Y772471D02*
X-1645337Y771836D01*
G01X-1646202Y781994D02*
X-1645986Y782417D01*
G01X-1646202Y778608D02*
X-1645986Y779031D01*
G01X-1646202Y772471D02*
X-1645986Y772894D01*
G01X-1646202Y769085D02*
X-1645986Y769509D01*
G01X-1642744Y788131D02*
X-1642096Y789189D01*
G01X-1645337Y770566D02*
X-1645122Y769932D01*
G01X-1645986Y773318D02*
X-1646202Y773952D01*
G01X-1645337D02*
X-1645122Y773318D01*
G01X-1645337Y780089D02*
X-1645122Y779454D01*
G01X-1645986Y782840D02*
X-1646202Y783475D01*
G01X-1645337D02*
X-1645122Y782840D01*
G01X-1643609Y788765D02*
X-1643176Y789400D01*
G01X-1651821Y789189D02*
X-1651173Y788131D01*
G01X-1645986Y770143D02*
X-1646202Y770566D01*
G01X-1645986Y779666D02*
X-1646202Y780089D01*
G01X-1643393Y787496D02*
X-1642744Y788131D01*
G01X-1646418Y781782D02*
X-1646202Y781994D01*
G01X-1645337Y781359D02*
X-1645986Y780724D01*
G01X-1646418Y778396D02*
X-1646202Y778608D01*
G01X-1645337Y777973D02*
X-1645770Y777550D01*
G01X-1646418Y772259D02*
X-1646202Y772471D01*
G01X-1645337Y771836D02*
X-1645986Y771202D01*
G01X-1646418Y768874D02*
X-1646202Y769085D01*
G01X-1650741Y789400D02*
X-1650308Y788765D01*
G01X-1644905Y787919D02*
X-1643609Y788765D01*
G01X-1646202Y770566D02*
X-1646418Y770778D01*
G01X-1645986Y771202D02*
X-1645337Y770566D01*
G01X-1646202Y773952D02*
X-1646634Y774376D01*
G01X-1645770D02*
X-1645337Y773952D01*
G01X-1646202Y780089D02*
X-1646418Y780301D01*
G01X-1645986Y780724D02*
X-1645337Y780089D01*
G01X-1651173Y788131D02*
X-1650524Y787496D01*
G01X-1646202Y783475D02*
X-1646634Y783898D01*
G01X-1645770D02*
X-1645337Y783475D01*
G01X-1644257Y787072D02*
X-1643393Y787496D01*
G01X-1646850Y781570D02*
X-1646418Y781782D01*
G01X-1646850Y778185D02*
X-1646418Y778396D01*
G01X-1646850Y772048D02*
X-1646418Y772259D01*
G01X-1650308Y788765D02*
X-1649011Y787919D01*
G01X-1645770Y777550D02*
X-1646850Y777127D01*
G01X-1644905Y786861D02*
X-1644257Y787072D01*
G01X-1646418Y770778D02*
X-1646850Y770990D01*
G01X-1646418Y780301D02*
X-1646850Y780513D01*
G01X-1650524Y787496D02*
X-1649660Y787072D01*
G01D02*
X-1649011Y786861D01*
G01D02*
X-1647931Y786649D01*
G01X-1649011Y787919D02*
X-1647715Y787707D01*
G01X-1646850Y770990D02*
X-1652037D01*
G01Y772048D02*
X-1646850D01*
G01X-1645122Y774376D02*
X-1645770D01*
G01X-1646634D02*
X-1652037D01*
G01Y775434D02*
X-1645122D01*
G01X-1646850Y777127D02*
X-1652037D01*
G01Y778185D02*
X-1646850D01*
G01Y780513D02*
X-1652037D01*
G01Y781570D02*
X-1646850D01*
G01X-1645122Y783898D02*
X-1645770D01*
G01X-1646634D02*
X-1652037D01*
G01Y784956D02*
X-1645122D01*
G01X-1647931Y786649D02*
X-1645986D01*
G01X-1647715Y787707D02*
X-1646202D01*
G01D02*
X-1644905Y787919D01*
G01X-1645986Y786649D02*
X-1644905Y786861D01*
G01X-1629596Y783346D02*
X-1583858D01*
G01X-1648580Y795960D02*
Y799346D01*
G01X-1647715D02*
Y795960D01*
G01X-1645986D02*
Y799346D01*
G01X-1645122D02*
Y795960D01*
G01X-1651821Y791728D02*
X-1652037Y790458D01*
G01X-1650741Y791516D02*
X-1650957Y790458D01*
G01X-1643176Y789400D02*
X-1642960Y790458D01*
G01X-1651173Y792786D02*
X-1651821Y791728D01*
G01X-1650308Y792151D02*
X-1650741Y791516D01*
G01X-1650957Y790458D02*
X-1650741Y789400D01*
G01X-1642960Y790458D02*
X-1643176Y791516D01*
G01X-1641880Y790458D02*
X-1642096Y791728D01*
G01X-1650524Y793421D02*
X-1651173Y792786D01*
G01X-1643176Y791516D02*
X-1643609Y792151D01*
G01X-1642096Y791728D02*
X-1642744Y792786D01*
G01X-1649011Y792998D02*
X-1650308Y792151D01*
G01X-1642744Y792786D02*
X-1643393Y793421D01*
G01X-1649660Y793844D02*
X-1650524Y793421D01*
G01X-1643609Y792151D02*
X-1644905Y792998D01*
G01X-1649011Y794056D02*
X-1649660Y793844D01*
G01X-1643393Y793421D02*
X-1644257Y793844D01*
G01D02*
X-1644905Y794056D01*
G01D02*
X-1645986Y794267D01*
G01X-1644905Y792998D02*
X-1646202Y793209D01*
G01D02*
X-1647715D01*
G01X-1645986Y794267D02*
X-1647931D01*
G01X-1645122Y795960D02*
X-1645986D01*
G01X-1647715D02*
X-1648580D01*
G01X-1647715Y793209D02*
X-1649011Y792998D01*
G01X-1647931Y794267D02*
X-1649011Y794056D01*
G01X-1652037Y801039D02*
Y802309D01*
G01Y808234D02*
Y809504D01*
G01X-1647283Y802309D02*
Y808234D01*
G01X-1645986D02*
Y802309D01*
G01X-1641880Y809504D02*
Y808234D01*
G01Y802309D02*
Y801039D01*
G01X-1648580Y799346D02*
X-1647715D01*
G01X-1645986D02*
X-1645122D01*
G01X-1641880Y801039D02*
X-1652037D01*
G01Y802309D02*
X-1647283D01*
G01X-1645986D02*
X-1641880D01*
G01Y808234D02*
X-1645986D01*
G01X-1647283D02*
X-1652037D01*
G01Y809504D02*
X-1641880D01*
G01X-1629596Y806968D02*
Y819764D01*
G01X-1565817Y806968D02*
X-1629596D01*
G01Y819764D02*
X-1318572D01*
G01X-1506447Y1038379D02*
X-1656264Y976994D01*
G01D02*
X-1659414D01*
G01X-1501024Y1043279D02*
X-1667766Y1029155D01*
G01D02*
X-1670915D01*
G01X-1613857Y1111429D02*
X-1667766Y1085494D01*
G01D02*
X-1681862D01*
G01X-1655559Y1099926D02*
G03X-1655974Y1098165I3522J-1759D01*
G01X-1655559Y1099926D02*
G03X-1655974Y1098165I3522J-1759D01*
G01X-1637377Y1136288D02*
X-1655559Y1099926D01*
G01X-1637377Y1136288D02*
X-1655559Y1099926D01*
G01X-1633856Y1138465D02*
G03X-1637377Y1136288I1J-3937D01*
G01X-1633856Y1138465D02*
G03X-1637377Y1136288I1J-3937D01*
G01X-1269825Y1138465D02*
X-1633856D01*
G01X-1269825D02*
X-1633856D01*
G01X-1599037Y-837696D02*
Y-856633D01*
G01X-1609125Y-655061D02*
G03X-1605188Y-651124I0J3937D01*
G01D02*
Y-225730D01*
G01X-1441802Y-221793D02*
X-1601251D01*
G01D02*
G03X-1605188Y-225730I0J-3937D01*
G01X-1608383Y-139721D02*
Y-159825D01*
G01X-1604282D02*
Y-139721D01*
G01X-1595260D02*
Y-159825D01*
G01X-1591159D02*
Y-139721D01*
G01X-1608383Y-159825D02*
X-1604282D01*
G01X-1595260D02*
X-1591159D01*
G01X-1606743Y-135533D02*
X-1608383Y-139721D01*
G01X-1604282D02*
X-1603462Y-138046D01*
G01X-1591159Y-139721D02*
X-1590339Y-138046D01*
G01X-1605102Y-133857D02*
X-1606743Y-135533D01*
G01X-1603462Y-138046D02*
X-1602642Y-137208D01*
G01X-1591979Y-133857D02*
X-1594440Y-136370D01*
G01X-1590339Y-138046D02*
X-1589518Y-137208D01*
G01X-1602642D02*
X-1601001Y-136370D01*
G01X-1589518Y-137208D02*
X-1587878Y-136370D01*
G01X-1602642Y-133020D02*
X-1605102Y-133857D01*
G01X-1589518Y-133020D02*
X-1591979Y-133857D01*
G01X-1596080Y-138046D02*
X-1595260Y-139721D01*
G01X-1596900Y-137208D02*
X-1596080Y-138046D01*
G01X-1594440Y-136370D02*
X-1596900Y-133857D01*
G01X-1583777Y-137208D02*
X-1582137Y-138883D01*
G01Y-135533D02*
X-1583777Y-133857D01*
G01X-1598541Y-136370D02*
X-1596900Y-137208D01*
G01Y-133857D02*
X-1599361Y-133020D01*
G01X-1586238Y-136370D02*
X-1583777Y-137208D01*
G01Y-133857D02*
X-1586238Y-133020D01*
G01X-1601001Y-136370D02*
X-1598541D01*
G01X-1587878D02*
X-1586238D01*
G01Y-133020D02*
X-1589518D01*
G01X-1599361D02*
X-1602642D01*
G01X-1582137Y-138883D02*
Y-159825D01*
G01X-1578035D02*
Y-133020D01*
G01X-1571474Y-139721D02*
Y-159825D01*
G01X-1567373D02*
Y-139721D01*
G01X-1582137Y-159825D02*
X-1578035D01*
G01X-1571474D02*
X-1567373D01*
G01X-1582137Y-133020D02*
Y-135533D01*
G01X-1569833D02*
X-1571474Y-139721D01*
G01X-1567373D02*
X-1566553Y-138046D01*
G01X-1568193Y-133857D02*
X-1569833Y-135533D01*
G01X-1566553Y-138046D02*
X-1565732Y-137208D01*
G01D02*
X-1564092Y-136370D01*
G01X-1565732Y-133020D02*
X-1568193Y-133857D01*
G01X-1561631Y-136370D02*
X-1559991Y-137208D01*
G01Y-133857D02*
X-1562452Y-133020D01*
G01X-1564092Y-136370D02*
X-1561631D01*
G01X-1562452Y-133020D02*
X-1565732D01*
G01X-1578035D02*
X-1582137D01*
G01X-1547432Y14230D02*
G03I-14764J0D01*
G01X-1553928D02*
G03I-8268J0D01*
G01X-1585108Y469173D02*
Y300276D01*
G01X-1566210Y602441D02*
Y300276D01*
G01X-1614905Y377192D02*
X-1615620Y390827D01*
G01X-1603538Y376260D02*
X-1613922D01*
G01X-1602555Y377192D02*
X-1614905D01*
G01D02*
G03X-1613922Y376260I983J52D01*
G01X-1619278Y392523D02*
X-1619372Y392583D01*
G01X-1619089Y393361D02*
X-1618994Y393301D01*
G01X-1615782Y391265D02*
X-1615687Y391205D01*
G01X-1615372Y392343D02*
X-1615467Y392403D01*
G01X-1615498Y393421D02*
X-1615404Y393361D01*
G01X-1617658Y396252D02*
X-1617500Y396144D01*
G01X-1607977Y394469D02*
X-1608135Y394577D01*
G01X-1607130Y396252D02*
X-1606972Y396144D01*
G01X-1613048Y389383D02*
X-1613259Y389542D01*
G01X-1613892Y392343D02*
X-1613735Y392223D01*
G01X-1621829Y393661D02*
X-1621703Y393541D01*
G01X-1619530Y392343D02*
X-1619404Y392223D01*
G01X-1618805Y392343D02*
X-1618931Y392463D01*
G01X-1614459Y390965D02*
X-1614585Y391085D01*
G01X-1614522Y391325D02*
X-1614459Y391265D01*
G01X-1613955Y393661D02*
X-1613829Y393541D01*
G01X-1608241Y394253D02*
X-1608453Y394469D01*
G01X-1619655Y391145D02*
X-1619498Y390965D01*
G01X-1615970Y391145D02*
X-1615813Y390965D01*
G01X-1615183Y392463D02*
X-1615341Y392642D01*
G01X-1615215Y393481D02*
X-1615372Y393661D01*
G01X-1604759Y391145D02*
X-1604601Y390965D01*
G01X-1621860Y393301D02*
X-1621766Y393181D01*
G01X-1619372Y392583D02*
X-1619467Y392702D01*
G01X-1618963Y392104D02*
X-1618868Y391983D01*
G01X-1615876Y391385D02*
X-1615782Y391265D01*
G01X-1614585Y391085D02*
X-1614680Y391205D01*
G01X-1615278Y392223D02*
X-1615372Y392343D01*
G01X-1615404Y393361D02*
X-1615309Y393241D01*
G01X-1613861Y392043D02*
X-1613955Y392163D01*
G01X-1613892Y393241D02*
X-1613987Y393361D01*
G01X-1607562Y391504D02*
X-1607656Y391624D01*
G01X-1607247Y393122D02*
X-1607152Y393002D01*
G01X-1604570Y391265D02*
X-1604664Y391385D01*
G01X-1613418Y389746D02*
X-1613260Y389543D01*
G01X-1618837Y393481D02*
X-1618963Y393661D01*
G01X-1605861Y393481D02*
X-1605987Y393661D01*
G01X-1617500Y396144D02*
X-1617394Y395981D01*
G01X-1608135Y394577D02*
X-1608241Y394739D01*
G01X-1606972Y396144D02*
X-1606866Y395981D01*
G01X-1605596Y396630D02*
X-1604274Y394469D01*
G01X-1604432Y394091D02*
X-1605755Y396306D01*
G01X-1621703Y393541D02*
X-1621577Y393301D01*
G01X-1619467Y391325D02*
X-1619561Y391504D01*
G01X-1619655Y392583D02*
X-1619530Y392343D01*
G01X-1618679Y392104D02*
X-1618805Y392343D01*
G01X-1615089Y392283D02*
X-1615183Y392463D01*
G01X-1605955Y393241D02*
X-1606018Y393361D01*
G01X-1618994Y393301D02*
X-1618931Y393181D01*
G01X-1615215Y392104D02*
X-1615278Y392223D01*
G01X-1614585Y391444D02*
X-1614522Y391325D01*
G01X-1613829Y393541D02*
X-1613703Y393301D01*
G01X-1617182Y396252D02*
X-1617076Y396035D01*
G01X-1608453Y394469D02*
X-1608559Y394685D01*
G01X-1606654Y396252D02*
X-1606548Y396035D01*
G01X-1613418Y389746D02*
X-1613519Y389986D01*
G01X-1618742Y393241D02*
X-1618837Y393481D01*
G01X-1616065Y391385D02*
X-1615970Y391145D01*
G01X-1615120Y393241D02*
X-1615215Y393481D01*
G01X-1621766Y393181D02*
X-1621703Y393002D01*
G01X-1619498Y390965D02*
X-1619341Y390905D01*
G01X-1615813Y390965D02*
X-1615656Y390905D01*
G01X-1618931Y392463D02*
X-1619089Y392523D01*
G01X-1621986Y393720D02*
X-1621829Y393661D01*
G01X-1614459Y391265D02*
X-1614302Y391205D01*
G01X-1613050Y389385D02*
X-1612805Y389286D01*
G01X-1619341Y391265D02*
X-1619467Y391325D01*
G01X-1621986Y393361D02*
X-1621860Y393301D01*
G01X-1619404Y392223D02*
X-1619278Y392163D01*
G01X-1619089D02*
X-1618963Y392104D01*
G01X-1614333Y390905D02*
X-1614459Y390965D01*
G01X-1604444Y391205D02*
X-1604570Y391265D01*
G01X-1604255Y392403D02*
X-1604129Y392343D01*
G01X-1608030Y394144D02*
X-1608241Y394253D01*
G01X-1606018Y393361D02*
X-1606113Y393421D01*
G01X-1605767Y393241D02*
X-1605861Y393481D01*
G01X-1604853Y391385D02*
X-1604759Y391145D01*
G01X-1609035Y394091D02*
X-1609511Y395333D01*
G01X-1609828Y395225D02*
X-1609405Y394091D01*
G01X-1618868Y391983D02*
X-1618805Y391804D01*
G01X-1615939Y391564D02*
X-1615876Y391385D01*
G01X-1614680Y391205D02*
X-1614743Y391385D01*
G01X-1615309Y393241D02*
X-1615246Y393062D01*
G01X-1613735Y392223D02*
X-1613672Y392043D01*
G01X-1613829Y393062D02*
X-1613892Y393241D01*
G01X-1612506Y390905D02*
X-1612979Y392283D01*
G01X-1612821Y392583D02*
X-1612254Y390905D01*
G01X-1614220Y396035D02*
X-1614272Y396198D01*
G01X-1613955D02*
X-1613902Y396035D01*
G01X-1609405D02*
X-1609458Y396198D01*
G01X-1609088Y396035D02*
X-1609141Y396198D01*
G01X-1619750Y391444D02*
X-1619655Y391145D01*
G01X-1621577Y393301D02*
X-1621514Y393062D01*
G01X-1618616Y391864D02*
X-1618679Y392104D01*
G01X-1618931Y393181D02*
X-1618900Y393062D01*
G01X-1614617Y391564D02*
X-1614585Y391444D01*
G01X-1613798Y391804D02*
X-1613861Y392043D01*
G01X-1604916Y391624D02*
X-1604853Y391385D01*
G01X-1604664D02*
X-1604727Y391624D01*
G01X-1617394Y395981D02*
X-1617341Y395765D01*
G01X-1608241Y394739D02*
X-1608294Y394955D01*
G01X-1606866Y395981D02*
X-1606813Y395765D01*
G01X-1616128Y391684D02*
X-1616065Y391385D01*
G01X-1615026Y391983D02*
X-1615089Y392283D01*
G01X-1617076Y396035D02*
X-1617023Y395765D01*
G01X-1619561Y391504D02*
X-1619593Y391684D01*
G01X-1619467Y392702D02*
X-1619498Y392882D01*
G01X-1621514Y393062D02*
X-1621482Y392762D01*
G01X-1618804Y388911D02*
X-1618967Y390457D01*
G01X-1616159Y392104D02*
X-1616128Y391684D01*
G01X-1607765Y394415D02*
X-1607977Y394469D01*
G01X-1614176Y393720D02*
X-1613955Y393661D01*
G01Y392163D02*
X-1614144Y392223D01*
G01X-1618963Y393661D02*
X-1619120Y393720D01*
G01X-1615341Y392642D02*
X-1615498Y392702D01*
G01X-1615372Y393661D02*
X-1615530Y393720D01*
G01X-1613987Y393361D02*
X-1614144Y393421D01*
G01X-1604601Y390965D02*
X-1604444Y390905D01*
G01X-1604097Y392642D02*
X-1604255Y392702D01*
G01X-1605987Y393661D02*
X-1606144Y393720D01*
G01X-1605357Y390846D02*
X-1605294Y390546D01*
G01X-1605168D02*
X-1605231Y390846D01*
G01X-1605704Y390905D02*
X-1605987Y392283D01*
G01X-1606176Y392163D02*
X-1605924Y390905D01*
G01X-1608559Y394685D02*
X-1608612Y394955D01*
G01X-1606548Y396035D02*
X-1606496Y395765D01*
G01X-1611120Y393720D02*
X-1610680Y391265D01*
G01X-1617608Y393720D02*
X-1617104Y390905D01*
G01X-1610805D02*
X-1611309Y393720D01*
G01X-1618711Y393062D02*
X-1618742Y393241D01*
G01X-1617293Y390905D02*
X-1617419Y391624D01*
G01X-1617734Y393481D02*
X-1617451Y391864D01*
G01X-1615970Y391744D02*
X-1615939Y391564D01*
G01X-1615183Y391924D02*
X-1615215Y392104D01*
G01X-1615089Y393062D02*
X-1615120Y393241D01*
G01X-1614743Y391385D02*
X-1614774Y391564D01*
G01X-1605924Y393062D02*
X-1605955Y393241D01*
G01X-1605735Y393062D02*
X-1605767Y393241D01*
G01X-1613552Y390236D02*
X-1613518Y389984D01*
G01X-1621703Y393002D02*
X-1621671Y392762D01*
G01X-1619781Y391684D02*
X-1619750Y391444D01*
G01X-1619687Y392822D02*
X-1619655Y392583D01*
G01X-1613672Y392043D02*
X-1613640Y391804D01*
G01X-1613703Y393301D02*
X-1613672Y393062D01*
G01X-1605420Y391385D02*
X-1605357Y390846D01*
G01X-1605231D02*
X-1605294Y391385D01*
G01X-1605452Y391924D02*
X-1605420Y391385D01*
G01X-1605294D02*
X-1605326Y391924D01*
G01X-1623297Y391220D02*
Y404738D01*
G01X-1622742Y390905D02*
Y393720D01*
G01X-1622553Y391265D02*
Y393361D01*
G01X-1621722Y391220D02*
X-1621724Y409998D01*
G01X-1621671Y392762D02*
Y391864D01*
G01X-1621482Y392762D02*
Y391864D01*
G01X-1621230Y393421D02*
Y393720D01*
G01X-1621013Y402244D02*
Y390827D01*
G01X-1620726Y390905D02*
Y393421D01*
G01X-1620537D02*
Y390905D01*
G01X-1620344Y390827D02*
Y389252D01*
G01X-1620033Y393720D02*
Y393421D01*
G01X-1619687Y393062D02*
Y392822D01*
G01X-1619498Y392882D02*
Y393002D01*
G01X-1619439Y398228D02*
Y390827D01*
G01X-1619139Y394091D02*
Y396630D01*
G01X-1618966Y390457D02*
Y389252D01*
G01X-1618822Y394415D02*
Y396306D01*
G01X-1618805Y391804D02*
Y391624D01*
G01X-1618616Y391564D02*
Y391864D01*
G01X-1618209Y390827D02*
Y393189D01*
G01X-1617391Y390827D02*
Y393189D01*
G01X-1617341Y395765D02*
Y394955D01*
G01X-1617023Y395765D02*
Y394955D01*
G01X-1616852Y391924D02*
Y392223D01*
G01X-1616600Y394091D02*
Y396630D01*
G01X-1616411Y392223D02*
Y391924D01*
G01X-1616283Y396630D02*
Y394091D01*
G01X-1616159Y392523D02*
Y392104D01*
G01X-1616013Y389252D02*
Y390827D01*
G01X-1616002Y392403D02*
Y392523D01*
G01X-1615970Y391924D02*
Y391744D01*
G01X-1615859Y394091D02*
Y396630D01*
G01X-1615542Y395225D02*
Y394091D01*
G01Y396360D02*
Y395549D01*
G01X-1615423Y390827D02*
Y389252D01*
G01X-1615183Y391744D02*
Y391924D01*
G01X-1615026Y391684D02*
Y391983D01*
G01X-1614635Y390827D02*
Y389252D01*
G01X-1614478Y390827D02*
Y389252D01*
G01X-1614270Y392223D02*
Y392463D01*
G01X-1614220Y395874D02*
Y396035D01*
G01X-1613927Y397520D02*
Y390827D01*
G01X-1613902Y396035D02*
Y395820D01*
G01X-1613829Y392942D02*
Y393062D01*
G01X-1613798Y391564D02*
Y391804D01*
G01X-1613672Y393062D02*
Y392942D01*
G01X-1613651Y390827D02*
Y393189D01*
G01X-1613640Y391804D02*
Y391564D01*
G01X-1613552Y393189D02*
Y390236D01*
G01X-1613388Y390905D02*
Y393720D01*
G01X-1613199Y391864D02*
Y390905D01*
G01Y393720D02*
Y392343D01*
G01X-1612632Y394091D02*
Y396360D01*
G01X-1612315D02*
Y394091D01*
G01X-1612002Y391924D02*
Y392223D01*
G01X-1611683Y393976D02*
Y393189D01*
G01Y389252D02*
Y390827D01*
G01X-1611561Y392223D02*
Y391924D01*
G01X-1611514Y393189D02*
Y390236D01*
G01X-1611352Y389252D02*
Y390827D01*
G01X-1611348Y389252D02*
Y390827D01*
G01X-1611045Y396630D02*
Y394091D01*
G01X-1610728Y396360D02*
Y395549D01*
G01Y394091D02*
Y395225D01*
G01X-1609798Y391924D02*
Y392223D01*
G01X-1609714Y393189D02*
Y389252D01*
G01X-1609405Y395874D02*
Y396035D01*
G01X-1609357Y392223D02*
Y391924D01*
G01X-1609105Y393421D02*
Y393720D01*
G01X-1609088Y395820D02*
Y396035D01*
G01X-1608612Y394955D02*
Y395765D01*
G01X-1608601Y390905D02*
Y393421D01*
G01X-1608412D02*
Y390905D01*
G01X-1608294Y394955D02*
Y395765D01*
G01X-1607908Y393720D02*
Y393421D01*
G01X-1607746Y393189D02*
Y389252D01*
G01X-1606900Y393720D02*
Y390905D01*
G01X-1606813Y395765D02*
Y394955D01*
G01X-1606711Y393421D02*
Y392523D01*
G01Y390905D02*
Y392163D01*
G01X-1606496Y395765D02*
Y394955D01*
G01X-1606112Y389252D02*
Y390827D01*
G01X-1606072Y394091D02*
Y396630D01*
G01X-1605946Y393189D02*
Y390236D01*
G01X-1605924Y392882D02*
Y393062D01*
G01X-1605777Y393976D02*
Y393189D01*
G01Y389252D02*
Y390827D01*
G01X-1605755Y396306D02*
Y394091D01*
G01X-1605735Y392822D02*
Y393062D01*
G01X-1605452Y392343D02*
Y391924D01*
G01X-1605326D02*
Y392343D01*
G01X-1604916Y393720D02*
Y392163D01*
G01X-1604759Y392463D02*
Y393421D01*
G01X-1604274Y394469D02*
Y396630D01*
G01X-1617400Y397283D02*
X-1617596Y390827D01*
G01X-1612808Y389286D02*
X-1612542Y389252D01*
G01X-1604918D02*
X-1605202Y389291D01*
X-1605435Y389387D01*
X-1605647Y389545D01*
X-1605817Y389761D01*
X-1605915Y389998D01*
X-1605946Y390236D01*
G01X-1607765Y394091D02*
X-1608030Y394144D01*
G01X-1605420Y392882D02*
X-1605452Y392343D01*
G01X-1605326D02*
X-1605294Y392882D01*
G01X-1616128Y392942D02*
X-1616159Y392523D01*
G01X-1616002D02*
X-1615970Y392882D01*
G01X-1615743Y388911D02*
X-1615541Y390827D01*
G01X-1621482Y391864D02*
X-1621514Y391564D01*
G01X-1605357Y393421D02*
X-1605420Y392882D01*
G01X-1605294D02*
X-1605231Y393421D01*
G01X-1621671Y391864D02*
X-1621703Y391624D01*
G01X-1619655Y393301D02*
X-1619687Y393062D01*
G01X-1614743D02*
X-1614711Y393301D01*
G01X-1613672Y392942D02*
X-1613703Y392702D01*
G01X-1619498Y393002D02*
X-1619467Y393181D01*
G01X-1604918Y389252D02*
X-1605066Y389263D01*
X-1605212Y389294D01*
X-1605351Y389345D01*
X-1605481Y389415D01*
X-1605600Y389502D01*
X-1605703Y389603D01*
X-1605789Y389716D01*
X-1605857Y389839D01*
X-1605907Y389968D01*
X-1605936Y390101D01*
X-1605946Y390236D01*
G01X-1618018Y391864D02*
X-1617734Y393481D01*
G01X-1618049Y391624D02*
X-1618175Y390905D01*
G01X-1615970Y392882D02*
X-1615939Y393062D01*
G01Y392104D02*
X-1615970Y391924D01*
G01X-1615215Y391564D02*
X-1615183Y391744D01*
G01X-1613640Y391564D02*
X-1613672Y391385D01*
G01X-1605955Y392702D02*
X-1605924Y392882D01*
G01X-1605767Y392642D02*
X-1605735Y392822D01*
G01X-1618364Y390905D02*
X-1617860Y393720D01*
G01X-1610050D02*
X-1610554Y390905D01*
G01X-1610680Y391265D02*
X-1610239Y393720D01*
G01X-1617023Y394955D02*
X-1617076Y394685D01*
G01X-1608612Y395765D02*
X-1608559Y396035D01*
G01X-1606496Y394955D02*
X-1606548Y394685D01*
G01X-1616065Y393241D02*
X-1616128Y392942D01*
G01X-1615089Y391385D02*
X-1615026Y391684D01*
G01X-1605294Y393720D02*
X-1605357Y393421D01*
G01X-1605231D02*
X-1605168Y393720D01*
G01X-1617341Y394955D02*
X-1617394Y394739D01*
G01X-1608294Y395765D02*
X-1608241Y395981D01*
G01X-1621514Y391564D02*
X-1621577Y391325D01*
G01X-1618679D02*
X-1618616Y391564D01*
G01X-1612542Y389252D02*
X-1612394Y389263D01*
X-1612248Y389294D01*
X-1612109Y389345D01*
X-1611979Y389415D01*
X-1611861Y389502D01*
X-1611757Y389603D01*
X-1611671Y389716D01*
X-1611603Y389839D01*
X-1611554Y389968D01*
X-1611524Y390101D01*
X-1611514Y390236D01*
G01X-1617434Y387677D02*
X-1617113D01*
G01X-1618804Y388911D02*
X-1615743D01*
G01X-1604918Y389252D02*
X-1607746D01*
G01X-1596131D02*
X-1604918D01*
G01X-1609714D02*
X-1612542D01*
G01X-1607746D02*
X-1609714D01*
G01X-1612542D02*
X-1621328D01*
G01X-1603908Y390236D02*
X-1607746D01*
G01X-1609714D02*
X-1613552D01*
G01X-1605294Y390546D02*
X-1605168D01*
G01X-1598179Y390827D02*
X-1619439D01*
G01X-1621328D02*
X-1619439D01*
G01X-1610554Y390905D02*
X-1610805D01*
G01X-1608412D02*
X-1608601D01*
G01X-1614081D02*
X-1614333D01*
G01X-1612254D02*
X-1612506D01*
G01X-1613199D02*
X-1613388D01*
G01X-1618175D02*
X-1618364D01*
G01X-1617104D02*
X-1617293D01*
G01X-1620537D02*
X-1620726D01*
G01X-1621986D02*
X-1622742D01*
G01X-1619341D02*
X-1619089D01*
G01X-1615656D02*
X-1615498D01*
G01X-1605924D02*
X-1605704D01*
G01X-1606900D02*
X-1606711D01*
G01X-1604444D02*
X-1604255D01*
G01Y391205D02*
X-1604444D01*
G01X-1615687D02*
X-1615467D01*
G01X-1614302D02*
X-1614113D01*
G01X-1623297Y391220D02*
X-1621722D01*
G01X-1619089Y391265D02*
X-1619341D01*
G01X-1621986D02*
X-1622553D01*
G01X-1614774Y391564D02*
X-1614617D01*
G01X-1604727Y391624D02*
X-1604916D01*
G01X-1617419D02*
X-1618049D01*
G01X-1619593Y391684D02*
X-1619781D01*
G01X-1617451Y391864D02*
X-1618018D01*
G01X-1609357Y391924D02*
X-1609798D01*
G01X-1611561D02*
X-1612002D01*
G01X-1616411D02*
X-1616852D01*
G01X-1619278Y392163D02*
X-1619089D01*
G01X-1606711D02*
X-1606176D01*
G01X-1604916D02*
X-1604696D01*
G01X-1614144Y392223D02*
X-1614270D01*
G01X-1616852D02*
X-1616411D01*
G01X-1612002D02*
X-1611561D01*
G01X-1609798D02*
X-1609357D01*
G01X-1615467Y392403D02*
X-1615687D01*
G01X-1604444D02*
X-1604255D01*
G01X-1614270Y392463D02*
X-1614144D01*
G01X-1619089Y392523D02*
X-1619278D01*
G01X-1606711D02*
X-1606113D01*
G01X-1604255Y392702D02*
X-1604444D01*
G01X-1615498D02*
X-1615656D01*
G01X-1623297Y392767D02*
X-1621722D01*
G01X-1614585Y393062D02*
X-1614743D01*
G01X-1618900D02*
X-1618711D01*
G01X-1615246D02*
X-1615089D01*
G01X-1598789Y393189D02*
X-1618209D01*
G01X-1622553Y393361D02*
X-1621986D01*
G01X-1619278D02*
X-1619089D01*
G01X-1607908Y393421D02*
X-1608412D01*
G01X-1606113D02*
X-1606711D01*
G01X-1608601D02*
X-1609105D01*
G01X-1614144D02*
X-1614270D01*
G01X-1620726D02*
X-1621230D01*
G01X-1620033D02*
X-1620537D01*
G01X-1615687D02*
X-1615498D01*
G01X-1604759D02*
X-1603845D01*
G01Y393720D02*
X-1604916D01*
G01X-1606144D02*
X-1606900D01*
G01X-1605168D02*
X-1605294D01*
G01X-1615530D02*
X-1615656D01*
G01X-1619120D02*
X-1619278D01*
G01X-1622742D02*
X-1621986D01*
G01X-1621230D02*
X-1620033D01*
G01X-1617860D02*
X-1617608D01*
G01X-1614239D02*
X-1614176D01*
G01X-1612506D02*
X-1612254D01*
G01X-1613388D02*
X-1613199D01*
G01X-1610239D02*
X-1610050D01*
G01X-1611309D02*
X-1611120D01*
G01X-1609105D02*
X-1607908D01*
G01X-1611683Y393976D02*
X-1605777D01*
G01X-1603956Y394091D02*
X-1604432D01*
G01X-1607342D02*
X-1607765D01*
G01X-1605755D02*
X-1606072D01*
G01X-1612315D02*
X-1612632D01*
G01X-1616283D02*
X-1616600D01*
G01X-1615542D02*
X-1615859D01*
G01X-1617870D02*
X-1619139D01*
G01X-1609405D02*
X-1609035D01*
G01X-1611045D02*
X-1610728D01*
G01X-1607342Y394415D02*
X-1607765D01*
G01X-1617870D02*
X-1618822D01*
G01X-1614590Y395225D02*
X-1615542D01*
G01X-1610728D02*
X-1609828D01*
G01X-1615542Y395549D02*
X-1614537D01*
G01X-1610728D02*
X-1609723D01*
G01X-1607746Y395945D02*
X-1609714D01*
G01X-1606813Y394955D02*
X-1606866Y394739D01*
G01X-1613892Y392702D02*
X-1613829Y392942D01*
G01Y391444D02*
X-1613798Y391564D01*
G01X-1607656Y391624D02*
X-1607247Y393122D01*
G01X-1607152Y393002D02*
X-1607562Y391504D01*
G01X-1614272Y395711D02*
X-1614220Y395874D01*
G01X-1613902Y395820D02*
X-1613955Y395657D01*
G01X-1609458Y395711D02*
X-1609405Y395874D01*
G01X-1609141Y395657D02*
X-1609088Y395820D01*
G01X-1621703Y391624D02*
X-1621766Y391444D01*
G01X-1618805Y391624D02*
X-1618868Y391444D01*
G01X-1615939Y393062D02*
X-1615876Y393241D01*
G01X-1615278Y391385D02*
X-1615215Y391564D01*
G01X-1614522Y393241D02*
X-1614585Y393062D01*
G01X-1613703Y392702D02*
X-1613766Y392523D01*
G01X-1613672Y391385D02*
X-1613735Y391205D01*
G01X-1612542Y389252D02*
X-1612258Y389291D01*
X-1612025Y389387D01*
X-1611813Y389545D01*
X-1611643Y389761D01*
X-1611545Y389998D01*
X-1611514Y390236D01*
G01X-1604652Y389286D02*
X-1604918Y389252D01*
G01X-1615970Y393481D02*
X-1616065Y393241D01*
G01X-1615183Y391145D02*
X-1615089Y391385D01*
G01X-1605861Y392403D02*
X-1605767Y392642D01*
G01X-1607130Y394469D02*
X-1607342Y394415D01*
G01X-1607078Y394144D02*
X-1607342Y394091D01*
G01X-1617605Y394144D02*
X-1617870Y394091D01*
G01X-1614325Y395279D02*
X-1614590Y395225D01*
G01X-1617076Y394685D02*
X-1617182Y394469D01*
G01X-1608559Y396035D02*
X-1608453Y396252D01*
G01X-1606548Y394685D02*
X-1606654Y394469D01*
G01X-1612254Y393720D02*
X-1612821Y392583D01*
G01X-1613199Y392343D02*
X-1612506Y393720D01*
G01X-1621577Y391325D02*
X-1621703Y391085D01*
G01X-1619530Y393541D02*
X-1619655Y393301D01*
G01X-1618805Y391085D02*
X-1618679Y391325D01*
G01X-1615876Y392223D02*
X-1615939Y392104D01*
G01X-1614711Y393301D02*
X-1614585Y393541D01*
G01X-1613955Y392583D02*
X-1613892Y392702D01*
G01Y391325D02*
X-1613829Y391444D01*
G01X-1612979Y392283D02*
X-1613199Y391864D01*
G01X-1606018Y392583D02*
X-1605955Y392702D01*
G01X-1614459Y393661D02*
X-1614239Y393720D01*
G01X-1617658Y394469D02*
X-1617870Y394415D01*
G01X-1617394Y394739D02*
X-1617500Y394577D01*
G01X-1608241Y395981D02*
X-1608135Y396144D01*
G01X-1606866Y394739D02*
X-1606972Y394577D01*
G01X-1613766Y392523D02*
X-1613892Y392343D01*
G01X-1604696Y392163D02*
X-1604570Y392343D01*
G01X-1609300Y395441D02*
X-1609141Y395657D01*
G01X-1613955D02*
X-1614114Y395441D01*
G01X-1621766Y391444D02*
X-1621860Y391325D01*
G01X-1619467Y393181D02*
X-1619372Y393301D01*
G01X-1618868Y391444D02*
X-1618963Y391325D01*
G01X-1615876Y393241D02*
X-1615782Y393361D01*
G01X-1615813Y392642D02*
X-1616002Y392403D01*
G01X-1615782Y392343D02*
X-1615876Y392223D01*
G01X-1614428Y393361D02*
X-1614522Y393241D01*
G01X-1615372Y391265D02*
X-1615278Y391385D01*
G01X-1613735Y391205D02*
X-1613829Y391085D01*
G01X-1615813Y393661D02*
X-1615970Y393481D01*
G01X-1615341Y390965D02*
X-1615183Y391145D01*
G01X-1604601Y392642D02*
X-1604759Y392463D01*
G01X-1617182Y394469D02*
X-1617394Y394253D01*
G01X-1614378Y395604D02*
X-1614272Y395711D01*
G01X-1609564Y395604D02*
X-1609458Y395711D01*
G01X-1606654Y394469D02*
X-1606866Y394253D01*
G01X-1619404Y393661D02*
X-1619530Y393541D01*
G01X-1621703Y391085D02*
X-1621829Y390965D01*
G01X-1618931D02*
X-1618805Y391085D01*
G01X-1614585Y393541D02*
X-1614459Y393661D01*
G01X-1613955Y391265D02*
X-1613892Y391325D01*
G01X-1613829Y391085D02*
X-1613955Y390965D01*
G01X-1605987Y392283D02*
X-1605861Y392403D01*
G01X-1614114Y395441D02*
X-1614325Y395279D01*
G01X-1604412Y389383D02*
X-1604201Y389542D01*
X-1604041Y389747D01*
X-1603941Y389986D01*
G01X-1617500Y394577D02*
X-1617658Y394469D01*
G01X-1608135Y396144D02*
X-1607977Y396252D01*
G01X-1606972Y394577D02*
X-1607130Y394469D01*
G01X-1619372Y393301D02*
X-1619278Y393361D01*
G01X-1615782D02*
X-1615687Y393421D01*
G01Y392403D02*
X-1615782Y392343D01*
G01X-1614144Y392463D02*
X-1613955Y392583D01*
G01X-1615467Y391205D02*
X-1615372Y391265D01*
G01X-1606113Y392523D02*
X-1606018Y392583D01*
G01X-1617394Y394253D02*
X-1617605Y394144D01*
G01X-1609511Y395333D02*
X-1609300Y395441D01*
G01X-1606866Y394253D02*
X-1607078Y394144D01*
G01X-1621680Y391042D02*
X-1623083Y390327D01*
G01X-1619278Y393720D02*
X-1619404Y393661D01*
G01X-1621860Y391325D02*
X-1621986Y391265D01*
G01X-1618963Y391325D02*
X-1619089Y391265D01*
G01X-1613955Y390965D02*
X-1614081Y390905D01*
G01X-1604570Y392343D02*
X-1604444Y392403D01*
G01X-1604129Y391265D02*
X-1604255Y391205D01*
G01X-1618957Y390456D02*
X-1618953Y390458D01*
G01X-1618450Y390679D02*
X-1618957Y390456D01*
G01X-1618110Y390827D02*
X-1618686Y390576D01*
G01X-1618434Y390686D02*
X-1618110Y390827D01*
G01X-1604655Y389286D02*
X-1604410Y389385D01*
G01X-1615656Y393720D02*
X-1615813Y393661D01*
G01X-1621829Y390965D02*
X-1621986Y390905D01*
G01X-1614270Y393421D02*
X-1614428Y393361D01*
G01X-1615656Y392702D02*
X-1615813Y392642D01*
G01X-1619089Y390905D02*
X-1618931Y390965D01*
G01X-1615498Y390905D02*
X-1615341Y390965D01*
G01X-1614113Y391205D02*
X-1613955Y391265D01*
G01X-1604444Y392702D02*
X-1604601Y392642D01*
G01X-1604255Y390905D02*
X-1604097Y390965D01*
G01X-1614537Y395549D02*
X-1614378Y395604D01*
G01X-1609723Y395549D02*
X-1609564Y395604D01*
G01X-1623297Y391220D02*
G03X-1621328Y389252I1968J0D01*
G01X-1618804Y388911D02*
G03X-1617434Y387677I1370J144D01*
G01X-1617113D02*
G03X-1615743Y388911I0J1378D01*
G01X-1621722Y391220D02*
G03X-1621328Y390827I394J1D01*
G01X-1609714Y395945D02*
G03X-1611683Y393976I0J-1969D01*
G01X-1605777D02*
G03X-1607746Y395945I-1969J0D01*
G01X-1602555Y377192D02*
X-1601840Y390827D01*
G01X-1603538Y376260D02*
G03X-1602555Y377192I0J984D01*
G01X-1602422Y394253D02*
X-1602633Y394469D01*
G01X-1599777D02*
X-1599935Y394631D01*
G01X-1600094Y395604D02*
X-1599883Y395387D01*
G01X-1598454Y395171D02*
X-1598666Y395387D01*
G01X-1598983Y396252D02*
X-1598878Y396144D01*
G01X-1603341Y391145D02*
X-1603184Y390965D01*
G01X-1603940Y392463D02*
X-1604097Y392642D01*
G01X-1601956Y391145D02*
X-1601798Y390965D01*
G01X-1602554Y392463D02*
X-1602711Y392642D01*
G01X-1602585Y393481D02*
X-1602743Y393661D01*
G01X-1601168Y392463D02*
X-1601326Y392642D01*
G01X-1601200Y393481D02*
X-1601357Y393661D01*
G01X-1598113Y391145D02*
X-1597956Y390965D01*
G01X-1596728Y391145D02*
X-1596570Y390965D01*
G01X-1597326Y392463D02*
X-1597483Y392642D01*
G01X-1597357Y393481D02*
X-1597515Y393661D01*
G01X-1595940Y392463D02*
X-1596098Y392642D01*
G01X-1595972Y393481D02*
X-1596129Y393661D01*
G01X-1604129Y392343D02*
X-1604034Y392223D01*
G01X-1603247Y391385D02*
X-1603152Y391265D01*
G01X-1602648Y392223D02*
X-1602743Y392343D01*
G01X-1601861Y391385D02*
X-1601767Y391265D01*
G01X-1602774Y393361D02*
X-1602680Y393241D01*
G01X-1601263Y392223D02*
X-1601357Y392343D01*
G01X-1601389Y393361D02*
X-1601294Y393241D01*
G01X-1598019Y391385D02*
X-1597924Y391265D01*
G01X-1597420Y392223D02*
X-1597515Y392343D01*
G01X-1596633Y391385D02*
X-1596539Y391265D01*
G01X-1597546Y393361D02*
X-1597452Y393241D01*
G01X-1596035Y392223D02*
X-1596129Y392343D01*
G01X-1596161Y393361D02*
X-1596066Y393241D01*
G01X-1602422Y394739D02*
X-1602316Y394577D01*
G01X-1598772Y395063D02*
X-1598666Y394901D01*
G01X-1600253Y394577D02*
X-1600094Y394307D01*
G01X-1602459Y392283D02*
X-1602554Y392463D01*
G01X-1601200Y392104D02*
X-1601263Y392223D01*
G01X-1601074Y392283D02*
X-1601168Y392463D01*
G01X-1597231Y392283D02*
X-1597326Y392463D01*
G01X-1595972Y392104D02*
X-1596035Y392223D01*
G01X-1602585Y392104D02*
X-1602648Y392223D01*
G01X-1597357Y392104D02*
X-1597420Y392223D01*
G01X-1602633Y394469D02*
X-1602739Y394685D01*
G01X-1595781Y391042D02*
X-1594378Y390327D01*
G01X-1602210Y394144D02*
X-1602422Y394253D01*
G01X-1599883Y395387D02*
X-1599671Y395279D01*
G01X-1598666Y395387D02*
X-1598878Y395495D01*
G01X-1600094Y394307D02*
X-1599830Y394144D01*
G01X-1603152Y391265D02*
X-1603058Y391205D01*
G01X-1601767Y391265D02*
X-1601672Y391205D01*
G01X-1602743Y392343D02*
X-1602837Y392403D01*
G01X-1601357Y392343D02*
X-1601452Y392403D01*
G01X-1602869Y393421D02*
X-1602774Y393361D01*
G01X-1601483Y393421D02*
X-1601389Y393361D01*
G01X-1597924Y391265D02*
X-1597830Y391205D01*
G01X-1596539Y391265D02*
X-1596444Y391205D01*
G01X-1597515Y392343D02*
X-1597609Y392403D01*
G01X-1596129Y392343D02*
X-1596224Y392403D01*
G01X-1597641Y393421D02*
X-1597546Y393361D01*
G01X-1596255Y393421D02*
X-1596161Y393361D01*
G01X-1602316Y394577D02*
X-1602157Y394469D01*
G01X-1601100Y396144D02*
X-1601258Y396252D01*
G01X-1599618Y395604D02*
X-1599777Y395711D01*
G01X-1598930Y395171D02*
X-1598772Y395063D01*
G01X-1595846Y392283D02*
X-1595940Y392463D01*
G01X-1598348Y394955D02*
X-1598454Y395171D01*
G01X-1598878Y396144D02*
X-1598824Y396035D01*
G01X-1603845Y392223D02*
X-1603940Y392463D01*
G01X-1603436Y391385D02*
X-1603341Y391145D01*
G01X-1602050Y391385D02*
X-1601956Y391145D01*
G01X-1602491Y393241D02*
X-1602585Y393481D01*
G01X-1601105Y393241D02*
X-1601200Y393481D01*
G01X-1598208Y391385D02*
X-1598113Y391145D01*
G01X-1596822Y391385D02*
X-1596728Y391145D01*
G01X-1597263Y393241D02*
X-1597357Y393481D01*
G01X-1595877Y393241D02*
X-1595972Y393481D01*
G01X-1604034Y392223D02*
X-1603971Y392043D01*
G01X-1603310Y391564D02*
X-1603247Y391385D01*
G01X-1602680Y393241D02*
X-1602617Y393062D01*
G01X-1601924Y391564D02*
X-1601861Y391385D01*
G01X-1601294Y393241D02*
X-1601231Y393062D01*
G01X-1598082Y391564D02*
X-1598019Y391385D01*
G01X-1597452Y393241D02*
X-1597389Y393062D01*
G01X-1596696Y391564D02*
X-1596633Y391385D01*
G01X-1596066Y393241D02*
X-1596003Y393062D01*
G01X-1601046Y395981D02*
X-1601100Y396144D01*
G01X-1599935Y394631D02*
X-1599989Y394793D01*
G01X-1599777Y395711D02*
X-1599830Y395874D01*
G01X-1598507Y396035D02*
X-1598560Y396198D01*
G01X-1602475Y394955D02*
X-1602422Y394739D01*
G01X-1601875Y388911D02*
X-1602038Y390457D01*
G01X-1602157Y394469D02*
X-1601946Y394415D01*
G01X-1599565D02*
X-1599777Y394469D01*
G01X-1599671Y395279D02*
X-1599459Y395225D01*
G01Y395549D02*
X-1599618Y395604D01*
G01X-1603184Y390965D02*
X-1603026Y390905D01*
G01X-1601798Y390965D02*
X-1601641Y390905D01*
G01X-1602711Y392642D02*
X-1602869Y392702D01*
G01X-1597956Y390965D02*
X-1597798Y390905D01*
G01X-1601326Y392642D02*
X-1601483Y392702D01*
G01X-1596570Y390965D02*
X-1596413Y390905D01*
G01X-1602743Y393661D02*
X-1602900Y393720D01*
G01X-1601357Y393661D02*
X-1601515Y393720D01*
G01X-1597483Y392642D02*
X-1597641Y392702D01*
G01X-1596098Y392642D02*
X-1596255Y392702D01*
G01X-1597515Y393661D02*
X-1597672Y393720D01*
G01X-1596129Y393661D02*
X-1596287Y393720D01*
G01X-1600306Y394793D02*
X-1600253Y394577D01*
G01X-1600147Y395820D02*
X-1600094Y395604D01*
G01X-1603782Y391924D02*
X-1603845Y392223D01*
G01X-1603499Y391684D02*
X-1603436Y391385D01*
G01X-1602396Y391983D02*
X-1602459Y392283D01*
G01X-1602113Y391684D02*
X-1602050Y391385D01*
G01X-1601011Y391983D02*
X-1601074Y392283D01*
G01X-1600696Y393421D02*
X-1600759Y393720D01*
G01X-1600129Y390846D02*
X-1600066Y390546D01*
G01X-1600633Y393720D02*
X-1600570Y393421D01*
G01X-1599940Y390546D02*
X-1600003Y390846D01*
G01X-1598271Y391684D02*
X-1598208Y391385D01*
G01X-1597168Y391983D02*
X-1597231Y392283D01*
G01X-1596885Y391684D02*
X-1596822Y391385D01*
G01X-1595783Y391983D02*
X-1595846Y392283D01*
G01X-1595468Y393421D02*
X-1595531Y393720D01*
G01X-1595405D02*
X-1595342Y393421D01*
G01X-1602739Y394685D02*
X-1602793Y394955D01*
G01X-1600782Y396252D02*
X-1600729Y395981D01*
G01X-1603971Y392043D02*
X-1603940Y391864D01*
G01X-1603341Y391744D02*
X-1603310Y391564D01*
G01X-1602554Y391924D02*
X-1602585Y392104D01*
G01X-1602459Y393062D02*
X-1602491Y393241D01*
G01X-1601956Y391744D02*
X-1601924Y391564D01*
G01X-1601168Y391924D02*
X-1601200Y392104D01*
G01X-1601074Y393062D02*
X-1601105Y393241D01*
G01X-1598113Y391744D02*
X-1598082Y391564D01*
G01X-1597326Y391924D02*
X-1597357Y392104D01*
G01X-1597231Y393062D02*
X-1597263Y393241D01*
G01X-1596728Y391744D02*
X-1596696Y391564D01*
G01X-1595940Y391924D02*
X-1595972Y392104D01*
G01X-1595846Y393062D02*
X-1595877Y393241D01*
G01X-1600633Y392882D02*
X-1600696Y393421D01*
G01X-1600570D02*
X-1600507Y392882D01*
G01X-1600192Y391385D02*
X-1600129Y390846D01*
G01X-1600003D02*
X-1600066Y391385D01*
G01X-1595405Y392882D02*
X-1595468Y393421D01*
G01X-1595342D02*
X-1595279Y392882D01*
G01X-1603530Y392104D02*
X-1603499Y391684D01*
G01X-1602145Y392104D02*
X-1602113Y391684D01*
G01X-1598302Y392104D02*
X-1598271Y391684D01*
G01X-1596917Y392104D02*
X-1596885Y391684D01*
G01X-1600602Y392343D02*
X-1600633Y392882D01*
G01X-1600507D02*
X-1600476Y392343D01*
G01X-1600224Y391924D02*
X-1600192Y391385D01*
G01X-1600066D02*
X-1600098Y391924D01*
G01X-1595374Y392343D02*
X-1595405Y392882D01*
G01X-1595279D02*
X-1595248Y392343D01*
G01X-1600218Y397283D02*
X-1600022Y390827D01*
G01X-1603956Y396630D02*
Y394091D01*
G01X-1603940Y391864D02*
Y391744D01*
G01X-1603908Y393189D02*
Y390236D01*
G01X-1603845Y393421D02*
Y393720D01*
G01X-1603809Y393189D02*
Y390827D01*
G01X-1603782Y391684D02*
Y391924D01*
G01X-1603691Y397520D02*
Y390827D01*
G01X-1603533Y394091D02*
Y396630D01*
G01X-1603530Y392523D02*
Y392104D01*
G01X-1603373Y392403D02*
Y392523D01*
G01X-1603341Y391924D02*
Y391744D01*
G01X-1603216Y396630D02*
Y394091D01*
G01X-1602983Y390827D02*
Y389252D01*
G01X-1602824Y390827D02*
Y389252D01*
G01X-1602793Y394955D02*
Y395765D01*
G01X-1602554Y391744D02*
Y391924D01*
G01X-1602475Y395765D02*
Y394955D01*
G01X-1602396Y391684D02*
Y391983D01*
G01X-1602145Y392523D02*
Y392104D01*
G01X-1602037Y390457D02*
Y389252D01*
G01X-1601987Y392403D02*
Y392523D01*
G01X-1601956Y391924D02*
Y391744D01*
G01X-1601446Y389252D02*
Y390827D01*
G01X-1601168Y391744D02*
Y391924D01*
G01X-1601011Y391684D02*
Y391983D01*
G01X-1600602Y391924D02*
Y392343D01*
G01X-1600476D02*
Y391924D01*
G01X-1600224Y392343D02*
Y391924D01*
G01X-1600147Y396035D02*
Y395820D01*
G01X-1600098Y391924D02*
Y392343D01*
G01X-1599830Y395874D02*
Y395981D01*
G01X-1599688Y393421D02*
Y393720D01*
G01X-1598789Y390827D02*
Y393189D01*
G01X-1598666Y394901D02*
Y394739D01*
G01X-1598554Y393720D02*
Y393421D01*
G01X-1598494Y390827D02*
Y389252D01*
G01X-1598348Y394685D02*
Y394955D01*
G01X-1598302Y392523D02*
Y392104D01*
G01X-1598179Y398228D02*
Y390827D01*
G01X-1598145Y392403D02*
Y392523D01*
G01X-1598113Y391924D02*
Y391744D01*
G01X-1597326D02*
Y391924D01*
G01X-1597168Y391684D02*
Y391983D01*
G01X-1597116Y390827D02*
Y389252D01*
G01X-1596917Y392523D02*
Y392104D01*
G01X-1596759Y392403D02*
Y392523D01*
G01X-1596728Y391924D02*
Y391744D01*
G01X-1596604Y402244D02*
Y390827D01*
G01X-1595940Y391744D02*
Y391924D01*
G01X-1595783Y391684D02*
Y391983D01*
G01X-1595738Y391220D02*
Y413653D01*
G01X-1595374Y391924D02*
Y392343D01*
G01X-1595248D02*
Y391924D01*
G01X-1594163Y391220D02*
Y404738D01*
G01X-1601946Y394091D02*
X-1602210Y394144D01*
G01X-1599830D02*
X-1599565Y394091D01*
G01X-1598878Y395495D02*
X-1599142Y395549D01*
G01Y395225D02*
X-1598930Y395171D01*
G01X-1600633Y391385D02*
X-1600602Y391924D01*
G01X-1600476D02*
X-1600507Y391385D01*
G01X-1600192Y392882D02*
X-1600224Y392343D01*
G01X-1600098D02*
X-1600066Y392882D01*
G01X-1595405Y391385D02*
X-1595374Y391924D01*
G01X-1595248D02*
X-1595279Y391385D01*
G01X-1603499Y392942D02*
X-1603530Y392523D01*
G01X-1602113Y392942D02*
X-1602145Y392523D01*
G01X-1598271Y392942D02*
X-1598302Y392523D01*
G01X-1596885Y392942D02*
X-1596917Y392523D01*
G01X-1603373D02*
X-1603341Y392882D01*
G01X-1601987Y392523D02*
X-1601956Y392882D01*
G01X-1598145Y392523D02*
X-1598113Y392882D01*
G01X-1596759Y392523D02*
X-1596728Y392882D01*
G01X-1598813Y388911D02*
X-1598612Y390827D01*
G01X-1600696Y390846D02*
X-1600633Y391385D01*
G01X-1600507D02*
X-1600570Y390846D01*
G01X-1600129Y393421D02*
X-1600192Y392882D01*
G01X-1600066D02*
X-1600003Y393421D01*
G01X-1603908Y390236D02*
X-1603942Y389984D01*
G01X-1595468Y390846D02*
X-1595405Y391385D01*
G01X-1595279D02*
X-1595342Y390846D01*
G01X-1603940Y391744D02*
X-1603971Y391564D01*
G01X-1603341Y392882D02*
X-1603310Y393062D01*
G01Y392104D02*
X-1603341Y391924D01*
G01X-1602585Y391564D02*
X-1602554Y391744D01*
G01X-1601956Y392882D02*
X-1601924Y393062D01*
G01Y392104D02*
X-1601956Y391924D01*
G01X-1601200Y391564D02*
X-1601168Y391744D01*
G01X-1598113Y392882D02*
X-1598082Y393062D01*
G01Y392104D02*
X-1598113Y391924D01*
G01X-1597357Y391564D02*
X-1597326Y391744D01*
G01X-1596728Y392882D02*
X-1596696Y393062D01*
G01Y392104D02*
X-1596728Y391924D01*
G01X-1595972Y391564D02*
X-1595940Y391744D01*
G01X-1602793Y395765D02*
X-1602739Y396035D01*
G01X-1600729Y394739D02*
X-1600782Y394469D01*
G01X-1603845Y391385D02*
X-1603782Y391684D01*
G01X-1603436Y393241D02*
X-1603499Y392942D01*
G01X-1602459Y391385D02*
X-1602396Y391684D01*
G01X-1602050Y393241D02*
X-1602113Y392942D01*
G01X-1601074Y391385D02*
X-1601011Y391684D01*
G01X-1600759Y390546D02*
X-1600696Y390846D01*
G01X-1600066Y393720D02*
X-1600129Y393421D01*
G01X-1600570Y390846D02*
X-1600633Y390546D01*
G01X-1600003Y393421D02*
X-1599940Y393720D01*
G01X-1598208Y393241D02*
X-1598271Y392942D01*
G01X-1597231Y391385D02*
X-1597168Y391684D01*
G01X-1596822Y393241D02*
X-1596885Y392942D01*
G01X-1595846Y391385D02*
X-1595783Y391684D01*
G01X-1595531Y390546D02*
X-1595468Y390846D01*
G01X-1595342D02*
X-1595405Y390546D01*
G01X-1600505Y387677D02*
X-1600184D01*
G01X-1601875Y388911D02*
X-1598813D01*
G01X-1595405Y390546D02*
X-1595531D01*
G01X-1600633D02*
X-1600759D01*
G01X-1600066D02*
X-1599940D01*
G01X-1596131Y390827D02*
X-1598179D01*
G01X-1599184Y390905D02*
X-1599373D01*
G01X-1603026D02*
X-1602869D01*
G01X-1601641D02*
X-1601483D01*
G01X-1597798D02*
X-1597641D01*
G01X-1596413D02*
X-1596255D01*
G01X-1603058Y391205D02*
X-1602837D01*
G01X-1601672D02*
X-1601452D01*
G01X-1597830D02*
X-1597609D01*
G01X-1596444D02*
X-1596224D01*
G01X-1594163Y391220D02*
X-1595738D01*
G01X-1597609Y392403D02*
X-1597830D01*
G01X-1596224D02*
X-1596444D01*
G01X-1601452D02*
X-1601672D01*
G01X-1602837D02*
X-1603058D01*
G01X-1597641Y392702D02*
X-1597798D01*
G01X-1596255D02*
X-1596413D01*
G01X-1601483D02*
X-1601641D01*
G01X-1602869D02*
X-1603026D01*
G01X-1594163Y392767D02*
X-1595738D01*
G01X-1602617Y393062D02*
X-1602459D01*
G01X-1601231D02*
X-1601074D01*
G01X-1597389D02*
X-1597231D01*
G01X-1596003D02*
X-1595846D01*
G01X-1598743Y393421D02*
X-1599688D01*
G01X-1603058D02*
X-1602869D01*
G01X-1601672D02*
X-1601483D01*
G01X-1597830D02*
X-1597641D01*
G01X-1596444D02*
X-1596255D01*
G01X-1597672Y393720D02*
X-1597798D01*
G01X-1596287D02*
X-1596413D01*
G01X-1601515D02*
X-1601641D01*
G01X-1599940D02*
X-1600066D01*
G01X-1602900D02*
X-1603026D01*
G01X-1600759D02*
X-1600633D01*
G01X-1599688D02*
X-1598554D01*
G01X-1595531D02*
X-1595405D01*
G01X-1601470Y394091D02*
X-1601946D01*
G01X-1603216D02*
X-1603533D01*
G01X-1599565D02*
X-1599142D01*
G01Y394415D02*
X-1599565D01*
G01X-1601946D02*
X-1601470D01*
G01X-1601046Y394739D02*
X-1600729D01*
G01X-1599989Y394793D02*
X-1600306D01*
G01X-1599459Y395225D02*
X-1599142D01*
G01Y395549D02*
X-1599459D01*
G01X-1600729Y395981D02*
X-1601046D01*
G01X-1598824Y396035D02*
X-1598507D01*
G01X-1602422Y395981D02*
X-1602475Y395765D01*
G01X-1600094Y396252D02*
X-1600147Y396035D01*
G01X-1599373Y390905D02*
X-1598743Y393421D01*
G01X-1598554D02*
X-1599184Y390905D01*
G01X-1601100Y394577D02*
X-1601046Y394739D01*
G01X-1599830Y395981D02*
X-1599777Y396144D01*
G01X-1603971Y391564D02*
X-1604034Y391385D01*
G01X-1603310Y393062D02*
X-1603247Y393241D01*
G01X-1602648Y391385D02*
X-1602585Y391564D01*
G01X-1601924Y393062D02*
X-1601861Y393241D01*
G01X-1601263Y391385D02*
X-1601200Y391564D01*
G01X-1598082Y393062D02*
X-1598019Y393241D01*
G01X-1597420Y391385D02*
X-1597357Y391564D01*
G01X-1596696Y393062D02*
X-1596633Y393241D01*
G01X-1596035Y391385D02*
X-1595972Y391564D01*
G01X-1603341Y393481D02*
X-1603436Y393241D01*
G01X-1603940Y391145D02*
X-1603845Y391385D01*
G01X-1601956Y393481D02*
X-1602050Y393241D01*
G01X-1602554Y391145D02*
X-1602459Y391385D01*
G01X-1601168Y391145D02*
X-1601074Y391385D01*
G01X-1598113Y393481D02*
X-1598208Y393241D01*
G01X-1596728Y393481D02*
X-1596822Y393241D01*
G01X-1597326Y391145D02*
X-1597231Y391385D01*
G01X-1595940Y391145D02*
X-1595846Y391385D01*
G01X-1598930Y394469D02*
X-1599142Y394415D01*
G01X-1601470D02*
X-1601258Y394469D01*
G01X-1599142Y394091D02*
X-1598878Y394144D01*
G01X-1601205D02*
X-1601470Y394091D01*
G01X-1602739Y396035D02*
X-1602633Y396252D01*
G01X-1598454Y394469D02*
X-1598348Y394685D01*
G01X-1603247Y392223D02*
X-1603310Y392104D01*
G01X-1601861Y392223D02*
X-1601924Y392104D01*
G01X-1598019Y392223D02*
X-1598082Y392104D01*
G01X-1596633Y392223D02*
X-1596696Y392104D01*
G01X-1602316Y396144D02*
X-1602422Y395981D01*
G01X-1598666Y394739D02*
X-1598772Y394577D01*
G01X-1603247Y393241D02*
X-1603152Y393361D01*
G01X-1603184Y392642D02*
X-1603373Y392403D01*
G01X-1604034Y391385D02*
X-1604129Y391265D01*
G01X-1603152Y392343D02*
X-1603247Y392223D01*
G01X-1601861Y393241D02*
X-1601767Y393361D01*
G01X-1601798Y392642D02*
X-1601987Y392403D01*
G01X-1602743Y391265D02*
X-1602648Y391385D01*
G01X-1601767Y392343D02*
X-1601861Y392223D01*
G01X-1601357Y391265D02*
X-1601263Y391385D01*
G01X-1598019Y393241D02*
X-1597924Y393361D01*
G01X-1597956Y392642D02*
X-1598145Y392403D01*
G01X-1597924Y392343D02*
X-1598019Y392223D01*
G01X-1596633Y393241D02*
X-1596539Y393361D01*
G01X-1596570Y392642D02*
X-1596759Y392403D01*
G01X-1597515Y391265D02*
X-1597420Y391385D01*
G01X-1596539Y392343D02*
X-1596633Y392223D01*
G01X-1596129Y391265D02*
X-1596035Y391385D01*
G01X-1603184Y393661D02*
X-1603341Y393481D01*
G01X-1601798Y393661D02*
X-1601956Y393481D01*
G01X-1604097Y390965D02*
X-1603940Y391145D01*
G01X-1602711Y390965D02*
X-1602554Y391145D01*
G01X-1601326Y390965D02*
X-1601168Y391145D01*
G01X-1597956Y393661D02*
X-1598113Y393481D01*
G01X-1596570Y393661D02*
X-1596728Y393481D01*
G01X-1597483Y390965D02*
X-1597326Y391145D01*
G01X-1596098Y390965D02*
X-1595940Y391145D01*
G01X-1600782Y394469D02*
X-1600994Y394253D01*
G01X-1598666D02*
X-1598454Y394469D01*
G01X-1602157Y396252D02*
X-1602316Y396144D01*
G01X-1599777D02*
X-1599618Y396252D01*
G01X-1601258Y394469D02*
X-1601100Y394577D01*
G01X-1598772D02*
X-1598930Y394469D01*
G01X-1603152Y393361D02*
X-1603058Y393421D01*
G01X-1601767Y393361D02*
X-1601672Y393421D01*
G01X-1603058Y392403D02*
X-1603152Y392343D01*
G01X-1601672Y392403D02*
X-1601767Y392343D01*
G01X-1602837Y391205D02*
X-1602743Y391265D01*
G01X-1601452Y391205D02*
X-1601357Y391265D01*
G01X-1597924Y393361D02*
X-1597830Y393421D01*
G01X-1596539Y393361D02*
X-1596444Y393421D01*
G01X-1597830Y392403D02*
X-1597924Y392343D01*
G01X-1596444Y392403D02*
X-1596539Y392343D01*
G01X-1597609Y391205D02*
X-1597515Y391265D01*
G01X-1596224Y391205D02*
X-1596129Y391265D01*
G01X-1600994Y394253D02*
X-1601205Y394144D01*
G01X-1598878D02*
X-1598666Y394253D01*
G01X-1602028Y390456D02*
X-1602024Y390458D01*
G01X-1602028Y390456D02*
X-1601501Y390688D01*
G01X-1602029Y390456D02*
X-1602021Y390459D01*
G01X-1601181Y390827D02*
X-1601757Y390576D01*
G01X-1603026Y393720D02*
X-1603184Y393661D01*
G01X-1601641Y393720D02*
X-1601798Y393661D01*
G01X-1603026Y392702D02*
X-1603184Y392642D01*
G01X-1601641Y392702D02*
X-1601798Y392642D01*
G01X-1597798Y393720D02*
X-1597956Y393661D01*
G01X-1596413Y393720D02*
X-1596570Y393661D01*
G01X-1602869Y390905D02*
X-1602711Y390965D01*
G01X-1597798Y392702D02*
X-1597956Y392642D01*
G01X-1601483Y390905D02*
X-1601326Y390965D01*
G01X-1596413Y392702D02*
X-1596570Y392642D01*
G01X-1597641Y390905D02*
X-1597483Y390965D01*
G01X-1596255Y390905D02*
X-1596098Y390965D01*
G01X-1596131Y389252D02*
G03X-1594163Y391220I-1J1969D01*
G01X-1601875Y388911D02*
G03X-1600505Y387677I1370J144D01*
G01X-1600184D02*
G03X-1598813Y388911I0J1378D01*
G01X-1596131Y390827D02*
G03X-1595738Y391220I-1J394D01*
G01X-1567457Y377174D02*
X-1568376Y390039D01*
G01X-1556497Y376260D02*
X-1566475D01*
G01X-1555515Y377174D02*
X-1567457D01*
G01D02*
G03X-1566475Y376260I982J70D01*
G01X-1568376Y390039D02*
Y400669D01*
G01X-1554596Y390039D02*
X-1568376D01*
G01X-1623442Y407731D02*
X-1623657Y407878D01*
G01X-1614325Y396576D02*
X-1614114Y396414D01*
G01X-1609300D02*
X-1609511Y396576D01*
G01X-1617394Y396468D02*
X-1617182Y396252D01*
G01X-1614272Y396198D02*
X-1614378Y396306D01*
G01X-1623442Y408170D02*
X-1623299Y408024D01*
G01X-1609458Y396198D02*
X-1609564Y396306D01*
G01X-1606866Y396468D02*
X-1606654Y396252D01*
G01X-1621645Y406976D02*
X-1621549Y406862D01*
X-1621427Y406782D01*
G01X-1614114Y396414D02*
X-1613955Y396198D01*
G01X-1609141D02*
X-1609300Y396414D01*
G01X-1623657Y407878D02*
X-1623800Y408097D01*
G01X-1619629Y402244D02*
X-1618946Y401063D01*
G01X-1614361Y397802D02*
X-1614320Y397724D01*
G01X-1623514Y408316D02*
X-1623442Y408170D01*
G01X-1621652Y408609D02*
X-1621795Y408901D01*
G01X-1620257Y405763D02*
X-1620176Y405578D01*
X-1620147Y405382D01*
G01X-1614396Y397882D02*
X-1614359Y397797D01*
G01X-1617605Y396576D02*
X-1617394Y396468D01*
G01X-1607078Y396576D02*
X-1606866Y396468D01*
G01X-1623156Y407585D02*
X-1623442Y407731D01*
G01X-1623299Y408024D02*
X-1623156Y407951D01*
G01X-1612352Y397283D02*
X-1612234Y396968D01*
G01X-1614394Y397877D02*
X-1614426Y397961D01*
G01X-1623800Y408097D02*
X-1623872Y408316D01*
G01X-1614452Y398050D02*
X-1614426Y397963D01*
G01X-1621366Y408901D02*
X-1621294Y408609D01*
G01X-1614473Y398140D02*
X-1614450Y398045D01*
G01X-1617870Y396306D02*
X-1617658Y396252D01*
G01X-1607342Y396306D02*
X-1607130Y396252D01*
G01X-1621296Y406741D02*
X-1621022Y406665D01*
X-1620777Y406539D01*
X-1620564Y406369D01*
X-1620388Y406161D01*
X-1620257Y405921D01*
X-1620176Y405659D01*
X-1620147Y405382D01*
G01X-1614378Y396306D02*
X-1614537Y396360D01*
G01X-1609564Y396306D02*
X-1609723Y396360D01*
G01X-1612106Y403031D02*
X-1611565Y399961D01*
G01X-1614472Y398135D02*
X-1614488Y398228D01*
G01X-1620147Y405382D02*
X-1620198Y405754D01*
X-1620356Y406111D01*
X-1620607Y406409D01*
X-1620933Y406626D01*
X-1621427Y406782D01*
G01X-1621722Y407246D02*
X-1621704Y407109D01*
X-1621645Y406976D01*
G01X-1622817Y404897D02*
X-1622821Y405039D01*
Y405152D01*
X-1622817Y405225D01*
G01X-1623297Y405761D02*
Y404738D01*
G01Y405761D02*
Y413653D01*
G01X-1622811Y404738D02*
Y402118D01*
G01X-1622209Y404708D02*
Y402118D01*
G01X-1621652Y408316D02*
Y408609D01*
G01X-1621296Y406741D02*
Y406343D01*
G01D02*
Y406741D01*
G01Y406343D02*
Y402118D01*
G01X-1621294Y408609D02*
Y408316D01*
G01X-1620226Y403819D02*
Y402244D01*
G01X-1620147Y405382D02*
Y402835D01*
G01X-1619439Y401915D02*
Y398228D01*
G01X-1618946Y401063D02*
Y398694D01*
G01X-1618651Y397209D02*
Y396968D01*
G01X-1618159Y400004D02*
Y400653D01*
G01X-1617683Y397409D02*
Y400572D01*
G01X-1617400Y398228D02*
Y397283D01*
G01X-1617206Y401220D02*
Y397409D01*
G01X-1616387Y398694D02*
Y401063D01*
G01X-1615502Y403819D02*
Y402835D01*
G01X-1614714Y403819D02*
Y402244D01*
G01X-1614320Y398228D02*
Y397283D01*
G01X-1613479Y396360D02*
Y396630D01*
G01X-1612746Y403031D02*
Y403819D01*
G01X-1611565Y397209D02*
Y396968D01*
G01X-1611468Y396630D02*
Y396360D01*
G01X-1609596Y396968D02*
Y397209D01*
G01X-1608809Y396611D02*
Y396529D01*
G01X-1608021Y397209D02*
Y396968D01*
G01X-1606053D02*
Y397209D01*
G01X-1604872Y403819D02*
Y403031D01*
G01X-1621296Y406343D02*
X-1621032Y406292D01*
X-1620787Y406205D01*
X-1620568Y406083D01*
X-1620391Y405935D01*
X-1620257Y405763D01*
G01X-1616813Y396611D02*
X-1618651Y396968D01*
G01X-1616768Y396843D02*
X-1618651Y397209D01*
G01X-1622811Y405249D02*
X-1622960Y405279D01*
X-1623096Y405354D01*
X-1623204Y405466D01*
X-1623274Y405607D01*
X-1623297Y405761D01*
G01X-1617870Y396630D02*
X-1617605Y396576D01*
G01X-1614590Y396630D02*
X-1614325Y396576D01*
G01X-1609511D02*
X-1609776Y396630D01*
G01X-1607342D02*
X-1607078Y396576D01*
G01X-1623156Y407951D02*
X-1622798Y407878D01*
G01X-1609967Y397357D02*
X-1610568Y397480D01*
G01X-1622869Y407512D02*
X-1623156Y407585D01*
G01X-1609410Y397289D02*
X-1608796Y397265D01*
G01X-1622209Y404708D02*
X-1622811Y404738D01*
G01X-1621722Y405195D02*
X-1622811Y405249D01*
G01X-1609994Y397361D02*
X-1609383Y397287D01*
G01X-1605511Y403031D02*
X-1606053Y399961D01*
G01X-1623281Y401934D02*
X-1623297Y401862D01*
G01X-1622811Y405249D02*
X-1622817Y405224D01*
X-1622821Y405152D01*
Y405039D01*
X-1622817Y404897D01*
X-1622811Y404738D01*
G01X-1608822Y397265D02*
X-1608207Y397289D01*
G01X-1621726Y401330D02*
X-1621736D01*
G01X-1604600Y397209D02*
X-1606053Y397207D01*
G01X-1618822Y396306D02*
X-1617870D01*
G01X-1607765D02*
X-1607342D01*
G01X-1609723Y396360D02*
X-1610728D01*
G01X-1612632D02*
X-1613479D01*
G01X-1611468D02*
X-1612315D01*
G01X-1614537D02*
X-1615542D01*
G01X-1616219Y396529D02*
X-1601399D01*
G01X-1600805Y396611D02*
X-1616813D01*
G01X-1609776Y396630D02*
X-1611045D01*
G01X-1619139D02*
X-1617870D01*
G01X-1616600D02*
X-1616283D01*
G01X-1615859D02*
X-1614590D01*
G01X-1613479D02*
X-1611468D01*
G01X-1607765D02*
X-1607342D01*
G01X-1606072D02*
X-1605596D01*
G01X-1604274D02*
X-1603956D01*
G01X-1616199Y396764D02*
X-1601418D01*
G01X-1600850Y396843D02*
X-1616768D01*
G01X-1605383Y396968D02*
X-1612234D01*
G01D02*
X-1618651D01*
G01X-1605383D02*
X-1598966D01*
G01X-1606053Y397205D02*
X-1611565D01*
G01X-1606053Y397209D02*
X-1608021D01*
G01X-1609596D02*
X-1618651D01*
G01X-1606053D02*
X-1598966D01*
G01X-1600218Y397283D02*
X-1617400D01*
G01X-1617206Y397409D02*
X-1617683D01*
G01X-1610636Y397480D02*
X-1606982D01*
G01X-1603691Y397520D02*
X-1613927D01*
G01X-1621722Y398181D02*
X-1623297D01*
G01X-1614320Y398228D02*
X-1619439D01*
G01X-1616387Y398694D02*
X-1618946D01*
G01X-1616387Y399041D02*
X-1618946D01*
G01X-1616387Y399876D02*
X-1618946D01*
G01X-1616387Y399882D02*
X-1618946D01*
G01X-1606053Y399961D02*
X-1611565D01*
G01X-1616387Y400717D02*
X-1618946D01*
G01X-1616387Y401063D02*
X-1618946D01*
G01X-1617683Y401220D02*
X-1617206D01*
G01X-1621722Y401330D02*
X-1622233D01*
G01D02*
X-1623297D01*
G01X-1622233D02*
X-1621754D01*
G01D02*
X-1622234D01*
G01X-1621013Y402118D02*
X-1623156D01*
G01X-1596604Y402244D02*
X-1621013D01*
G01X-1623297Y402433D02*
X-1621722D01*
G01X-1605560Y402756D02*
X-1612057D01*
G01X-1615502Y402835D02*
X-1620226D01*
G01X-1604872Y403031D02*
X-1612746D01*
G01X-1597391Y403819D02*
X-1604872D01*
G01X-1620226D02*
X-1612746D01*
G01X-1623297Y404425D02*
X-1621722D01*
G01X-1622811Y404738D02*
X-1623297D01*
G01Y404992D02*
X-1621722D01*
G01Y405382D02*
X-1620147D01*
G01X-1622296Y407512D02*
X-1622869D01*
G01X-1621722Y407551D02*
X-1623297D01*
G01X-1622798Y407878D02*
X-1622368D01*
G01X-1623297Y408168D02*
X-1621722D01*
G01X-1623872Y408316D02*
X-1623514D01*
G01X-1621754Y401330D02*
X-1621736D01*
G01X-1621885Y402118D02*
X-1621982Y401816D01*
X-1622108Y401567D01*
X-1622234Y401330D01*
G01X-1621294Y408316D02*
X-1621366Y408097D01*
G01X-1621885Y402118D02*
X-1621983Y401822D01*
X-1622106Y401561D01*
X-1622233Y401330D01*
G01X-1608234Y397287D02*
X-1607624Y397361D01*
G01X-1621726Y401330D02*
X-1621722D01*
G01X-1605265Y397283D02*
X-1605383Y396968D01*
G01X-1607650Y397357D02*
X-1607050Y397480D01*
G01X-1608030Y396576D02*
X-1607765Y396630D01*
G01X-1622368Y407878D02*
X-1622010Y407951D01*
G01X-1621724Y408170D02*
X-1621652Y408316D01*
G01X-1623233Y402021D02*
X-1623281Y401935D01*
G01X-1607977Y396252D02*
X-1607765Y396306D01*
G01X-1622010Y407585D02*
X-1622296Y407512D01*
G01X-1615705Y402244D02*
X-1616387Y401063D01*
G01X-1621366Y408097D02*
X-1621509Y407878D01*
G01X-1621722Y405195D02*
X-1621734Y405178D01*
X-1621778Y405130D01*
X-1621844Y405063D01*
G01X-1621722Y405194D02*
X-1621734Y405178D01*
X-1621779Y405128D01*
G01X-1623156Y402118D02*
X-1623234Y402019D01*
G01X-1618159Y400653D02*
X-1617683Y401220D01*
G01Y400572D02*
X-1618159Y400004D01*
G01X-1621778Y405130D02*
X-1621733Y405179D01*
G01X-1621796Y405112D02*
X-1621737Y405175D01*
X-1621722Y405195D01*
G01X-1621867Y408024D02*
X-1621724Y408170D01*
G01X-1608453Y396252D02*
X-1608241Y396468D01*
G01X-1621899Y405008D02*
X-1621778Y405130D01*
G01X-1621899Y405008D02*
X-1622057Y404853D01*
G01X-1622059Y404851D02*
X-1621945Y404962D01*
X-1621845Y405062D01*
G01X-1622209Y404708D02*
X-1622034Y404876D01*
G01X-1621509Y407878D02*
X-1621724Y407731D01*
G01X-1622010Y407951D02*
X-1621867Y408024D01*
G01X-1621724Y407731D02*
X-1622010Y407585D01*
G01X-1608241Y396468D02*
X-1608030Y396576D01*
G01X-1606989Y397478D02*
G03X-1606854Y397516I-1853J6840D01*
G01X-1610777Y397520D02*
G03X-1610629Y397478I2009J6796D01*
G01X-1616813Y396611D02*
G03X-1616219Y396529I1049J5410D01*
G01X-1616767Y396843D02*
G03X-1616199Y396765I1000J5178D01*
G01X-1615620Y399291D02*
G03I-1968J0D01*
G01X-1620541Y409134D02*
G03I-1969J0D01*
G01X-1620147Y405382D02*
G03X-1621296Y406741I-1378J0D01*
G01X-1621722Y407246D02*
G03X-1621296Y406741I512J-1D01*
G01X-1623297Y405761D02*
G03X-1622811Y405249I512J-1D01*
G01X-1616218Y396529D02*
G03X-1601400I7409J88865D01*
G01X-1616199Y396764D02*
G03X-1601419I7390J88630D01*
G01X-1621724Y410729D02*
X-1621437Y410437D01*
G01X-1621509Y409120D02*
X-1621366Y408901D01*
G01X-1621724Y410144D02*
X-1621867Y410364D01*
G01X-1622010Y410876D02*
X-1621724Y410729D01*
G01X-1621795Y408901D02*
X-1622010Y409048D01*
G01X-1621867Y410364D02*
X-1622082Y410510D01*
G01X-1621437Y410437D02*
X-1621366Y410144D01*
G01X-1621867Y409267D02*
X-1621509Y409120D01*
G01X-1623297Y415039D02*
Y413653D01*
G01X-1622726Y409120D02*
Y409413D01*
G01X-1621724Y409998D02*
Y410144D01*
G01X-1621722Y415039D02*
Y413653D01*
G01D02*
X-1621724Y410144D01*
G01X-1621366D02*
Y409998D01*
G01X-1622010Y409048D02*
X-1622440Y409120D01*
G01X-1622082Y410510D02*
X-1622440Y410583D01*
G01X-1622511Y410949D02*
X-1622010Y410876D01*
G01X-1623800Y410144D02*
X-1623729Y410437D01*
G01X-1621366Y409998D02*
X-1621437Y409705D01*
G01X-1621722Y408929D02*
X-1623297D01*
G01X-1622440Y409120D02*
X-1622726D01*
G01Y409413D02*
X-1622440D01*
G01X-1621722Y409689D02*
X-1623297D01*
G01X-1623442Y410144D02*
X-1623800D01*
G01X-1621722Y410307D02*
X-1623297D01*
G01X-1622440Y410583D02*
X-1622726D01*
G01X-1622655Y410949D02*
X-1622511D01*
G01X-1623297Y413653D02*
X-1621722D01*
G01X-1623297Y413858D02*
X-1621722D01*
G01Y414834D02*
X-1623297D01*
G01Y415039D02*
X-1621722D01*
G01X-1622726Y410583D02*
X-1623084Y410510D01*
G01X-1623156Y410876D02*
X-1622655Y410949D01*
G01X-1621867Y409705D02*
X-1621724Y409998D01*
G01X-1623299Y410364D02*
X-1623442Y410144D01*
G01X-1621437Y409705D02*
X-1621580Y409486D01*
G01X-1623729Y410437D02*
X-1623442Y410729D01*
G01X-1622010Y409559D02*
X-1621867Y409705D01*
G01X-1621580Y409486D02*
X-1621867Y409267D01*
G01X-1623084Y410510D02*
X-1623299Y410364D01*
G01X-1623442Y410729D02*
X-1623156Y410876D01*
G01X-1622440Y409413D02*
X-1622010Y409559D01*
G01X-1598719Y396414D02*
X-1598930Y396576D01*
G01X-1596933Y406332D02*
X-1596165Y405601D01*
G01X-1600994Y396468D02*
X-1600782Y396252D01*
G01X-1598730Y400977D02*
X-1598412Y400653D01*
G01X-1594304Y402118D02*
X-1594226Y402019D01*
G01X-1598560Y396198D02*
X-1598719Y396414D01*
G01X-1598809Y400329D02*
X-1598968Y400572D01*
G01X-1601912Y402244D02*
X-1601230Y401063D01*
G01X-1601205Y396576D02*
X-1600994Y396468D01*
G01X-1599047Y401139D02*
X-1598730Y400977D01*
G01X-1598968Y400572D02*
X-1599206Y400734D01*
G01X-1594228Y402021D02*
X-1594180Y401935D01*
X-1594163Y401862D01*
G01X-1595576Y402118D02*
X-1595477Y401822D01*
X-1595355Y401561D01*
X-1595227Y401330D01*
G01X-1595575Y402118D02*
X-1595478Y401816D01*
X-1595352Y401567D01*
X-1595226Y401330D01*
G01X-1599142Y396306D02*
X-1598983Y396252D01*
G01X-1598412Y400653D02*
X-1598332Y400329D01*
G01X-1595252Y404708D02*
X-1595257Y404821D01*
G01X-1595260Y404931D02*
X-1595257Y404822D01*
X-1595252Y404708D01*
G01X-1595262Y405027D02*
X-1595260Y404929D01*
G01X-1596163Y406650D02*
X-1596165Y406723D01*
G01Y406321D02*
X-1596163Y406113D01*
G01X-1595262Y405026D02*
Y405106D01*
X-1595260Y405167D01*
X-1595257Y405206D01*
X-1595252Y405219D01*
G01X-1603297Y398228D02*
Y397283D01*
G01X-1602903Y403819D02*
Y402244D01*
G01X-1602116Y403819D02*
Y402835D01*
G01X-1601230Y401063D02*
Y398694D01*
G01X-1601191Y397409D02*
Y397815D01*
G01X-1600218Y398228D02*
Y397283D01*
G01X-1598966Y397209D02*
Y396968D01*
G01X-1598809Y400166D02*
Y400329D01*
G01X-1598671Y398694D02*
Y401063D01*
G01X-1598332Y400329D02*
Y400166D01*
G01Y397815D02*
Y397409D01*
G01X-1598179Y401915D02*
Y398228D01*
G01X-1597391Y403819D02*
Y402244D01*
G01X-1597313Y405382D02*
Y402244D01*
G01X-1596395Y408535D02*
Y408974D01*
G01X-1596165Y406723D02*
Y405382D01*
G01Y402118D02*
Y405382D01*
G01Y405601D02*
Y406741D01*
G01X-1595252Y404708D02*
Y402118D01*
G01X-1594677Y407512D02*
Y408535D01*
G01X-1594650Y402118D02*
Y404738D01*
G01X-1594247Y408535D02*
Y407512D01*
G01X-1594163Y404738D02*
Y405761D01*
G01D02*
Y413653D01*
G01X-1593531Y408974D02*
Y408535D01*
G01X-1596163Y406113D02*
X-1596165Y405601D01*
G01X-1596164Y406632D02*
X-1596165Y406503D01*
G01Y406741D02*
Y406714D01*
G01X-1599523Y401220D02*
X-1599047Y401139D01*
G01X-1601470Y396630D02*
X-1601205Y396576D01*
G01X-1598930D02*
X-1599195Y396630D01*
G01X-1599206Y400734D02*
X-1599603Y400815D01*
G01X-1601258Y396252D02*
X-1601470Y396306D01*
G01X-1576053Y400846D02*
Y424882D01*
G01X-1574478Y400846D02*
Y424882D01*
G01X-1596165Y406364D02*
X-1596163Y406528D01*
X-1596165Y406714D01*
G01X-1594639Y405039D02*
X-1594643Y404896D01*
X-1594650Y404738D01*
G01D02*
X-1594643Y404897D01*
X-1594639Y405040D01*
Y405152D01*
X-1594643Y405225D01*
X-1594650Y405249D01*
G01X-1594163Y405761D02*
X-1594187Y405607D01*
X-1594255Y405468D01*
X-1594361Y405356D01*
X-1594497Y405281D01*
G01X-1595738Y404708D02*
X-1595714Y404863D01*
X-1595645Y405002D01*
X-1595541Y405111D01*
X-1595407Y405187D01*
X-1595252Y405219D01*
G01X-1594650Y404738D02*
X-1595252Y404708D01*
G01X-1594650Y405249D02*
X-1595252Y405219D01*
G01X-1595707Y401330D02*
X-1595738D01*
G01X-1601470Y396306D02*
X-1601946D01*
G01X-1599459D02*
X-1599142D01*
G01X-1599195Y396630D02*
X-1599459D01*
G01X-1603533D02*
X-1603216D01*
G01X-1601946D02*
X-1601470D01*
G01X-1602015Y397209D02*
X-1603241D01*
G01X-1598332Y397409D02*
X-1601191D01*
G01X-1600555Y397815D02*
X-1598332D01*
G01X-1595738Y398181D02*
X-1594163D01*
G01X-1598179Y398228D02*
X-1603297D01*
G01X-1601230Y398694D02*
X-1598671D01*
G01X-1601230Y399041D02*
X-1598671D01*
G01X-1601230Y399876D02*
X-1598671D01*
G01Y399882D02*
X-1601230D01*
G01X-1600714Y400329D02*
X-1601111D01*
G01X-1601230Y400717D02*
X-1598671D01*
G01X-1599603Y400815D02*
X-1599920D01*
G01X-1576053Y400846D02*
X-1574478D01*
G01X-1598671Y401063D02*
X-1601230D01*
G01X-1599841Y401220D02*
X-1599523D01*
G01X-1595227Y401330D02*
X-1595707D01*
G01X-1595226D02*
X-1595738D01*
G01X-1595226D02*
X-1594163D01*
G01X-1594304Y402118D02*
X-1596604D01*
G01X-1594163Y402433D02*
X-1595738D01*
G01X-1574478Y402815D02*
X-1576053D01*
G01X-1597391Y402835D02*
X-1602116D01*
G01X-1576053Y403996D02*
X-1574478D01*
G01X-1595738Y404425D02*
X-1594163D01*
G01X-1595252Y404708D02*
X-1595738D01*
G01X-1594650Y404738D02*
X-1594163D01*
G01Y404992D02*
X-1595738D01*
G01Y405382D02*
X-1597313D01*
G01X-1594247Y407512D02*
X-1594677D01*
G01X-1595738Y407551D02*
X-1594163D01*
G01X-1595738Y408168D02*
X-1594163D01*
G01X-1574478Y408228D02*
X-1576053D01*
G01X-1593531Y408535D02*
X-1594247D01*
G01X-1594677D02*
X-1596395D01*
G01X-1601111Y400329D02*
X-1601032Y400653D01*
G01X-1598332Y400166D02*
X-1598412Y399842D01*
G01X-1600397Y401139D02*
X-1599841Y401220D01*
G01X-1599459Y396630D02*
X-1599671Y396576D01*
G01X-1594497Y405281D02*
X-1594650Y405249D01*
G01X-1602210Y396576D02*
X-1601946Y396630D01*
G01X-1599920Y400815D02*
X-1600317Y400734D01*
G01X-1600805Y396611D02*
X-1598966Y396968D01*
G01Y397209D02*
X-1600850Y396843D01*
G01X-1595252Y405219D02*
X-1595375Y405198D01*
X-1595495Y405144D01*
X-1595598Y405060D01*
X-1595676Y404952D01*
X-1595723Y404831D01*
X-1595738Y404708D01*
G01X-1598968Y399842D02*
X-1598809Y400166D01*
G01X-1601946Y396306D02*
X-1602157Y396252D01*
G01X-1597989Y402244D02*
X-1598671Y401063D01*
G01X-1600555Y400572D02*
X-1600714Y400329D01*
G01X-1598412Y399842D02*
X-1598570Y399599D01*
G01X-1601032Y400653D02*
X-1600714Y400977D01*
G01X-1602633Y396252D02*
X-1602422Y396468D01*
G01X-1599883D02*
X-1600094Y396252D01*
G01X-1601191Y397815D02*
X-1598968Y399842D01*
G01X-1598570Y399599D02*
X-1600555Y397815D01*
G01X-1600317Y400734D02*
X-1600555Y400572D01*
G01X-1600714Y400977D02*
X-1600397Y401139D01*
G01X-1602422Y396468D02*
X-1602210Y396576D01*
G01X-1599671D02*
X-1599883Y396468D01*
G01X-1596165Y406723D02*
X-1596371Y406622D01*
X-1596559Y406457D01*
X-1596716Y406240D01*
X-1596835Y405980D01*
X-1596908Y405690D01*
X-1596933Y405382D01*
G01X-1599618Y396252D02*
X-1599459Y396306D01*
G01X-1596165Y406741D02*
X-1596523Y406628D01*
X-1596854Y406409D01*
X-1597106Y406108D01*
X-1597263Y405749D01*
X-1597313Y405382D01*
G01X-1601399Y396529D02*
G03X-1600805Y396611I-455J5492D01*
G01X-1601418Y396765D02*
G03X-1600850Y396843I-432J5256D01*
G01X-1597903Y399291D02*
G03I-1969J0D01*
G01X-1596165Y406741D02*
G03X-1597313Y405382I230J-1359D01*
G01X-1596165Y406741D02*
G03X-1595738Y407246I-85J505D01*
G01X-1576053Y401457D02*
G03X-1573691Y399094I2362J-1D01*
G01X-1592982Y409134D02*
G03I-1969J0D01*
G01X-1574478Y401457D02*
G03X-1573691Y400669I787J-1D01*
G01X-1594650Y405249D02*
G03X-1594163Y405761I-25J511D01*
G01X-1595252Y405219D02*
G03X-1595738Y404708I26J-511D01*
G01X-1576997Y420354D02*
X-1576198Y419719D01*
G01X-1574715D02*
X-1575513Y420354D01*
G01X-1576198Y419719D02*
X-1576146Y419659D01*
X-1576100Y419566D01*
X-1576061Y419446D01*
X-1576031Y419302D01*
X-1576013Y419143D01*
X-1576007Y418976D01*
G01X-1595738Y415039D02*
Y413653D01*
G01X-1594677Y410364D02*
Y408974D01*
G01X-1594247Y410949D02*
Y408974D01*
G01X-1594163Y415039D02*
Y413653D01*
G01X-1574524Y418976D02*
X-1574530Y419141D01*
X-1574548Y419301D01*
X-1574576Y419443D01*
X-1574615Y419565D01*
X-1574662Y419658D01*
X-1574715Y419719D01*
G01X-1578218Y420354D02*
Y417598D01*
G01X-1578083D02*
Y420354D01*
G01X-1578059D02*
Y417598D01*
G01X-1576644Y420354D02*
Y417598D01*
G01X-1576585D02*
Y420354D01*
G01X-1576576D02*
Y417598D01*
G01X-1576055D02*
Y420354D01*
G01X-1574557Y417598D02*
Y420354D01*
G01X-1574498Y413937D02*
Y412087D01*
G01X-1576007Y418976D02*
X-1576013Y418811D01*
X-1576031Y418652D01*
X-1576060Y418510D01*
X-1576099Y418388D01*
X-1576146Y418294D01*
X-1576198Y418234D01*
G01X-1594163Y408929D02*
X-1595738D01*
G01X-1594677Y408974D02*
X-1595894D01*
G01X-1594247D02*
X-1593531D01*
G01X-1595738Y409689D02*
X-1594163D01*
G01Y410307D02*
X-1595738D01*
G01X-1594677Y410949D02*
X-1594247D01*
G01X-1576053Y411378D02*
X-1574478D01*
G01X-1548474Y412087D02*
X-1574498D01*
G01X-1576053Y412480D02*
X-1574478D01*
G01X-1594163Y413653D02*
X-1595738D01*
G01X-1594163Y413858D02*
X-1595738D01*
G01X-1576053Y414449D02*
X-1574478D01*
G01X-1594163Y414834D02*
X-1595738D01*
G01X-1594163Y415039D02*
X-1595738D01*
G01X-1576053Y415074D02*
X-1574478D01*
G01X-1576053Y416417D02*
X-1574478D01*
G01Y417598D02*
X-1578218D01*
G01X-1576198Y418234D02*
X-1574715D01*
G01X-1574478Y418976D02*
X-1576053D01*
G01X-1576198Y419719D02*
X-1574715D01*
G01X-1576053Y420157D02*
X-1574478D01*
G01Y420354D02*
X-1578218D01*
G01X-1574478Y423701D02*
X-1576053D01*
G01X-1574478Y424882D02*
X-1576053D01*
G01X-1596395Y408974D02*
X-1594677Y410949D01*
G01X-1595894Y408974D02*
X-1594677Y410364D01*
G01X-1574715Y418234D02*
X-1574663Y418294D01*
X-1574616Y418387D01*
X-1574577Y418507D01*
X-1574548Y418650D01*
X-1574530Y418810D01*
X-1574524Y418976D01*
G01X-1576198Y418234D02*
X-1576997Y417598D01*
G01X-1575513D02*
X-1574715Y418234D01*
G01X-1576053Y416418D02*
G03X-1574831Y414468I2166J-1D01*
G01X-1573297Y418976D02*
G03I-1969J0D01*
G01X-1574478Y416418D02*
G03X-1574145Y415886I591J-1D01*
G01X-1574498Y413937D02*
G03X-1574831Y414468I-590J0D01*
G01X-1566407Y473110D02*
G03I-18701J0D01*
G01X-1573691Y412087D02*
Y400669D01*
G01X-1573100D02*
Y399094D01*
G01X-1572509Y412087D02*
Y400669D01*
G01X-1572313Y397520D02*
Y399094D01*
G01X-1571722Y408543D02*
Y410905D01*
G01X-1571604Y408031D02*
Y410236D01*
G01X-1571525Y400669D02*
Y399094D01*
G01X-1571328Y409016D02*
Y408031D01*
G01X-1571131Y409724D02*
Y408543D01*
G01X-1569557Y409724D02*
Y408543D01*
G01X-1569261Y408031D02*
Y409861D01*
G01X-1568986Y410236D02*
Y408031D01*
G01X-1568966Y408543D02*
Y410905D01*
G01X-1568769Y400669D02*
Y399094D01*
G01X-1567982Y400669D02*
Y399094D01*
G01X-1567588Y397520D02*
Y399094D01*
G01X-1567391Y400669D02*
Y399094D01*
G01X-1564439Y400669D02*
Y399094D01*
G01X-1567588Y397520D02*
X-1572313D01*
G01X-1549281Y399094D02*
X-1573691D01*
G01X-1549281Y400669D02*
X-1573691D01*
G01X-1571328Y408031D02*
X-1571604D01*
G01X-1568986D02*
X-1569261D01*
G01X-1568966Y408543D02*
X-1571722D01*
G01X-1568966Y408809D02*
X-1571722D01*
G01X-1568376Y409134D02*
G03I-1968J0D01*
G01X-1570272Y410189D02*
X-1570088Y410048D01*
G01X-1570226Y409861D02*
X-1570318Y409955D01*
G01X-1570088Y410048D02*
X-1569950Y409861D01*
G01X-1570180Y409720D02*
X-1570226Y409861D01*
G01X-1569950D02*
X-1569905Y409720D01*
G01X-1570502Y410236D02*
X-1570272Y410189D01*
G01X-1570318Y409955D02*
X-1570456Y410002D01*
G01X-1572923Y413937D02*
Y412087D01*
G01X-1572903D02*
Y413661D01*
G01X-1571328Y410002D02*
Y409298D01*
G01X-1570180Y409579D02*
Y409720D01*
G01X-1569905D02*
Y409533D01*
G01X-1569537D02*
Y409908D01*
G01X-1568179Y412677D02*
Y413661D01*
G01X-1567391D02*
Y412087D01*
G01X-1565423Y413661D02*
Y412874D01*
G01X-1570502Y409016D02*
X-1571328D01*
G01Y409298D02*
X-1570456D01*
G01X-1568966Y409658D02*
X-1571722D01*
G01X-1568966Y409724D02*
X-1571722D01*
G01X-1568966Y409791D02*
X-1571722D01*
G01X-1570456Y410002D02*
X-1571328D01*
G01X-1571604Y410236D02*
X-1570502D01*
G01X-1569261D02*
X-1568986D01*
G01X-1568966Y410639D02*
X-1571722D01*
G01X-1568966Y410905D02*
X-1571722D01*
G01X-1568179Y412677D02*
X-1572903D01*
G01X-1557549Y412874D02*
X-1565423D01*
G01Y413661D02*
X-1572903D01*
G01X-1570226Y409439D02*
X-1570180Y409579D01*
G01X-1569905Y409533D02*
X-1569950Y409392D01*
G01X-1570272Y409063D02*
X-1570502Y409016D01*
G01X-1569950Y409392D02*
X-1570088Y409204D01*
G01X-1569537Y409908D02*
X-1569261Y410236D01*
G01Y409861D02*
X-1569537Y409533D01*
G01X-1570318Y409345D02*
X-1570226Y409439D01*
G01X-1570088Y409204D02*
X-1570272Y409063D01*
G01X-1570456Y409298D02*
X-1570318Y409345D01*
G01X-1572923Y413937D02*
G03X-1574145Y415886I-2165J0D01*
G01X-1614990Y524764D02*
Y536575D01*
G01X-1613513Y530292D02*
Y524764D01*
G01X-1606624D02*
Y530292D01*
G01X-1605147Y536575D02*
Y524764D01*
G01D02*
X-1606624D01*
G01X-1613513D02*
X-1614990D01*
G01X-1578218Y473110D02*
G03I-6890J0D01*
G01X-1595305Y526774D02*
X-1594567Y525769D01*
G01X-1594320Y527528D02*
X-1593828Y526774D01*
G01X-1595797Y528031D02*
X-1595305Y526774D01*
G01X-1593828D02*
X-1593090Y526272D01*
G01X-1585216Y524764D02*
Y532805D01*
G01X-1583986Y531046D02*
Y524764D01*
G01X-1581279D02*
Y530795D01*
G01X-1580049D02*
Y524764D01*
G01X-1577342D02*
Y530795D01*
G01X-1576112D02*
Y524764D01*
G01X-1594567Y525769D02*
X-1593336Y525015D01*
G01X-1593090Y526272D02*
X-1592352Y526020D01*
G01X-1587677Y526774D02*
X-1587185Y528031D01*
G01X-1593336Y525015D02*
X-1592106Y524764D01*
G01X-1589153Y526774D02*
X-1588661Y527528D01*
G01X-1576112Y524764D02*
X-1577342D01*
G01X-1580049D02*
X-1581279D01*
G01X-1583986D02*
X-1585216D01*
G01X-1592106D02*
X-1590876D01*
G01X-1592352Y526020D02*
X-1590630D01*
G01X-1588415Y525769D02*
X-1587677Y526774D01*
G01X-1590876Y524764D02*
X-1589645Y525015D01*
G01X-1589891Y526272D02*
X-1589153Y526774D01*
G01X-1589645Y525015D02*
X-1588415Y525769D01*
G01X-1590630Y526020D02*
X-1589891Y526272D01*
G01X-1574143Y524764D02*
Y532805D01*
G01X-1572913Y531046D02*
Y524764D01*
G01X-1570206D02*
Y530795D01*
G01X-1568976D02*
Y524764D01*
G01X-1566269D02*
Y530795D01*
G01X-1565039D02*
Y524764D01*
G01D02*
X-1566269D01*
G01X-1568976D02*
X-1570206D01*
G01X-1572913D02*
X-1574143D01*
G01X-1613513Y536575D02*
Y531800D01*
G01X-1606624D02*
Y536575D01*
G01Y530292D02*
X-1613513D01*
G01Y531800D02*
X-1606624D01*
G01X-1614990Y536575D02*
X-1613513D01*
G01X-1606624D02*
X-1605147D01*
G01X-1617746Y572835D02*
Y586220D01*
G01X-1616072D02*
Y580809D01*
G01Y579100D02*
Y572835D01*
G01X-1608264D02*
Y579100D01*
G01Y580809D02*
Y586220D01*
G01X-1606591D02*
Y572835D01*
G01X-1604360Y577392D02*
Y578531D01*
G01Y580809D02*
Y581948D01*
G01X-1606591Y572835D02*
X-1608264D01*
G01X-1616072D02*
X-1617746D01*
G01X-1599898Y577392D02*
X-1604360D01*
G01Y578531D02*
X-1599898D01*
G01X-1608264Y579100D02*
X-1616072D01*
G01X-1599898Y580809D02*
X-1604360D01*
G01X-1616072D02*
X-1608264D01*
G01X-1604360Y581948D02*
X-1599898D01*
G01X-1617746Y586220D02*
X-1616072D01*
G01X-1608264D02*
X-1606591D01*
G01X-1594567Y528282D02*
X-1594320Y527528D01*
G01X-1594567Y529036D02*
Y528282D01*
G01X-1596043Y529790D02*
X-1595797Y528031D01*
G01X-1588415Y528282D02*
Y529036D01*
G01X-1587185Y528031D02*
Y529287D01*
G01X-1598504Y528282D02*
X-1603179Y530795D01*
G01X-1588661Y527528D02*
X-1588415Y528282D01*
G01X-1598011Y529036D02*
X-1598504Y528282D01*
G01X-1587923Y534565D02*
X-1588661Y535570D01*
G01X-1598504Y533308D02*
X-1598011Y532554D01*
G01X-1589399Y534565D02*
X-1588907Y533811D01*
G01X-1581279Y530795D02*
X-1581525Y531298D01*
G01X-1587185Y529287D02*
X-1587677Y530544D01*
G01X-1588415Y529036D02*
X-1588661Y529790D01*
G01X-1587677Y533811D02*
X-1587923Y534565D01*
G01X-1596043Y531549D02*
Y529790D01*
G01X-1594813Y531046D02*
Y531549D01*
G01X-1589153Y530292D02*
X-1589891Y530795D01*
G01X-1588661Y529790D02*
X-1589153Y530292D01*
G01X-1587677Y530544D02*
X-1588415Y531298D01*
G01X-1581525D02*
X-1581771Y531549D01*
G01X-1581033Y532554D02*
X-1580295Y531800D01*
G01X-1577588Y531298D02*
X-1577834Y531549D01*
G01X-1577096Y532554D02*
X-1576604Y532052D01*
G01X-1577342Y530795D02*
X-1577588Y531298D01*
G01X-1576604Y532052D02*
X-1576112Y530795D01*
G01X-1583986Y532805D02*
Y532052D01*
G01X-1595797Y533308D02*
X-1596043Y531549D01*
G01X-1594813D02*
X-1594567Y533057D01*
G01X-1601456Y530795D02*
X-1598011Y529036D01*
G01X-1581771Y531549D02*
X-1582263Y531800D01*
G01X-1577834Y531549D02*
X-1578326Y531800D01*
G01X-1588415Y531298D02*
X-1589645Y532052D01*
G01X-1588661Y535570D02*
X-1589891Y536324D01*
G01X-1590137Y535067D02*
X-1589399Y534565D01*
G01X-1589891Y530795D02*
X-1590630Y531046D01*
G01X-1590876Y535318D02*
X-1590137Y535067D01*
G01X-1581771Y532805D02*
X-1581033Y532554D01*
G01X-1577834Y532805D02*
X-1577096Y532554D01*
G01X-1594567Y533057D02*
X-1594320Y533811D01*
G01Y529790D02*
X-1594567Y529036D01*
G01X-1595305Y534565D02*
X-1595797Y533308D01*
G01X-1589645Y532052D02*
X-1590876Y532303D01*
G01X-1589891Y536324D02*
X-1591122Y536575D01*
G01X-1579803Y531298D02*
X-1580049Y530795D01*
G01X-1594320Y533811D02*
X-1593828Y534565D01*
G01X-1594567Y535570D02*
X-1595305Y534565D01*
G01X-1590630Y531046D02*
X-1592352D01*
G01X-1578326Y531800D02*
X-1579065D01*
G01X-1582263D02*
X-1582755D01*
G01X-1590876Y532303D02*
X-1592106D01*
G01X-1585216Y532805D02*
X-1583986D01*
G01X-1582755D02*
X-1581771D01*
G01X-1578818D02*
X-1577834D01*
G01X-1588907Y533811D02*
X-1587677D01*
G01X-1592352Y535318D02*
X-1590876D01*
G01X-1591122Y536575D02*
X-1592106D01*
G01X-1593828Y530292D02*
X-1594320Y529790D01*
G01X-1583986Y532052D02*
X-1583494Y532554D01*
G01Y531549D02*
X-1583986Y531046D01*
G01X-1580295Y531800D02*
X-1579557Y532554D01*
G01Y531549D02*
X-1579803Y531298D01*
G01X-1592106Y532303D02*
X-1593336Y532052D01*
G01X-1592106Y536575D02*
X-1593336Y536324D01*
G01X-1593828Y534565D02*
X-1593090Y535067D01*
G01X-1593336Y532052D02*
X-1594813Y531046D01*
G01X-1593090Y530795D02*
X-1593828Y530292D01*
G01X-1593336Y536324D02*
X-1594567Y535570D01*
G01X-1603179Y530795D02*
X-1598504Y533308D01*
G01X-1598011Y532554D02*
X-1601456Y530795D01*
G01X-1579065Y531800D02*
X-1579557Y531549D01*
G01X-1593090Y535067D02*
X-1592352Y535318D01*
G01Y531046D02*
X-1593090Y530795D01*
G01X-1583494Y532554D02*
X-1582755Y532805D01*
G01Y531800D02*
X-1583494Y531549D01*
G01X-1579557Y532554D02*
X-1578818Y532805D01*
G01X-1599898Y581948D02*
Y580809D01*
G01Y578531D02*
Y577392D01*
G01X-1597667Y580809D02*
Y578246D01*
G01X-1596273Y580524D02*
Y578531D01*
G01X-1596552Y574828D02*
X-1595715Y573974D01*
G01X-1595994Y576822D02*
X-1594878Y575113D01*
G01X-1589301Y582233D02*
X-1590417Y583942D01*
G01X-1597109Y575968D02*
X-1596552Y574828D01*
G01X-1588185Y583088D02*
X-1588743Y584227D01*
G01X-1580935Y579670D02*
X-1581214Y580240D01*
G01X-1576473Y579670D02*
X-1576752Y580240D01*
G01X-1575636Y581094D02*
X-1575078Y579670D01*
G01X-1597388Y576822D02*
X-1597109Y575968D01*
G01X-1587907Y582233D02*
X-1588185Y583088D01*
G01X-1597667Y578246D02*
X-1597388Y576822D01*
G01X-1587628Y580809D02*
X-1587907Y582233D01*
G01X-1596273Y578531D02*
X-1595994Y576822D01*
G01X-1589022Y580524D02*
X-1589301Y582233D01*
G01X-1589022Y578531D02*
Y580524D01*
G01X-1587628Y578246D02*
Y580809D01*
G01X-1585397Y572835D02*
Y581948D01*
G01X-1584002D02*
Y581094D01*
G01Y579955D02*
Y572835D01*
G01X-1580935D02*
Y579670D01*
G01X-1579541D02*
Y572835D01*
G01X-1576473D02*
Y579670D01*
G01X-1575078D02*
Y572835D01*
G01X-1595994Y582233D02*
X-1596273Y580524D01*
G01X-1589301Y576822D02*
X-1589022Y578531D01*
G01X-1597388Y582233D02*
X-1597667Y580809D01*
G01X-1594878Y575113D02*
X-1594042Y574543D01*
G01X-1588743Y584227D02*
X-1589580Y585081D01*
G01X-1581214Y580240D02*
X-1581493Y580524D01*
G01X-1580656Y581664D02*
X-1579819Y580809D01*
G01X-1576752Y580240D02*
X-1577031Y580524D01*
G01X-1576194Y581664D02*
X-1575636Y581094D01*
G01X-1587907Y576822D02*
X-1587628Y578246D01*
G01X-1597109Y583088D02*
X-1597388Y582233D01*
G01X-1588185Y575968D02*
X-1587907Y576822D01*
G01X-1581493Y580524D02*
X-1582050Y580809D01*
G01X-1577031Y580524D02*
X-1577588Y580809D01*
G01X-1595715Y573974D02*
X-1594320Y573119D01*
G01X-1589580Y585081D02*
X-1590974Y585936D01*
G01X-1590417Y583942D02*
X-1591253Y584512D01*
G01X-1596552Y584227D02*
X-1597109Y583088D01*
G01X-1588743Y574828D02*
X-1588185Y575968D01*
G01X-1581493Y581948D02*
X-1580656Y581664D01*
G01X-1577031Y581948D02*
X-1576194Y581664D01*
G01X-1579261Y580240D02*
X-1579541Y579670D01*
G01X-1594878Y583942D02*
X-1595994Y582233D01*
G01X-1590417Y575113D02*
X-1589301Y576822D01*
G01X-1594042Y574543D02*
X-1592647Y574259D01*
G01X-1594320Y573119D02*
X-1592647Y572835D01*
G01X-1590974Y585936D02*
X-1592647Y586220D01*
G01X-1591253Y584512D02*
X-1592647Y584796D01*
G01X-1595715Y585081D02*
X-1596552Y584227D01*
G01X-1584002Y581094D02*
X-1583444Y581664D01*
G01Y580524D02*
X-1584002Y579955D01*
G01X-1589580Y573974D02*
X-1588743Y574828D01*
G01X-1579819Y580809D02*
X-1578983Y581664D01*
G01Y580524D02*
X-1579261Y580240D01*
G01X-1575078Y572835D02*
X-1576473D01*
G01X-1579541D02*
X-1580935D01*
G01X-1584002D02*
X-1585397D01*
G01X-1577588Y580809D02*
X-1578425D01*
G01X-1582050D02*
X-1582608D01*
G01X-1585397Y581948D02*
X-1584002D01*
G01X-1582608D02*
X-1581493D01*
G01X-1578146D02*
X-1577031D01*
G01X-1594042Y584512D02*
X-1594878Y583942D01*
G01X-1591253Y574543D02*
X-1590417Y575113D01*
G01X-1592647Y574259D02*
X-1591253Y574543D01*
G01X-1592647Y584796D02*
X-1594042Y584512D01*
G01X-1592647Y572835D02*
X-1590974Y573119D01*
G01X-1592647Y586220D02*
X-1594320Y585936D01*
G01D02*
X-1595715Y585081D01*
G01X-1590974Y573119D02*
X-1589580Y573974D01*
G01X-1578425Y580809D02*
X-1578983Y580524D01*
G01X-1583444Y581664D02*
X-1582608Y581948D01*
G01Y580809D02*
X-1583444Y580524D01*
G01X-1578983Y581664D02*
X-1578146Y581948D01*
G01X-1542342Y610405D02*
G03I-19907J0D01*
G01X-1570452Y531298D02*
X-1570698Y531549D01*
G01X-1569960Y532554D02*
X-1569222Y531800D01*
G01X-1566515Y531298D02*
X-1566761Y531549D01*
G01X-1566023Y532554D02*
X-1565531Y532052D01*
G01X-1570206Y530795D02*
X-1570452Y531298D01*
G01X-1566269Y530795D02*
X-1566515Y531298D01*
G01X-1565531Y532052D02*
X-1565039Y530795D01*
G01X-1572913Y532805D02*
Y532052D01*
G01X-1570698Y531549D02*
X-1571191Y531800D01*
G01X-1566761Y531549D02*
X-1567254Y531800D01*
G01X-1570698Y532805D02*
X-1569960Y532554D01*
G01X-1566761Y532805D02*
X-1566023Y532554D01*
G01X-1568730Y531298D02*
X-1568976Y530795D01*
G01X-1567254Y531800D02*
X-1567992D01*
G01X-1571191D02*
X-1571683D01*
G01X-1574143Y532805D02*
X-1572913D01*
G01X-1571683D02*
X-1570698D01*
G01X-1567746D02*
X-1566761D01*
G01X-1572913Y532052D02*
X-1572421Y532554D01*
G01Y531549D02*
X-1572913Y531046D01*
G01X-1569222Y531800D02*
X-1568484Y532554D01*
G01Y531549D02*
X-1568730Y531298D01*
G01X-1567992Y531800D02*
X-1568484Y531549D01*
G01X-1572421Y532554D02*
X-1571683Y532805D01*
G01Y531800D02*
X-1572421Y531549D01*
G01X-1568484Y532554D02*
X-1567746Y532805D01*
G01X-1568385Y579670D02*
X-1568665Y580240D01*
G01X-1563924Y579670D02*
X-1564202Y580240D01*
G01X-1563087Y581094D02*
X-1562529Y579670D01*
G01X-1572848Y572835D02*
Y581948D01*
G01X-1571453D02*
Y581094D01*
G01Y579955D02*
Y572835D01*
G01X-1568385D02*
Y579670D01*
G01X-1566991D02*
Y572835D01*
G01X-1563924D02*
Y579670D01*
G01X-1562529D02*
Y572835D01*
G01X-1568665Y580240D02*
X-1568943Y580524D01*
G01X-1568107Y581664D02*
X-1567270Y580809D01*
G01X-1564202Y580240D02*
X-1564481Y580524D01*
G01X-1563645Y581664D02*
X-1563087Y581094D01*
G01X-1568943Y580524D02*
X-1569501Y580809D01*
G01X-1564481Y580524D02*
X-1565039Y580809D01*
G01X-1566712Y580240D02*
X-1566991Y579670D01*
G01X-1568943Y581948D02*
X-1568107Y581664D01*
G01X-1564481Y581948D02*
X-1563645Y581664D01*
G01X-1562529Y572835D02*
X-1563924D01*
G01X-1566991D02*
X-1568385D01*
G01X-1571453D02*
X-1572848D01*
G01X-1565039Y580809D02*
X-1565876D01*
G01X-1569501D02*
X-1570059D01*
G01X-1572848Y581948D02*
X-1571453D01*
G01X-1570059D02*
X-1568943D01*
G01X-1565597D02*
X-1564481D01*
G01X-1571453Y581094D02*
X-1570895Y581664D01*
G01Y580524D02*
X-1571453Y579955D01*
G01X-1567270Y580809D02*
X-1566433Y581664D01*
G01Y580524D02*
X-1566712Y580240D01*
G01X-1565876Y580809D02*
X-1566433Y580524D01*
G01X-1570895Y581664D02*
X-1570059Y581948D01*
G01Y580809D02*
X-1570895Y580524D01*
G01X-1566433Y581664D02*
X-1565597Y581948D01*
G01X-1621919Y594370D02*
Y631772D01*
G01X-1616053Y598819D02*
Y606496D01*
G01X-1615093D02*
Y603392D01*
G01Y602413D02*
Y598819D01*
G01X-1610615D02*
Y602413D01*
G01Y603392D02*
Y606496D01*
G01X-1609655D02*
Y598819D01*
G01X-1608376Y601432D02*
Y602086D01*
G01Y603392D02*
Y604046D01*
G01X-1605817D02*
Y603392D01*
G01Y602086D02*
Y601432D01*
G01X-1604537Y603392D02*
Y601922D01*
G01X-1604377Y601106D02*
X-1604217Y600616D01*
G01X-1604537Y601922D02*
X-1604377Y601106D01*
G01Y604209D02*
X-1604537Y603392D01*
G01X-1604217Y604699D02*
X-1604377Y604209D01*
G01X-1609655Y598819D02*
X-1610615D01*
G01X-1615093D02*
X-1616053D01*
G01X-1605817Y601432D02*
X-1608376D01*
G01Y602086D02*
X-1605817D01*
G01X-1610615Y602413D02*
X-1615093D01*
G01X-1605817Y603392D02*
X-1608376D01*
G01X-1615093D02*
X-1610615D01*
G01X-1608376Y604046D02*
X-1605817D01*
G01X-1616053Y606496D02*
X-1615093D01*
G01X-1610615D02*
X-1609655D01*
G01X-1603737Y603229D02*
Y602086D01*
G01X-1599579D02*
Y603229D01*
G01X-1598779Y601922D02*
Y603392D01*
G01X-1597500Y598819D02*
Y604046D01*
G01X-1596700D02*
Y603556D01*
G01Y602902D02*
Y598819D01*
G01X-1594941D02*
Y602739D01*
G01X-1594141D02*
Y598819D01*
G01X-1603578Y601106D02*
X-1602938Y600126D01*
G01X-1599739Y604209D02*
X-1600379Y605189D01*
G01X-1604217Y600616D02*
X-1603897Y599962D01*
G01X-1599099Y604699D02*
X-1599419Y605353D01*
G01X-1594941Y602739D02*
X-1595101Y603066D01*
G01X-1592381Y602739D02*
X-1592542Y603066D01*
G01X-1587743Y602739D02*
X-1587903Y603066D01*
G01X-1585184Y602739D02*
X-1585344Y603066D01*
G01X-1591902Y603556D02*
X-1591582Y602739D01*
G01X-1584704Y603556D02*
X-1584385Y602739D01*
G01X-1598939Y604209D02*
X-1599099Y604699D01*
G01X-1598779Y603392D02*
X-1598939Y604209D01*
G01X-1603737Y602086D02*
X-1603578Y601106D01*
G01X-1599579Y603229D02*
X-1599739Y604209D01*
G01X-1592381Y598819D02*
Y602739D01*
G01X-1591582D02*
Y598819D01*
G01X-1590302D02*
Y604046D01*
G01X-1589503D02*
Y603556D01*
G01Y602902D02*
Y598819D01*
G01X-1587743D02*
Y602739D01*
G01X-1586944D02*
Y598819D01*
G01X-1585184D02*
Y602739D01*
G01X-1584385D02*
Y598819D01*
G01X-1603578Y604209D02*
X-1603737Y603229D01*
G01X-1599739Y601106D02*
X-1599579Y602086D01*
G01X-1598939Y601106D02*
X-1598779Y601922D01*
G01X-1603897Y599962D02*
X-1603418Y599472D01*
G01X-1599419Y605353D02*
X-1599899Y605842D01*
G01X-1595101Y603066D02*
X-1595261Y603229D01*
G01X-1594781Y603883D02*
X-1594301Y603392D01*
G01X-1592542Y603066D02*
X-1592702Y603229D01*
G01X-1592222Y603883D02*
X-1591902Y603556D01*
G01X-1587903Y603066D02*
X-1588063Y603229D01*
G01X-1587583Y603883D02*
X-1587104Y603392D01*
G01X-1585344Y603066D02*
X-1585504Y603229D01*
G01X-1585024Y603883D02*
X-1584704Y603556D01*
G01X-1599099Y600616D02*
X-1598939Y601106D01*
G01X-1603418Y599472D02*
X-1602618Y598982D01*
G01X-1599899Y605842D02*
X-1600698Y606333D01*
G01X-1602938Y600126D02*
X-1602458Y599799D01*
G01X-1600379Y605189D02*
X-1600859Y605516D01*
G01X-1603897Y605353D02*
X-1604217Y604699D01*
G01X-1599419Y599962D02*
X-1599099Y600616D01*
G01X-1593981Y603066D02*
X-1594141Y602739D01*
G01X-1586784Y603066D02*
X-1586944Y602739D01*
G01X-1595261Y603229D02*
X-1595580Y603392D01*
G01X-1592702Y603229D02*
X-1593021Y603392D01*
G01X-1588063Y603229D02*
X-1588383Y603392D01*
G01X-1585504Y603229D02*
X-1585824Y603392D01*
G01X-1602938Y605189D02*
X-1603578Y604209D01*
G01X-1600379Y600126D02*
X-1599739Y601106D01*
G01X-1595261Y604046D02*
X-1594781Y603883D01*
G01X-1592702Y604046D02*
X-1592222Y603883D01*
G01X-1588063Y604046D02*
X-1587583Y603883D01*
G01X-1585504Y604046D02*
X-1585024Y603883D01*
G01X-1602618Y598982D02*
X-1601658Y598819D01*
G01X-1600698Y606333D02*
X-1601658Y606496D01*
G01X-1602458Y599799D02*
X-1601658Y599636D01*
G01X-1600859Y605516D02*
X-1601658Y605679D01*
G01X-1603418Y605842D02*
X-1603897Y605353D01*
G01X-1596700Y603556D02*
X-1596380Y603883D01*
G01Y603229D02*
X-1596700Y602902D01*
G01X-1599899Y599472D02*
X-1599419Y599962D01*
G01X-1594301Y603392D02*
X-1593821Y603883D01*
G01Y603229D02*
X-1593981Y603066D01*
G01X-1589503Y603556D02*
X-1589183Y603883D01*
G01Y603229D02*
X-1589503Y602902D01*
G01X-1587104Y603392D02*
X-1586624Y603883D01*
G01Y603229D02*
X-1586784Y603066D01*
G01X-1584385Y598819D02*
X-1585184D01*
G01X-1586944D02*
X-1587743D01*
G01X-1589503D02*
X-1590302D01*
G01X-1591582D02*
X-1592381D01*
G01X-1594141D02*
X-1594941D01*
G01X-1596700D02*
X-1597500D01*
G01X-1585824Y603392D02*
X-1586304D01*
G01X-1588383D02*
X-1588703D01*
G01X-1593021D02*
X-1593501D01*
G01X-1595580D02*
X-1595900D01*
G01X-1597500Y604046D02*
X-1596700D01*
G01X-1595900D02*
X-1595261D01*
G01X-1593341D02*
X-1592702D01*
G01X-1590302D02*
X-1589503D01*
G01X-1588703D02*
X-1588063D01*
G01X-1586144D02*
X-1585504D01*
G01X-1602458Y605516D02*
X-1602938Y605189D01*
G01X-1600859Y599799D02*
X-1600379Y600126D01*
G01X-1602618Y606333D02*
X-1603418Y605842D01*
G01X-1600698Y598982D02*
X-1599899Y599472D01*
G01X-1601658Y598819D02*
X-1600698Y598982D01*
G01X-1593501Y603392D02*
X-1593821Y603229D01*
G01X-1586304Y603392D02*
X-1586624Y603229D01*
G01X-1601658Y599636D02*
X-1600859Y599799D01*
G01X-1601658Y605679D02*
X-1602458Y605516D01*
G01X-1601658Y606496D02*
X-1602618Y606333D01*
G01X-1596380Y603883D02*
X-1595900Y604046D01*
G01Y603392D02*
X-1596380Y603229D01*
G01X-1593821Y603883D02*
X-1593341Y604046D01*
G01X-1589183Y603883D02*
X-1588703Y604046D01*
G01Y603392D02*
X-1589183Y603229D01*
G01X-1586624Y603883D02*
X-1586144Y604046D01*
G01X-1572903Y619764D02*
G03Y606378I0J-6693D01*
G01X-1559517D02*
X-1572903D01*
G01X-1566210Y594370D02*
G03Y631772I0J18701D01*
G01X-1559517Y619764D02*
X-1572903D01*
G01X-1609124Y806968D02*
Y783346D01*
G01X-1583858D02*
G03X-1565817Y806968I18041J4921D01*
G01X-1561460Y783449D02*
X-1523000Y740912D01*
G01X-1559320Y788268D02*
G03I-6497J0D01*
G01X-1609517Y790276D02*
Y797953D01*
G01X-1608558D02*
Y794849D01*
G01Y793869D02*
Y790276D01*
G01D02*
X-1609517D01*
G01X-1604080Y793869D02*
X-1608558D01*
G01Y794849D02*
X-1604080D01*
G01X-1609517Y797953D02*
X-1608558D01*
G01X-1604080Y790276D02*
Y793869D01*
G01Y794849D02*
Y797953D01*
G01X-1603120D02*
Y790276D01*
G01X-1601840Y794849D02*
Y795503D01*
G01Y792889D02*
Y793542D01*
G01X-1599281Y795503D02*
Y794849D01*
G01Y793542D02*
Y792889D01*
G01X-1598002Y794849D02*
Y793379D01*
G01X-1597202Y794686D02*
Y793542D01*
G01X-1593044D02*
Y794686D01*
G01X-1597042Y795666D02*
X-1597202Y794686D01*
G01X-1593204Y792563D02*
X-1593044Y793542D01*
G01X-1597842Y795666D02*
X-1598002Y794849D01*
G01X-1592404Y792563D02*
X-1592244Y793379D01*
G01X-1597682Y796156D02*
X-1597842Y795666D01*
G01X-1592244Y793379D02*
Y794849D01*
G01X-1590964Y790276D02*
Y795503D01*
G01X-1590165D02*
Y795013D01*
G01Y794359D02*
Y790276D01*
G01X-1588405D02*
Y794196D01*
G01X-1587605D02*
Y790276D01*
G01X-1585846D02*
Y794196D01*
G01X-1585046D02*
Y790276D01*
G01X-1583767D02*
Y795503D01*
G01X-1582967D02*
Y795013D01*
G01Y794359D02*
Y790276D01*
G01X-1581208D02*
Y794196D01*
G01X-1580408D02*
Y790276D01*
G01X-1578649D02*
Y794196D01*
G01X-1577849D02*
Y790276D01*
G01X-1592564Y792072D02*
X-1592404Y792563D01*
G01X-1597362Y796809D02*
X-1597682Y796156D01*
G01X-1592883Y791419D02*
X-1592564Y792072D01*
G01X-1587446Y794522D02*
X-1587605Y794196D01*
G01X-1580248Y794522D02*
X-1580408Y794196D01*
G01X-1596402Y796646D02*
X-1597042Y795666D01*
G01X-1593843Y791582D02*
X-1593204Y792563D01*
G01X-1597842D02*
X-1597682Y792072D01*
G01X-1592404Y795666D02*
X-1592564Y796156D01*
G01X-1598002Y793379D02*
X-1597842Y792563D01*
G01X-1592244Y794849D02*
X-1592404Y795666D01*
G01X-1597202Y793542D02*
X-1597042Y792563D01*
G01X-1593044Y794686D02*
X-1593204Y795666D01*
G01X-1596882Y797299D02*
X-1597362Y796809D01*
G01X-1597682Y792072D02*
X-1597362Y791419D01*
G01X-1592564Y796156D02*
X-1592883Y796809D01*
G01X-1588405Y794196D02*
X-1588565Y794522D01*
G01X-1585846Y794196D02*
X-1586006Y794522D01*
G01X-1581208Y794196D02*
X-1581368Y794522D01*
G01X-1578649Y794196D02*
X-1578809Y794522D01*
G01X-1585367Y795013D02*
X-1585046Y794196D01*
G01X-1578169Y795013D02*
X-1577849Y794196D01*
G01X-1590165Y795013D02*
X-1589845Y795339D01*
G01Y794686D02*
X-1590165Y794359D01*
G01X-1593363Y790929D02*
X-1592883Y791419D01*
G01X-1587765Y794849D02*
X-1587286Y795339D01*
G01Y794686D02*
X-1587446Y794522D01*
G01X-1582967Y795013D02*
X-1582647Y795339D01*
G01Y794686D02*
X-1582967Y794359D01*
G01X-1580568Y794849D02*
X-1580088Y795339D01*
G01Y794686D02*
X-1580248Y794522D01*
G01X-1597042Y792563D02*
X-1596402Y791582D01*
G01X-1593204Y795666D02*
X-1593843Y796646D01*
G01X-1595922Y796973D02*
X-1596402Y796646D01*
G01X-1594323Y791255D02*
X-1593843Y791582D01*
G01X-1596082Y797789D02*
X-1596882Y797299D01*
G01X-1594163Y790439D02*
X-1593363Y790929D01*
G01X-1597362Y791419D02*
X-1596882Y790929D01*
G01X-1592883Y796809D02*
X-1593363Y797299D01*
G01X-1588565Y794522D02*
X-1588725Y794686D01*
G01X-1588245Y795339D02*
X-1587765Y794849D01*
G01X-1586006Y794522D02*
X-1586166Y794686D01*
G01X-1585686Y795339D02*
X-1585367Y795013D01*
G01X-1581368Y794522D02*
X-1581528Y794686D01*
G01X-1581048Y795339D02*
X-1580568Y794849D01*
G01X-1578809Y794522D02*
X-1578969Y794686D01*
G01X-1578489Y795339D02*
X-1578169Y795013D01*
G01X-1586966Y794849D02*
X-1587286Y794686D01*
G01X-1579768Y794849D02*
X-1580088Y794686D01*
G01X-1589845Y795339D02*
X-1589365Y795503D01*
G01Y794849D02*
X-1589845Y794686D01*
G01X-1587286Y795339D02*
X-1586806Y795503D01*
G01X-1582647Y795339D02*
X-1582168Y795503D01*
G01Y794849D02*
X-1582647Y794686D01*
G01X-1580088Y795339D02*
X-1579609Y795503D01*
G01X-1596882Y790929D02*
X-1596082Y790439D01*
G01X-1593363Y797299D02*
X-1594163Y797789D01*
G01X-1596402Y791582D02*
X-1595922Y791255D01*
G01X-1593843Y796646D02*
X-1594323Y796973D01*
G01X-1588725Y794686D02*
X-1589045Y794849D01*
G01X-1586166Y794686D02*
X-1586486Y794849D01*
G01X-1581528Y794686D02*
X-1581848Y794849D01*
G01X-1578969Y794686D02*
X-1579289Y794849D01*
G01X-1588725Y795503D02*
X-1588245Y795339D01*
G01X-1586166Y795503D02*
X-1585686Y795339D01*
G01X-1581528Y795503D02*
X-1581048Y795339D01*
G01X-1578969Y795503D02*
X-1578489Y795339D01*
G01X-1595922Y791255D02*
X-1595123Y791092D01*
G01X-1596082Y790439D02*
X-1595123Y790276D01*
G01X-1594163Y797789D02*
X-1595123Y797953D01*
G01X-1594323Y796973D02*
X-1595123Y797136D01*
G01X-1577849Y790276D02*
X-1578649D01*
G01X-1580408D02*
X-1581208D01*
G01X-1582967D02*
X-1583767D01*
G01X-1585046D02*
X-1585846D01*
G01X-1587605D02*
X-1588405D01*
G01X-1590165D02*
X-1590964D01*
G01X-1603120D02*
X-1604080D01*
G01X-1599281Y792889D02*
X-1601840D01*
G01Y793542D02*
X-1599281D01*
G01X-1579289Y794849D02*
X-1579768D01*
G01X-1581848D02*
X-1582168D01*
G01X-1586486D02*
X-1586966D01*
G01X-1589045D02*
X-1589365D01*
G01X-1599281D02*
X-1601840D01*
G01Y795503D02*
X-1599281D01*
G01X-1590964D02*
X-1590165D01*
G01X-1589365D02*
X-1588725D01*
G01X-1586806D02*
X-1586166D01*
G01X-1583767D02*
X-1582967D01*
G01X-1582168D02*
X-1581528D01*
G01X-1579609D02*
X-1578969D01*
G01X-1604080Y797953D02*
X-1603120D01*
G01X-1595123Y791092D02*
X-1594323Y791255D01*
G01X-1595123Y790276D02*
X-1594163Y790439D01*
G01X-1595123Y797953D02*
X-1596082Y797789D01*
G01X-1595123Y797136D02*
X-1595922Y796973D01*
G01X-1566407Y847126D02*
G03I-18701J0D01*
G01X-1585108Y851063D02*
Y881744D01*
G01X-1578218Y847126D02*
G03I-6890J0D01*
G01X-1565817Y792205D02*
Y882369D01*
G01X-1588061Y1114843D02*
G03I-18701J0D01*
G01X-1598887D02*
G03I-7875J0D01*
G01X-1606761Y1118779D02*
Y1173504D01*
G01X-1599037Y1340060D02*
Y1321123D01*
G01X-1558350Y-139721D02*
Y-159825D01*
G01X-1554250D02*
Y-139721D01*
G01X-1558350Y-159825D02*
X-1554250D01*
G01Y-139721D02*
X-1553429Y-138046D01*
G01X-1555070Y-133857D02*
X-1557530Y-136370D01*
G01X-1552609Y-133020D02*
X-1555070Y-133857D01*
G01X-1559171Y-138046D02*
X-1558350Y-139721D01*
G01X-1559991Y-137208D02*
X-1559171Y-138046D01*
G01X-1557530Y-136370D02*
X-1559991Y-133857D01*
G01X-1545227Y-138883D02*
Y-159825D01*
G01X-1541126D02*
Y-133020D01*
G01X-1534565Y-155637D02*
Y-159825D01*
G01X-1532104Y-137208D02*
X-1511598Y-155637D01*
G01X-1545227Y-159825D02*
X-1541126D01*
G01X-1534565D02*
X-1505037D01*
G01X-1511598Y-155637D02*
X-1534565D01*
G01X-1545227Y-133020D02*
Y-135533D01*
G01X-1533744Y-126319D02*
X-1534565Y-129669D01*
G01X-1529643D02*
X-1528003Y-127156D01*
G01X-1553429Y-138046D02*
X-1552609Y-137208D01*
G01X-1534565Y-129669D02*
Y-131344D01*
G01X-1529643D02*
Y-129669D01*
G01X-1552609Y-137208D02*
X-1550968Y-136370D01*
G01X-1534565Y-131344D02*
X-1533744Y-134695D01*
G01X-1528003D02*
X-1529643Y-131344D01*
G01X-1533744Y-134695D02*
X-1532104Y-137208D01*
G01X-1505037Y-155637D02*
X-1528003Y-134695D01*
G01X-1546868Y-137208D02*
X-1545227Y-138883D01*
G01Y-135533D02*
X-1546868Y-133857D01*
G01X-1549328Y-136370D02*
X-1546868Y-137208D01*
G01Y-133857D02*
X-1549328Y-133020D01*
G01X-1550968Y-136370D02*
X-1549328D01*
G01X-1541126Y-133020D02*
X-1545227D01*
G01X-1549328D02*
X-1552609D01*
G01X-1505037Y-159825D02*
Y-155637D01*
G01X-1496835Y-148098D02*
X-1481251Y-139721D01*
G01X-1486992D02*
X-1498475Y-145585D01*
G01D02*
X-1496835Y-148098D01*
G01Y-131344D02*
X-1498475Y-133857D01*
G01X-1505857Y-129669D02*
X-1506677Y-126319D01*
G01X-1511598Y-127156D02*
X-1509958Y-129669D01*
G01X-1498475Y-133857D02*
X-1486992Y-139721D01*
G01X-1481251D02*
X-1496835Y-131344D01*
G01X-1509958Y-129669D02*
X-1505857D01*
G01X-1530463Y-122968D02*
X-1533744Y-126319D01*
G01X-1528003Y-127156D02*
X-1525542Y-125481D01*
G01X-1527183Y-121293D02*
X-1530463Y-122968D01*
G01X-1525542Y-125481D02*
X-1521441Y-124643D01*
G01X-1522261Y-120455D02*
X-1527183Y-121293D01*
G01X-1506677Y-126319D02*
X-1509958Y-122968D01*
G01X-1514059Y-125481D02*
X-1511598Y-127156D01*
G01X-1509958Y-122968D02*
X-1513239Y-121293D01*
G01D02*
X-1518980Y-120455D01*
G01X-1518160Y-124643D02*
X-1514059Y-125481D01*
G01X-1521441Y-124643D02*
X-1518160D01*
G01X-1518980Y-120455D02*
X-1522261D01*
G01X-1535777Y374685D02*
Y300276D01*
G01X-1555515Y377174D02*
X-1554596Y390039D01*
G01X-1556497Y376260D02*
G03X-1555515Y377174I0J984D01*
G01X-1554596Y390039D02*
Y400669D01*
G01X-1535777Y378622D02*
Y804016D01*
G01Y378622D02*
Y804016D01*
G01X-1539714Y374685D02*
G03X-1535777Y378622I0J3937D01*
G01X-1539714Y374685D02*
G03X-1535777Y378622I0J3937D01*
G01X-1558533Y400669D02*
Y399094D01*
G01X-1555580Y400669D02*
Y399094D01*
G01X-1555383Y397520D02*
Y399094D01*
G01X-1554990Y400669D02*
Y399094D01*
G01X-1554202Y400669D02*
Y399094D01*
G01X-1554005Y410905D02*
Y408543D01*
G01X-1553415D02*
Y409724D01*
G01X-1551840D02*
Y408543D01*
G01X-1551446Y400669D02*
Y399094D01*
G01X-1551250Y408543D02*
Y410905D01*
G01X-1550659Y397520D02*
Y399094D01*
G01X-1550462Y412087D02*
Y400669D01*
G01X-1549872D02*
Y399094D01*
G01X-1549281Y412087D02*
Y400669D01*
G01X-1548494Y400846D02*
Y424882D01*
G01X-1546919D02*
Y400846D01*
G01X-1550659Y397520D02*
X-1555383D01*
G01X-1548494Y400846D02*
X-1546919D01*
G01Y402815D02*
X-1548494D01*
G01Y403996D02*
X-1546919D01*
G01Y408228D02*
X-1548494D01*
G01X-1551250Y408543D02*
X-1554005D01*
G01X-1551250Y408809D02*
X-1554005D01*
G01X-1549281Y399094D02*
G03X-1546919Y401457I0J2362D01*
G01X-1550659Y409134D02*
G03I-1969J0D01*
G01X-1549281Y400669D02*
G03X-1548494Y401457I0J787D01*
G01X-1546774Y418234D02*
X-1546826Y418294D01*
X-1546872Y418387D01*
X-1546911Y418507D01*
X-1546941Y418650D01*
X-1546959Y418810D01*
X-1546965Y418976D01*
G01X-1548257Y418234D02*
X-1547459Y417598D01*
G01X-1545975D02*
X-1546774Y418234D01*
G01X-1548448Y418976D02*
X-1548443Y418811D01*
X-1548424Y418652D01*
X-1548396Y418510D01*
X-1548357Y418388D01*
X-1548310Y418294D01*
X-1548257Y418234D01*
G01X-1557549Y413661D02*
Y412874D01*
G01X-1555580Y412087D02*
Y413661D01*
G01X-1554793Y412677D02*
Y413661D01*
G01X-1550068Y412087D02*
Y413661D01*
G01X-1550049Y413937D02*
Y412087D01*
G01X-1548474Y413937D02*
Y412087D01*
G01X-1548415Y420354D02*
Y417598D01*
G01X-1546917Y420354D02*
Y417598D01*
G01X-1546396D02*
Y420354D01*
G01X-1546387D02*
Y417598D01*
G01X-1546328Y420354D02*
Y417598D01*
G01X-1544913D02*
Y420354D01*
G01X-1544889D02*
Y417598D01*
G01X-1544754Y420354D02*
Y417598D01*
G01X-1546965Y418976D02*
X-1546959Y419141D01*
X-1546941Y419301D01*
X-1546912Y419443D01*
X-1546873Y419565D01*
X-1546826Y419658D01*
X-1546774Y419719D01*
G01X-1551250Y409658D02*
X-1554005D01*
G01X-1551250Y409724D02*
X-1554005D01*
G01X-1551250Y409791D02*
X-1554005D01*
G01X-1551250Y410639D02*
X-1554005D01*
G01X-1551250Y410905D02*
X-1554005D01*
G01X-1546919Y411378D02*
X-1548494D01*
G01Y412480D02*
X-1546919D01*
G01X-1550068Y412677D02*
X-1554793D01*
G01X-1550068Y413661D02*
X-1557549D01*
G01X-1548494Y414449D02*
X-1546919D01*
G01X-1548494Y415074D02*
X-1546919D01*
G01X-1548494Y416417D02*
X-1546919D01*
G01X-1544754Y417598D02*
X-1548494D01*
G01X-1546774Y418234D02*
X-1548257D01*
G01X-1546919Y418976D02*
X-1548494D01*
G01X-1546774Y419719D02*
X-1548257D01*
G01X-1548494Y420157D02*
X-1546919D01*
G01X-1544754Y420354D02*
X-1548494D01*
G01X-1546919Y423701D02*
X-1548494D01*
G01X-1546919Y424882D02*
X-1548494D01*
G01X-1548257Y419719D02*
X-1548309Y419659D01*
X-1548356Y419566D01*
X-1548395Y419446D01*
X-1548424Y419302D01*
X-1548442Y419143D01*
X-1548448Y418976D01*
G01X-1547459Y420354D02*
X-1548257Y419719D01*
G01X-1546774D02*
X-1545975Y420354D01*
G01X-1548827Y415886D02*
G03X-1550049Y413937I943J-1949D01*
G01X-1548141Y414468D02*
G03X-1546919Y416418I-944J1949D01*
G01X-1545738Y418976D02*
G03I-1968J0D01*
G01X-1548827Y415886D02*
G03X-1548494Y416418I-258J531D01*
G01X-1548141Y414468D02*
G03X-1548474Y413937I257J-531D01*
G01X-1539832Y547913D02*
Y500669D01*
G01X-1399757Y482448D02*
X-1506581D01*
G01X-1559517Y606378D02*
G03Y619764I0J6693D01*
G01X-1546503Y622585D02*
X-1519187Y658141D01*
G01D02*
X-1507376D01*
G01X-1523000Y740912D02*
X-1519850D01*
G01D02*
X-1413026D01*
G01X-1559124Y820354D02*
Y884606D01*
G01X-1366880Y820354D02*
X-1559124D01*
G01X-1372391Y807953D02*
X-1531840D01*
G01X-1372391D02*
X-1531840D01*
G01D02*
G03X-1535777Y804016I0J-3937D01*
G01X-1518179Y843346D02*
Y863031D01*
G01X-1515718Y852561D02*
Y843346D01*
G01D02*
X-1518179D01*
G01X-1504235Y852561D02*
X-1515718D01*
G01X-1504235Y843346D02*
Y852561D01*
G01X-1501775Y863031D02*
Y843346D01*
G01X-1498494Y853398D02*
X-1490702Y857587D01*
G01X-1489881Y856330D02*
X-1495623Y853398D01*
G01D02*
X-1489881Y850466D01*
G01X-1490702Y849210D02*
X-1498494Y853398D01*
G01X-1501775Y843346D02*
X-1504235D01*
G01X-1559124Y884606D02*
X-1366880D01*
G01X-1560423Y1138465D02*
Y904646D01*
G01D02*
X-1505580D01*
G01X-1515718Y863031D02*
Y855074D01*
G01D02*
X-1504235D01*
G01X-1518179Y863031D02*
X-1515718D01*
G01X-1504235Y855074D02*
Y863031D01*
G01D02*
X-1501775D01*
G01X-1505580Y982953D02*
Y908150D01*
G01Y904646D02*
Y1036611D01*
G01Y908150D02*
X-1430777D01*
G01X-1553554Y953368D02*
Y961242D01*
G01X-1552569D02*
Y958059D01*
G01Y957054D02*
Y953368D01*
G01X-1547976D02*
Y957054D01*
G01Y958059D02*
Y961242D01*
G01X-1546992D02*
Y953368D01*
G01X-1545680Y957389D02*
X-1542563Y959065D01*
G01X-1542235Y958562D02*
X-1544531Y957389D01*
G01D02*
X-1542235Y956216D01*
G01X-1542563Y955714D02*
X-1545680Y957389D01*
G01X-1546992Y953368D02*
X-1547976D01*
G01X-1552569D02*
X-1553554D01*
G01X-1547976Y957054D02*
X-1552569D01*
G01Y958059D02*
X-1547976D01*
G01X-1553554Y961242D02*
X-1552569D01*
G01X-1547976D02*
X-1546992D01*
G01X-1542235Y956216D02*
X-1542563Y955714D01*
G01X-1540922Y956719D02*
X-1536985Y961242D01*
G01X-1539774Y956719D02*
X-1536985Y959902D01*
G01X-1529439Y957724D02*
X-1529603Y957389D01*
G01X-1522057Y957724D02*
X-1522221Y957389D01*
G01X-1532228Y958227D02*
X-1531900Y958562D01*
G01Y957892D02*
X-1532228Y957557D01*
G01X-1529767Y958059D02*
X-1529275Y958562D01*
G01Y957892D02*
X-1529439Y957724D01*
G01X-1524846Y958227D02*
X-1524518Y958562D01*
G01Y957892D02*
X-1524846Y957557D01*
G01X-1522385Y958059D02*
X-1521893Y958562D01*
G01Y957892D02*
X-1522057Y957724D01*
G01X-1540922Y955714D02*
Y956719D01*
G01X-1536985Y959902D02*
Y956719D01*
G01Y953368D02*
Y955714D01*
G01X-1536001Y961242D02*
Y956719D01*
G01Y955714D02*
Y953368D01*
G01X-1534361Y956719D02*
Y955714D01*
G01X-1533048Y953368D02*
Y958729D01*
G01X-1532228D02*
Y958227D01*
G01Y957557D02*
Y953368D01*
G01X-1530424D02*
Y957389D01*
G01X-1529603D02*
Y953368D01*
G01X-1527799D02*
Y957389D01*
G01X-1526979D02*
Y953368D01*
G01X-1525666D02*
Y958729D01*
G01X-1524846D02*
Y958227D01*
G01Y957557D02*
Y953368D01*
G01X-1523042D02*
Y957389D01*
G01X-1522221D02*
Y953368D01*
G01X-1520417D02*
Y957389D01*
G01X-1519597D02*
Y953368D01*
G01X-1528947Y958059D02*
X-1529275Y957892D01*
G01X-1521565Y958059D02*
X-1521893Y957892D01*
G01X-1531900Y958562D02*
X-1531408Y958729D01*
G01Y958059D02*
X-1531900Y957892D01*
G01X-1529275Y958562D02*
X-1528783Y958729D01*
G01X-1524518Y958562D02*
X-1524026Y958729D01*
G01Y958059D02*
X-1524518Y957892D01*
G01X-1521893Y958562D02*
X-1521401Y958729D01*
G01X-1530424Y957389D02*
X-1530587Y957724D01*
G01X-1527799Y957389D02*
X-1527963Y957724D01*
G01X-1523042Y957389D02*
X-1523205Y957724D01*
G01X-1520417Y957389D02*
X-1520581Y957724D01*
G01X-1527307Y958227D02*
X-1526979Y957389D01*
G01X-1519925Y958227D02*
X-1519597Y957389D01*
G01X-1542563Y959065D02*
X-1542235Y958562D01*
G01X-1530587Y957724D02*
X-1530752Y957892D01*
G01X-1530259Y958562D02*
X-1529767Y958059D01*
G01X-1527963Y957724D02*
X-1528127Y957892D01*
G01X-1527635Y958562D02*
X-1527307Y958227D01*
G01X-1523205Y957724D02*
X-1523370Y957892D01*
G01X-1522878Y958562D02*
X-1522385Y958059D01*
G01X-1520581Y957724D02*
X-1520745Y957892D01*
G01X-1520253Y958562D02*
X-1519925Y958227D01*
G01X-1530752Y957892D02*
X-1531080Y958059D01*
G01X-1528127Y957892D02*
X-1528455Y958059D01*
G01X-1523370Y957892D02*
X-1523698Y958059D01*
G01X-1520745Y957892D02*
X-1521073Y958059D01*
G01X-1530752Y958729D02*
X-1530259Y958562D01*
G01X-1528127Y958729D02*
X-1527635Y958562D01*
G01X-1523370Y958729D02*
X-1522878Y958562D01*
G01X-1520745Y958729D02*
X-1520253Y958562D01*
G01X-1519597Y953368D02*
X-1520417D01*
G01X-1524846D02*
X-1525666D01*
G01X-1522221D02*
X-1523042D01*
G01X-1526979D02*
X-1527799D01*
G01X-1529603D02*
X-1530424D01*
G01X-1532228D02*
X-1533048D01*
G01X-1536001D02*
X-1536985D01*
G01X-1534361Y955714D02*
X-1536001D01*
G01X-1536985D02*
X-1540922D01*
G01X-1536985Y956719D02*
X-1539774D01*
G01X-1536001D02*
X-1534361D01*
G01X-1521073Y958059D02*
X-1521565D01*
G01X-1523698D02*
X-1524026D01*
G01X-1528455D02*
X-1528947D01*
G01X-1531080D02*
X-1531408D01*
G01X-1533048Y958729D02*
X-1532228D01*
G01X-1531408D02*
X-1530752D01*
G01X-1528783D02*
X-1528127D01*
G01X-1525666D02*
X-1524846D01*
G01X-1524026D02*
X-1523370D01*
G01X-1521401D02*
X-1520745D01*
G01X-1536985Y961242D02*
X-1536001D01*
G01X-1430777Y982953D02*
X-1505580D01*
G01X-1478021Y1043976D02*
G03I-14764J0D01*
G01X-1484517D02*
G03I-8268J0D01*
G01X-1505580Y1051342D02*
Y1138465D01*
G01X-1433928Y-655061D02*
X-804125D01*
G01X-1437865Y-651124D02*
G03X-1433928Y-655061I3937J0D01*
G01X-1437865Y-651124D02*
Y-225730D01*
G01X-1397629Y-497384D02*
G03I-18700J0D01*
G01X-1397432Y-241478D02*
G03I-18701J0D01*
G01X-1437865Y-225730D02*
G03X-1441802Y-221793I-3937J0D01*
G01X-1422826Y-234785D02*
G03Y-248171I0J-6693D01*
G01X-1474689Y-120455D02*
Y-159825D01*
G01X-1469768D02*
Y-141396D01*
G01X-1474689Y-159825D02*
X-1469768D01*
G01Y-141396D02*
X-1446802D01*
G01X-1469768Y-136370D02*
Y-120455D01*
G01X-1446802Y-136370D02*
X-1469768D01*
G01X-1446802Y-141396D02*
Y-159825D01*
G01X-1441881D02*
Y-120455D01*
G01X-1446802Y-159825D02*
X-1441881D01*
G01X-1446802Y-120455D02*
Y-136370D01*
G01X-1469768Y-120455D02*
X-1474689D01*
G01X-1441881D02*
X-1446802D01*
G01X-1489881Y850466D02*
X-1490702Y849210D01*
G01X-1485781Y847954D02*
X-1485370Y846697D01*
G01X-1486601Y855911D02*
X-1485781Y853817D01*
G01X-1485370Y846697D02*
X-1484140Y845022D01*
G01X-1485781Y853817D02*
X-1484550Y852142D01*
G01D02*
X-1482500Y850885D01*
G01X-1483730Y847954D02*
X-1485781D01*
G01X-1473887Y852561D02*
Y851723D01*
G01X-1471837D02*
Y854655D01*
G01X-1472247Y848791D02*
X-1471837Y851723D01*
G01X-1473887D02*
X-1474298Y849210D01*
G01D02*
X-1474708Y847954D01*
G01X-1473067Y846697D02*
X-1472247Y848791D01*
G01X-1475528Y853817D02*
X-1474708Y855074D01*
G01Y847954D02*
X-1475528Y846697D01*
G01X-1474298Y845022D02*
X-1473067Y846697D01*
G01X-1468556Y843346D02*
Y845441D01*
G01X-1466505D02*
Y843346D01*
G01X-1456663Y852561D02*
Y854236D01*
G01X-1476758Y852979D02*
X-1475528Y853817D01*
G01X-1476348Y850885D02*
X-1473887Y852561D01*
G01X-1475528Y846697D02*
X-1476758Y845859D01*
G01X-1471837Y854655D02*
X-1472247Y857587D01*
G01X-1476348Y843765D02*
X-1474298Y845022D01*
G01X-1462815Y846697D02*
X-1463225Y847954D01*
G01X-1477989Y852561D02*
X-1476758Y852979D01*
G01X-1455023Y854236D02*
X-1452562Y855074D01*
G01X-1476758Y845859D02*
X-1477989Y845441D01*
G01X-1482910Y846697D02*
X-1483730Y847954D01*
G01X-1484140Y855074D02*
X-1483320Y853817D01*
G01X-1461994Y845441D02*
X-1462815Y846697D01*
G01X-1461174Y847954D02*
X-1460764Y847116D01*
G01D02*
X-1459944Y846278D01*
G01X-1481680Y845859D02*
X-1482910Y846697D01*
G01X-1484140Y845022D02*
X-1482090Y843765D01*
G01X-1483320Y853817D02*
X-1482090Y852979D01*
G01X-1460764Y844603D02*
X-1461994Y845441D01*
G01X-1480449D02*
X-1481680Y845859D01*
G01X-1459124Y843765D02*
X-1460764Y844603D01*
G01X-1459944Y846278D02*
X-1459124Y845859D01*
G01X-1482090Y843765D02*
X-1480039Y843346D01*
G01X-1459124Y845859D02*
X-1457073Y845441D01*
G01X-1482500Y850885D02*
X-1480449Y850466D01*
G01X-1457483Y843346D02*
X-1459124Y843765D01*
G01X-1482090Y852979D02*
X-1480859Y852561D01*
G01X-1452562Y852142D02*
X-1455023Y852561D01*
G01X-1454202Y843346D02*
X-1457483D01*
G01X-1466505D02*
X-1468556D01*
G01X-1480039D02*
X-1478399D01*
G01X-1477989Y845441D02*
X-1480449D01*
G01X-1468556D02*
X-1466505D01*
G01X-1457073D02*
X-1454613D01*
G01X-1463225Y847954D02*
X-1461174D01*
G01X-1480449Y850466D02*
X-1478399D01*
G01X-1455023Y852561D02*
X-1456663D01*
G01X-1480859D02*
X-1477989D01*
G01X-1456663Y854236D02*
X-1455023D01*
G01X-1454613Y845441D02*
X-1452562Y845859D01*
G01X-1478399Y843346D02*
X-1476348Y843765D01*
G01X-1478399Y850466D02*
X-1476348Y850885D01*
G01X-1450511Y847954D02*
Y849629D01*
G01X-1448461D02*
Y847954D01*
G01X-1445180Y843346D02*
Y856749D01*
G01X-1443130Y853817D02*
Y843346D01*
G01X-1438618D02*
Y853398D01*
G01X-1436568D02*
Y843346D01*
G01X-1432057D02*
Y853398D01*
G01X-1448461Y847954D02*
X-1448871Y846697D01*
G01X-1450922Y847116D02*
X-1450511Y847954D01*
G01X-1436158Y854236D02*
X-1436568Y853398D01*
G01X-1449281Y855911D02*
X-1450102Y854655D01*
G01X-1448871Y846697D02*
X-1449691Y845441D01*
G01X-1451742Y846278D02*
X-1450922Y847116D01*
G01X-1442309Y854655D02*
X-1443130Y853817D01*
G01X-1435748Y854655D02*
X-1436158Y854236D01*
G01X-1450102Y854655D02*
X-1451742Y853398D01*
G01X-1430006D02*
Y843346D01*
G01X-1449691Y845441D02*
X-1450922Y844603D01*
G01X-1434928Y855074D02*
X-1435748Y854655D01*
G01X-1452562Y845859D02*
X-1451742Y846278D01*
G01X-1450922Y844603D02*
X-1452562Y843765D01*
G01X-1448871Y851304D02*
X-1448461Y849629D01*
G01X-1441079Y855074D02*
X-1442309Y854655D01*
G01X-1450511Y849629D02*
X-1451332Y851304D01*
G01X-1438618Y853398D02*
X-1439029Y854236D01*
G01X-1432057Y853398D02*
X-1432467Y854236D01*
G01X-1430826Y855492D02*
X-1430006Y853398D01*
G01X-1449691Y852561D02*
X-1448871Y851304D01*
G01X-1439029Y854236D02*
X-1439439Y854655D01*
G01X-1432467Y854236D02*
X-1432877Y854655D01*
G01X-1451332Y851304D02*
X-1452562Y852142D01*
G01X-1451742Y853398D02*
X-1449691Y852561D01*
G01X-1439439Y854655D02*
X-1440259Y855074D01*
G01X-1432877Y854655D02*
X-1433697Y855074D01*
G01X-1430006Y843346D02*
X-1432057D01*
G01X-1436568D02*
X-1438618D01*
G01X-1443130D02*
X-1445180D01*
G01X-1452562Y843765D02*
X-1454202Y843346D01*
G01X-1486601Y857587D02*
Y855911D01*
G01X-1484550Y857168D02*
Y856330D01*
G01X-1484140Y858424D02*
X-1484550Y857168D01*
G01X-1485781Y859681D02*
X-1486601Y857587D01*
G01X-1484550Y856330D02*
X-1484140Y855074D01*
G01X-1490702Y857587D02*
X-1489881Y856330D01*
G01X-1484550Y861356D02*
X-1485781Y859681D01*
G01X-1482500Y862613D02*
X-1484550Y861356D01*
G01X-1474298Y856330D02*
Y857168D01*
G01X-1462815Y858424D02*
X-1462405Y860100D01*
G01X-1474708Y855074D02*
X-1474298Y856330D01*
G01X-1483320Y859681D02*
X-1484140Y858424D01*
G01X-1459944Y859681D02*
X-1460764Y858424D01*
G01X-1472247Y857587D02*
X-1473067Y859681D01*
G01X-1474298Y857168D02*
X-1474708Y858424D01*
G01D02*
X-1475528Y859681D01*
G01X-1460764Y858424D02*
X-1462815D01*
G01X-1462405Y860100D02*
X-1460764Y861775D01*
G01X-1482090Y860518D02*
X-1483320Y859681D01*
G01X-1458714Y860518D02*
X-1459944Y859681D01*
G01X-1460764Y861775D02*
X-1459124Y862613D01*
G01X-1480859Y860937D02*
X-1482090Y860518D01*
G01X-1473067Y859681D02*
X-1474298Y861356D01*
G01D02*
X-1476348Y862613D01*
G01X-1475528Y859681D02*
X-1476758Y860518D01*
G01D02*
X-1477989Y860937D01*
G01X-1455433Y863031D02*
X-1452562Y862613D01*
G01X-1476348D02*
X-1478399Y863031D01*
G01X-1452972Y860518D02*
X-1455023Y860937D01*
G01D02*
X-1456663D01*
G01X-1477989D02*
X-1480859D01*
G01X-1478399Y863031D02*
X-1480449D01*
G01X-1456253D02*
X-1455433D01*
G01X-1456663Y860937D02*
X-1458714Y860518D01*
G01X-1459124Y862613D02*
X-1456253Y863031D01*
G01X-1480449D02*
X-1482500Y862613D01*
G01X-1451742Y855911D02*
X-1450922Y857587D01*
G01D02*
Y858424D01*
G01X-1448871D02*
Y857587D01*
G01X-1443130Y856749D02*
Y855492D01*
G01X-1448871Y857587D02*
X-1449281Y855911D01*
G01X-1452562Y855074D02*
X-1451742Y855911D01*
G01X-1443130Y855492D02*
X-1442309Y856330D01*
G01X-1436978Y855074D02*
X-1435748Y856330D01*
G01X-1449281Y860100D02*
X-1448871Y858424D01*
G01X-1442309Y856330D02*
X-1441079Y856749D01*
G01X-1435748Y856330D02*
X-1434517Y856749D01*
G01X-1450922Y858424D02*
X-1451742Y859681D01*
G01X-1438208Y856330D02*
X-1436978Y855074D01*
G01X-1431647Y856330D02*
X-1430826Y855492D01*
G01X-1439439Y856749D02*
X-1438208Y856330D01*
G01X-1432877Y856749D02*
X-1431647Y856330D01*
G01X-1433697Y855074D02*
X-1434928D01*
G01X-1440259D02*
X-1441079D01*
G01X-1445180Y856749D02*
X-1443130D01*
G01X-1441079D02*
X-1439439D01*
G01X-1434517D02*
X-1432877D01*
G01X-1450922Y861775D02*
X-1449281Y860100D01*
G01X-1451742Y859681D02*
X-1452972Y860518D01*
G01X-1452562Y862613D02*
X-1450922Y861775D01*
G01X-1430777Y908150D02*
Y982953D01*
G01X-1431565Y978228D02*
Y982165D01*
G01X-1435502D02*
X-1431565Y978228D01*
G01X-1431129Y983642D02*
X-1431113Y983674D01*
G01X-1431045Y983625D02*
X-1431079Y983576D01*
G01X-1430794Y984446D02*
X-1430844Y984380D01*
G01X-1430911Y984429D02*
X-1430878Y984462D01*
G01X-1431163Y983609D02*
X-1431129Y983642D01*
G01X-1431079Y983576D02*
X-1431113Y983543D01*
G01X-1430844Y984380D02*
X-1430911Y984331D01*
G01X-1430777Y984528D02*
X-1430794Y984446D01*
G01X-1431113Y983674D02*
X-1431096Y983740D01*
G01X-1430878Y984462D02*
X-1430861Y984511D01*
G01X-1431029Y983674D02*
X-1431045Y983625D01*
G01X-1430962Y984413D02*
X-1430911Y984429D01*
G01Y984331D02*
X-1430962Y984314D01*
G01X-1431113Y983543D02*
X-1431163Y983527D01*
G01X-1431565Y984101D02*
Y984183D01*
G01Y983511D02*
Y983592D01*
G01Y983888D02*
Y983970D01*
G01Y983182D02*
Y983281D01*
G01Y984823D02*
Y984921D01*
G01X-1431213Y984528D02*
Y984823D01*
G01X-1431113D02*
Y984511D01*
G01X-1431029Y984183D02*
Y984101D01*
G01Y983740D02*
Y983674D01*
G01Y983970D02*
Y983888D01*
G01X-1430861Y984101D02*
Y984183D01*
G01Y984511D02*
Y984823D01*
G01X-1430777Y984921D02*
Y984528D01*
G01Y984183D02*
Y984101D01*
G01Y983281D02*
Y983182D01*
G01X-1431096Y983740D02*
X-1431113Y983806D01*
G01X-1431045D02*
X-1431029Y983740D01*
G01X-1431196Y984446D02*
X-1431213Y984528D01*
G01X-1431113Y984511D02*
X-1431096Y984462D01*
G01X-1431146Y984380D02*
X-1431196Y984446D01*
G01X-1431113Y983806D02*
X-1431146Y983855D01*
G01X-1431079D02*
X-1431045Y983806D01*
G01X-1431146Y983855D02*
X-1431180Y983888D01*
G01X-1431113D02*
X-1431079Y983855D01*
G01X-1431096Y984462D02*
X-1431062Y984429D01*
G01X-1430911Y983281D02*
X-1431029Y983379D01*
G01X-1430894D02*
X-1430777Y983281D01*
G01X-1431079Y984331D02*
X-1431146Y984380D01*
G01X-1431029Y984314D02*
X-1431079Y984331D01*
G01X-1431062Y984429D02*
X-1431012Y984413D01*
G01X-1431565Y982165D02*
X-1435502D01*
G01X-1430777Y983182D02*
X-1431565D01*
G01Y983281D02*
X-1430911D01*
G01X-1431029Y983379D02*
X-1430894D01*
G01X-1431246Y983511D02*
X-1431565D01*
G01Y983592D02*
X-1431246D01*
G01X-1431180Y983888D02*
X-1431565D01*
G01X-1431029D02*
X-1431113D01*
G01X-1431565Y983970D02*
X-1431029D01*
G01Y984101D02*
X-1431565D01*
G01X-1430777D02*
X-1430861D01*
G01X-1431565Y984183D02*
X-1431029D01*
G01X-1430861D02*
X-1430777D01*
G01X-1430962Y984314D02*
X-1431029D01*
G01X-1431012Y984413D02*
X-1430962D01*
G01X-1431213Y984823D02*
X-1431565D01*
G01X-1430861D02*
X-1431113D01*
G01X-1431565Y984921D02*
X-1430777D01*
G01X-1431163Y983527D02*
X-1431246Y983511D01*
G01Y983592D02*
X-1431163Y983609D01*
G01X-1488848Y1043976D02*
X-1386526D01*
G01X-1492785Y1047913D02*
Y1092298D01*
G01X-1456852Y1052082D02*
X-1457262Y1050956D01*
G01X-1462433Y1049286D02*
Y1044756D01*
G01X-1461033Y1060555D02*
Y1048658D01*
G01X-1460793Y1052356D02*
Y1049857D01*
G01X-1460483Y1060677D02*
Y1048535D01*
G01X-1460033Y1048006D02*
Y1044106D01*
G01X-1459983Y1048602D02*
Y1052106D01*
G01X-1459773Y1044756D02*
Y1064456D01*
G01X-1459473Y1062856D02*
Y1046356D01*
G01X-1456533Y1044106D02*
Y1065106D01*
G01X-1455983Y1062856D02*
Y1046356D01*
G01X-1460483Y1049133D02*
X-1460624Y1049300D01*
X-1460722Y1049485D01*
X-1460777Y1049673D01*
X-1460793Y1049857D01*
G01X-1461966Y1049535D02*
X-1460483Y1048535D01*
G01Y1048658D02*
X-1460461Y1048648D01*
X-1460396Y1048637D01*
X-1460295Y1048627D01*
X-1460165Y1048616D01*
X-1460020Y1048606D01*
G01X-1461033Y1048658D02*
X-1461001Y1048649D01*
X-1460905Y1048641D01*
X-1460752Y1048632D01*
X-1460552Y1048624D01*
X-1460060Y1048606D01*
G01X-1456533Y1044106D02*
X-1460033D01*
G01X-1452783Y1044756D02*
X-1462433D01*
G01Y1046356D02*
X-1441223D01*
G01X-1455983Y1047510D02*
X-1441223D01*
G01Y1048256D02*
X-1455983D01*
G01Y1048456D02*
X-1441223D01*
G01X-1460020Y1048606D02*
X-1460060D01*
G01X-1461033Y1048658D02*
X-1460483D01*
G01Y1048859D02*
X-1461033D01*
G01X-1453043Y1049156D02*
X-1455983D01*
G01Y1049371D02*
X-1453043D01*
G01X-1461033Y1049857D02*
X-1460793D01*
G01X-1457262Y1050956D02*
X-1453043D01*
G01X-1460060Y1048606D02*
X-1460036D01*
X-1460023Y1048605D01*
X-1460009Y1048604D01*
X-1459997D01*
X-1459983Y1048602D01*
G01X-1460020Y1048606D02*
X-1460008D01*
X-1459996Y1048604D01*
X-1459990D01*
X-1459983Y1048602D01*
G01X-1461966Y1049535D02*
G03X-1462433Y1049286I-167J-249D01*
G01X-1460033Y1048006D02*
G03X-1459983Y1048602I0J300D01*
G01X-1451614Y1042114D02*
X-1451744Y1041937D01*
G01X-1451223Y1042603D02*
X-1450962Y1042913D01*
G01Y1042558D02*
X-1451223Y1042248D01*
G01X-1453443Y1048950D02*
X-1453361Y1049044D01*
G01X-1452987D02*
X-1453343Y1048632D01*
G01X-1449504Y1048950D02*
X-1449421Y1049044D01*
G01X-1449047D02*
X-1449403Y1048632D01*
G01X-1445563Y1048950D02*
X-1445481Y1049044D01*
G01X-1445107D02*
X-1445463Y1048632D01*
G01X-1441623Y1048950D02*
X-1441541Y1049044D01*
G01X-1441167D02*
X-1441523Y1048632D01*
G01X-1437659Y1049413D02*
X-1438016Y1049002D01*
G01X-1437958Y1048632D02*
X-1437602Y1049044D01*
G01X-1437227D02*
X-1437583Y1048632D01*
G01X-1433720Y1049413D02*
X-1434076Y1049002D01*
G01X-1434018Y1048632D02*
X-1433661Y1049044D01*
G01X-1433287D02*
X-1433643Y1048632D01*
G01X-1451962Y1042070D02*
X-1451875Y1042159D01*
G01X-1451200Y1049044D02*
X-1451068Y1049156D01*
G01X-1450844Y1048632D02*
X-1450743Y1048718D01*
G01X-1447260Y1049044D02*
X-1447129Y1049156D01*
G01X-1446904Y1048632D02*
X-1446804Y1048718D01*
G01X-1443320Y1049044D02*
X-1443189Y1049156D01*
G01X-1442964Y1048632D02*
X-1442863Y1048718D01*
G01X-1439380Y1049044D02*
X-1438947Y1049413D01*
G01X-1439024Y1048632D02*
X-1438591Y1049002D01*
G01X-1435440Y1049044D02*
X-1435007Y1049413D01*
G01X-1435083Y1048632D02*
X-1434651Y1049002D01*
G01X-1431500Y1049044D02*
X-1431067Y1049413D01*
G01X-1431144Y1048632D02*
X-1430711Y1049002D01*
G01X-1451744Y1041937D02*
X-1451918Y1041804D01*
G01X-1453361Y1049044D02*
X-1453384Y1049028D01*
X-1453404Y1049018D01*
X-1453422Y1049015D01*
G01X-1449421Y1049044D02*
X-1449444Y1049028D01*
X-1449464Y1049018D01*
X-1449482Y1049015D01*
G01X-1445481Y1049044D02*
X-1445504Y1049028D01*
X-1445524Y1049018D01*
X-1445542Y1049015D01*
G01X-1441541Y1049044D02*
X-1441564Y1049028D01*
X-1441584Y1049018D01*
X-1441602Y1049015D01*
G01X-1437602Y1049044D02*
X-1437624Y1049028D01*
X-1437644Y1049018D01*
X-1437662Y1049015D01*
G01X-1433661Y1049044D02*
X-1433684Y1049028D01*
X-1433704Y1049018D01*
X-1433722Y1049015D01*
G01X-1450844Y1048632D02*
X-1450976Y1048541D01*
X-1451127Y1048484D01*
X-1451286Y1048465D01*
G01X-1446904Y1048632D02*
X-1447037Y1048541D01*
X-1447187Y1048484D01*
X-1447346Y1048465D01*
G01X-1442964Y1048632D02*
X-1443096Y1048541D01*
X-1443247Y1048484D01*
X-1443406Y1048465D01*
G01X-1439024Y1048632D02*
X-1439156Y1048541D01*
X-1439307Y1048484D01*
X-1439466Y1048465D01*
G01X-1435083Y1048632D02*
X-1435217Y1048541D01*
X-1435367Y1048484D01*
X-1435526Y1048465D01*
G01X-1431144Y1048632D02*
X-1431276Y1048541D01*
X-1431427Y1048484D01*
X-1431586Y1048465D01*
G01X-1451200Y1049044D02*
X-1451226Y1049028D01*
X-1451255Y1049018D01*
X-1451286Y1049015D01*
G01X-1447260Y1049044D02*
X-1447286Y1049028D01*
X-1447315Y1049018D01*
X-1447346Y1049015D01*
G01X-1443320Y1049044D02*
X-1443346Y1049028D01*
X-1443376Y1049018D01*
X-1443406Y1049015D01*
G01X-1439380Y1049044D02*
X-1439406Y1049028D01*
X-1439435Y1049018D01*
X-1439466Y1049015D01*
G01X-1435440Y1049044D02*
X-1435466Y1049028D01*
X-1435496Y1049018D01*
X-1435526Y1049015D01*
G01X-1431500Y1049044D02*
X-1431526Y1049028D01*
X-1431555Y1049018D01*
X-1431586Y1049015D01*
G01X-1452092Y1042026D02*
X-1451962Y1042070D01*
G01X-1451875Y1042159D02*
X-1451831Y1042292D01*
G01X-1451570Y1042248D02*
X-1451614Y1042114D01*
G01X-1450808Y1049156D02*
X-1450826Y1049044D01*
G01X-1446868Y1049156D02*
X-1446885Y1049044D01*
G01X-1442928Y1049156D02*
X-1442945Y1049044D01*
G01X-1438947Y1049413D02*
X-1439005Y1049044D01*
G01X-1438591Y1049002D02*
X-1438649Y1048632D01*
G01X-1435007Y1049413D02*
X-1435065Y1049044D01*
G01X-1434651Y1049002D02*
X-1434709Y1048632D01*
G01X-1431067Y1049413D02*
X-1431126Y1049044D01*
G01X-1430711Y1049002D02*
X-1430769Y1048632D01*
G01X-1453422Y1048939D02*
X-1453420Y1048950D01*
X-1453409Y1048981D01*
X-1453379Y1049024D01*
G01X-1449482Y1048939D02*
X-1449480Y1048950D01*
X-1449468Y1048981D01*
X-1449439Y1049024D01*
G01X-1445542Y1048939D02*
X-1445540Y1048950D01*
X-1445529Y1048981D01*
X-1445499Y1049024D01*
G01X-1441602Y1048939D02*
X-1441600Y1048950D01*
X-1441589Y1048981D01*
X-1441559Y1049024D01*
G01X-1437662Y1048939D02*
X-1437660Y1048950D01*
X-1437648Y1048981D01*
X-1437619Y1049024D01*
G01X-1433722Y1048939D02*
X-1433720Y1048950D01*
X-1433709Y1048981D01*
X-1433679Y1049024D01*
G01X-1453443Y1049156D02*
Y1047706D01*
G01X-1453422Y1049015D02*
Y1048465D01*
G01X-1453293Y1049015D02*
Y1048465D01*
G01X-1453179Y1040827D02*
Y1042913D01*
G01X-1453149Y1048465D02*
Y1049015D01*
G01X-1453043Y1053406D02*
Y1049156D01*
G01X-1452941Y1049015D02*
Y1048465D01*
G01X-1452918Y1041759D02*
Y1040827D01*
G01Y1042691D02*
Y1042026D01*
G01X-1452911Y1049015D02*
Y1048465D01*
G01X-1452900Y1043415D02*
Y1052259D01*
G01X-1452783Y1045756D02*
Y1044756D01*
G01X-1452441Y1049542D02*
Y1052505D01*
G01X-1451831Y1042292D02*
Y1042425D01*
G01X-1451732Y1052505D02*
Y1049542D01*
G01X-1451570Y1042425D02*
Y1042248D01*
G01X-1451286Y1052270D02*
Y1043415D01*
G01X-1451283Y1044756D02*
Y1045756D01*
G01X-1451275Y1048465D02*
Y1049015D01*
G01X-1451246Y1048465D02*
Y1049015D01*
G01X-1451223Y1042248D02*
Y1042603D01*
G01X-1451143Y1053406D02*
Y1049156D01*
G01X-1451038Y1049015D02*
Y1048465D01*
G01X-1450962Y1040827D02*
Y1042558D01*
G01X-1450893Y1048465D02*
Y1049015D01*
G01X-1450765Y1048465D02*
Y1049015D01*
G01X-1450743Y1049156D02*
Y1047706D01*
G01X-1450701Y1042913D02*
Y1040827D01*
G01X-1449504Y1049156D02*
Y1047706D01*
G01X-1449482Y1049015D02*
Y1048465D01*
G01X-1449354Y1049015D02*
Y1048465D01*
G01X-1449209D02*
Y1049015D01*
G01X-1449104Y1053406D02*
Y1049156D01*
G01X-1449001Y1049015D02*
Y1048465D01*
G01X-1448972Y1049015D02*
Y1048465D01*
G01X-1448961Y1043415D02*
Y1052259D01*
G01X-1448860Y1045756D02*
Y1044756D01*
G01X-1448500Y1049542D02*
Y1052505D01*
G01X-1447792D02*
Y1049542D01*
G01X-1447360Y1044756D02*
Y1045756D01*
G01X-1447346Y1052270D02*
Y1043415D01*
G01X-1447335Y1048465D02*
Y1049015D01*
G01X-1447306Y1048465D02*
Y1049015D01*
G01X-1447204Y1053406D02*
Y1049156D01*
G01X-1447098Y1049015D02*
Y1048465D01*
G01X-1446954D02*
Y1049015D01*
G01X-1446825Y1048465D02*
Y1049015D01*
G01X-1446804Y1049156D02*
Y1047706D01*
G01X-1445563Y1049156D02*
Y1047706D01*
G01X-1445542Y1049015D02*
Y1048465D01*
G01X-1445413Y1049015D02*
Y1048465D01*
G01X-1445269D02*
Y1049015D01*
G01X-1445163Y1053406D02*
Y1049156D01*
G01X-1445061Y1049015D02*
Y1048465D01*
G01X-1445031Y1049015D02*
Y1048465D01*
G01X-1445020Y1043415D02*
Y1052259D01*
G01X-1444936Y1045756D02*
Y1044756D01*
G01X-1444561Y1049542D02*
Y1052505D01*
G01X-1443852D02*
Y1049542D01*
G01X-1443436Y1044756D02*
Y1045756D01*
G01X-1443406Y1052270D02*
Y1043415D01*
G01X-1443395Y1048465D02*
Y1049015D01*
G01X-1443366Y1048465D02*
Y1049015D01*
G01X-1443263Y1053406D02*
Y1049156D01*
G01X-1443158Y1049015D02*
Y1048465D01*
G01X-1443013D02*
Y1049015D01*
G01X-1442885Y1048465D02*
Y1049015D01*
G01X-1442863Y1049156D02*
Y1047706D01*
G01X-1441623Y1049156D02*
Y1047706D01*
G01X-1441602Y1049015D02*
Y1048465D01*
G01X-1441473Y1049015D02*
Y1048465D01*
G01X-1441329D02*
Y1049015D01*
G01X-1441223Y1060056D02*
Y1049156D01*
G01Y1048456D02*
Y1044756D01*
G01X-1441121Y1049015D02*
Y1048465D01*
G01X-1441091Y1049015D02*
Y1048465D01*
G01X-1441080Y1043415D02*
Y1052259D01*
G01X-1440620Y1049542D02*
Y1052505D01*
G01X-1439912D02*
Y1049542D01*
G01X-1439466Y1052270D02*
Y1043415D01*
G01X-1439455Y1048465D02*
Y1049015D01*
G01X-1439426Y1048465D02*
Y1049015D01*
G01X-1439323Y1053406D02*
Y1049156D01*
G01X-1439218Y1049015D02*
Y1048465D01*
G01X-1439073D02*
Y1049015D01*
G01X-1438945Y1048465D02*
Y1049015D01*
G01X-1438923Y1049156D02*
Y1047706D01*
G01X-1437683Y1049156D02*
Y1047706D01*
G01X-1437662Y1049015D02*
Y1048465D01*
G01X-1437533Y1049015D02*
Y1048465D01*
G01X-1437389D02*
Y1049015D01*
G01X-1437283Y1053406D02*
Y1049156D01*
G01X-1437181Y1049015D02*
Y1048465D01*
G01X-1437152Y1049015D02*
Y1048465D01*
G01X-1437141Y1043415D02*
Y1052259D01*
G01X-1436681Y1049542D02*
Y1052505D01*
G01X-1435972D02*
Y1049542D01*
G01X-1435526Y1052270D02*
Y1043415D01*
G01X-1435515Y1048465D02*
Y1049015D01*
G01X-1435486Y1048465D02*
Y1049015D01*
G01X-1435383Y1053406D02*
Y1049156D01*
G01X-1435278Y1049015D02*
Y1048465D01*
G01X-1435133D02*
Y1049015D01*
G01X-1435005Y1048465D02*
Y1049015D01*
G01X-1434983Y1049156D02*
Y1047706D01*
G01X-1433743Y1049156D02*
Y1047706D01*
G01X-1433722Y1049015D02*
Y1048465D01*
G01X-1433593Y1049015D02*
Y1048465D01*
G01X-1433449D02*
Y1049015D01*
G01X-1433343Y1053406D02*
Y1049156D01*
G01X-1433241Y1049015D02*
Y1048465D01*
G01X-1433211Y1049015D02*
Y1048465D01*
G01X-1433200Y1043415D02*
Y1052259D01*
G01X-1432741Y1049542D02*
Y1052505D01*
G01X-1432032D02*
Y1049542D01*
G01X-1431586Y1052270D02*
Y1043415D01*
G01X-1431575Y1048465D02*
Y1049015D01*
G01X-1431546Y1048465D02*
Y1049015D01*
G01X-1431443Y1053406D02*
Y1049156D01*
G01X-1431338Y1049015D02*
Y1048465D01*
G01X-1431193D02*
Y1049015D01*
G01X-1431065Y1048465D02*
Y1049015D01*
G01X-1431043Y1047706D02*
Y1049156D01*
G01X-1453361Y1049044D02*
X-1453379Y1049156D01*
G01X-1449421Y1049044D02*
X-1449439Y1049156D01*
G01X-1445481Y1049044D02*
X-1445499Y1049156D01*
G01X-1441541Y1049044D02*
X-1441559Y1049156D01*
G01X-1451286Y1048468D02*
Y1048467D01*
X-1451285Y1048466D01*
X-1451283Y1048465D01*
X-1451275D01*
G01X-1447346Y1048468D02*
Y1048467D01*
X-1447344Y1048465D01*
X-1447335D01*
G01X-1443406Y1048468D02*
Y1048467D01*
X-1443404Y1048465D01*
X-1443395D01*
G01X-1439466Y1048468D02*
Y1048467D01*
X-1439464Y1048465D01*
X-1439455D01*
G01X-1435526Y1048468D02*
Y1048467D01*
X-1435524Y1048465D01*
X-1435515D01*
G01X-1437958Y1048632D02*
X-1438016Y1049002D01*
G01X-1437602Y1049044D02*
X-1437659Y1049413D01*
G01X-1434018Y1048632D02*
X-1434076Y1049002D01*
G01X-1433661Y1049044D02*
X-1433720Y1049413D01*
G01X-1451831Y1042425D02*
X-1451875Y1042558D01*
G01X-1451614D02*
X-1451570Y1042425D01*
G01X-1431586Y1048468D02*
Y1048467D01*
X-1431585Y1048466D01*
X-1431583Y1048465D01*
X-1431575D01*
G01X-1450808Y1049024D02*
X-1450778Y1048981D01*
X-1450767Y1048950D01*
X-1450765Y1048939D01*
G01X-1446868Y1049024D02*
X-1446838Y1048981D01*
X-1446826Y1048950D01*
X-1446825Y1048939D01*
G01X-1450844Y1048632D02*
X-1451200Y1049044D01*
G01X-1450826D02*
X-1450743Y1048950D01*
G01X-1451744Y1042736D02*
X-1451614Y1042558D01*
G01X-1442928Y1049024D02*
X-1442898Y1048981D01*
X-1442887Y1048950D01*
X-1442885Y1048939D01*
G01X-1438988Y1049024D02*
X-1438958Y1048981D01*
X-1438946Y1048950D01*
X-1438945Y1048939D01*
G01X-1435048Y1049024D02*
X-1435018Y1048981D01*
X-1435007Y1048950D01*
X-1435005Y1048939D01*
G01X-1431108Y1049024D02*
X-1431078Y1048981D01*
X-1431067Y1048950D01*
X-1431065Y1048939D01*
G01X-1451875Y1042558D02*
X-1451962Y1042647D01*
G01X-1437958Y1048632D02*
X-1437874Y1048541D01*
X-1437772Y1048484D01*
X-1437662Y1048465D01*
G01X-1434018Y1048632D02*
X-1433934Y1048541D01*
X-1433833Y1048484D01*
X-1433722Y1048465D01*
G01X-1451286Y1049017D02*
X-1451285Y1049016D01*
X-1451281Y1049015D01*
X-1451275D01*
G01X-1447346Y1049017D02*
X-1447345Y1049016D01*
X-1447341Y1049015D01*
X-1447335D01*
G01X-1443406Y1049017D02*
X-1443405Y1049016D01*
X-1443402Y1049015D01*
X-1443395D01*
G01X-1439466Y1049017D02*
X-1439465Y1049016D01*
X-1439461Y1049015D01*
X-1439455D01*
G01X-1435526Y1049017D02*
X-1435525Y1049016D01*
X-1435522Y1049015D01*
X-1435515D01*
G01X-1431586Y1049017D02*
X-1431585Y1049016D01*
X-1431581Y1049015D01*
X-1431575D01*
G01X-1446904Y1048632D02*
X-1447260Y1049044D01*
G01X-1446885D02*
X-1446804Y1048950D01*
G01X-1442964Y1048632D02*
X-1443320Y1049044D01*
G01X-1442945D02*
X-1442863Y1048950D01*
G01X-1439024Y1048632D02*
X-1439380Y1049044D01*
G01X-1439005D02*
X-1438649Y1048632D01*
G01X-1438947Y1049413D02*
X-1438591Y1049002D01*
G01X-1435083Y1048632D02*
X-1435440Y1049044D01*
G01X-1435065D02*
X-1434709Y1048632D01*
G01X-1435007Y1049413D02*
X-1434651Y1049002D01*
G01X-1431144Y1048632D02*
X-1431500Y1049044D01*
G01X-1431126D02*
X-1430769Y1048632D01*
G01X-1431067Y1049413D02*
X-1430711Y1049002D01*
G01X-1451918Y1042869D02*
X-1451744Y1042736D01*
G01X-1453443Y1048718D02*
X-1453343Y1048632D01*
G01X-1452987Y1049044D02*
X-1453118Y1049156D01*
G01X-1449504Y1048718D02*
X-1449403Y1048632D01*
G01X-1449047Y1049044D02*
X-1449178Y1049156D01*
G01X-1445563Y1048718D02*
X-1445463Y1048632D01*
G01X-1445107Y1049044D02*
X-1445238Y1049156D01*
G01X-1441623Y1048718D02*
X-1441523Y1048632D01*
G01X-1441167Y1049044D02*
X-1441298Y1049156D01*
G01X-1438016Y1049002D02*
X-1437583Y1048632D01*
G01X-1437227Y1049044D02*
X-1437659Y1049413D01*
G01X-1434076Y1049002D02*
X-1433643Y1048632D01*
G01X-1433287Y1049044D02*
X-1433720Y1049413D01*
G01X-1451286Y1049356D02*
X-1451353Y1049395D01*
X-1451423Y1049431D01*
X-1451495Y1049463D01*
X-1451574Y1049494D01*
X-1451650Y1049520D01*
X-1451732Y1049542D01*
G01X-1447346Y1049356D02*
X-1447413Y1049395D01*
X-1447483Y1049431D01*
X-1447555Y1049463D01*
X-1447634Y1049494D01*
X-1447711Y1049520D01*
X-1447792Y1049542D01*
G01X-1443406Y1049356D02*
X-1443473Y1049395D01*
X-1443543Y1049431D01*
X-1443615Y1049463D01*
X-1443694Y1049494D01*
X-1443770Y1049520D01*
X-1443852Y1049542D01*
G01X-1439466Y1049356D02*
X-1439533Y1049395D01*
X-1439603Y1049431D01*
X-1439675Y1049463D01*
X-1439754Y1049494D01*
X-1439830Y1049520D01*
X-1439912Y1049542D01*
G01X-1435526Y1049356D02*
X-1435593Y1049395D01*
X-1435663Y1049431D01*
X-1435735Y1049463D01*
X-1435814Y1049494D01*
X-1435891Y1049520D01*
X-1435972Y1049542D01*
G01X-1431586Y1049356D02*
X-1431653Y1049395D01*
X-1431723Y1049431D01*
X-1431795Y1049463D01*
X-1431874Y1049494D01*
X-1431950Y1049520D01*
X-1432032Y1049542D01*
G01X-1451962Y1042647D02*
X-1452092Y1042691D01*
G01X-1452135Y1042913D02*
X-1451918Y1042869D01*
G01X-1452900Y1049015D02*
X-1452931Y1049018D01*
X-1452961Y1049028D01*
X-1452987Y1049044D01*
G01X-1448961Y1049015D02*
X-1448991Y1049018D01*
X-1449020Y1049028D01*
X-1449047Y1049044D01*
G01X-1445020Y1049015D02*
X-1445051Y1049018D01*
X-1445081Y1049028D01*
X-1445107Y1049044D01*
G01X-1441080Y1049015D02*
X-1441111Y1049018D01*
X-1441141Y1049028D01*
X-1441167Y1049044D01*
G01X-1437141Y1049015D02*
X-1437171Y1049018D01*
X-1437201Y1049028D01*
X-1437227Y1049044D01*
G01X-1433200Y1049015D02*
X-1433231Y1049018D01*
X-1433261Y1049028D01*
X-1433287Y1049044D01*
G01X-1452900Y1048465D02*
X-1453060Y1048484D01*
X-1453210Y1048541D01*
X-1453343Y1048632D01*
G01X-1448961Y1048465D02*
X-1449120Y1048484D01*
X-1449270Y1048541D01*
X-1449403Y1048632D01*
G01X-1445020Y1048465D02*
X-1445180Y1048484D01*
X-1445330Y1048541D01*
X-1445463Y1048632D01*
G01X-1441080Y1048465D02*
X-1441240Y1048484D01*
X-1441391Y1048541D01*
X-1441523Y1048632D01*
G01X-1437141Y1048465D02*
X-1437300Y1048484D01*
X-1437450Y1048541D01*
X-1437583Y1048632D01*
G01X-1433200Y1048465D02*
X-1433360Y1048484D01*
X-1433510Y1048541D01*
X-1433643Y1048632D01*
G01X-1450765Y1049015D02*
X-1450783Y1049018D01*
X-1450803Y1049028D01*
X-1450826Y1049044D01*
G01X-1446825Y1049015D02*
X-1446843Y1049018D01*
X-1446863Y1049028D01*
X-1446885Y1049044D01*
G01X-1442885Y1049015D02*
X-1442903Y1049018D01*
X-1442922Y1049028D01*
X-1442945Y1049044D01*
G01X-1438945Y1049015D02*
X-1438963Y1049018D01*
X-1438983Y1049028D01*
X-1439005Y1049044D01*
G01X-1435005Y1049015D02*
X-1435023Y1049018D01*
X-1435043Y1049028D01*
X-1435065Y1049044D01*
G01X-1431065Y1049015D02*
X-1431083Y1049018D01*
X-1431103Y1049028D01*
X-1431126Y1049044D01*
G01X-1433211Y1049015D02*
X-1433205D01*
X-1433202Y1049016D01*
X-1433200Y1049017D01*
G01X-1437152Y1049015D02*
X-1437145D01*
X-1437142Y1049016D01*
X-1437141Y1049017D01*
G01X-1441091Y1049015D02*
X-1441085D01*
X-1441082Y1049016D01*
X-1441080Y1049017D01*
G01X-1445031Y1049015D02*
X-1445025D01*
X-1445022Y1049016D01*
X-1445020Y1049017D01*
G01X-1448972Y1049015D02*
X-1448965D01*
X-1448962Y1049016D01*
X-1448961Y1049017D01*
G01X-1452911Y1049015D02*
X-1452905D01*
X-1452902Y1049016D01*
X-1452900Y1049017D01*
G01X-1442885Y1048465D02*
X-1442863D01*
G01X-1446825D02*
X-1446804D01*
G01X-1450765D02*
X-1450743D01*
G01X-1433211D02*
X-1433203D01*
X-1433200Y1048468D01*
G01X-1437152Y1048465D02*
X-1437143D01*
X-1437141Y1048467D01*
Y1048468D01*
G01X-1441091Y1048465D02*
X-1441083D01*
X-1441080Y1048468D01*
G01X-1445031Y1048465D02*
X-1445023D01*
X-1445020Y1048468D01*
G01X-1448972Y1048465D02*
X-1448963D01*
X-1448961Y1048467D01*
Y1048468D01*
G01X-1452911Y1048465D02*
X-1452903D01*
X-1452900Y1048468D01*
G01X-1450701Y1040827D02*
X-1450962D01*
G01X-1452918D02*
X-1453179D01*
G01X-1452135Y1041759D02*
X-1452918D01*
G01Y1042026D02*
X-1452092D01*
G01Y1042691D02*
X-1452918D01*
G01X-1453179Y1042913D02*
X-1452135D01*
G01X-1450962D02*
X-1450701D01*
G01X-1431586Y1043415D02*
X-1433200D01*
G01X-1435526D02*
X-1437141D01*
G01X-1439466D02*
X-1441080D01*
G01X-1443406D02*
X-1445020D01*
G01X-1447346D02*
X-1448961D01*
G01X-1451286D02*
X-1452900D01*
G01X-1441223Y1044756D02*
X-1443436D01*
G01X-1421993D02*
X-1441223D01*
G01X-1444936D02*
X-1447360D01*
G01X-1448860D02*
X-1451283D01*
G01X-1443936Y1046256D02*
X-1444436D01*
G01X-1447860D02*
X-1448360D01*
G01X-1451783D02*
X-1452283D01*
G01X-1421993Y1046356D02*
X-1441223D01*
G01Y1047510D02*
X-1428443D01*
G01X-1452900Y1047565D02*
X-1451286D01*
G01X-1448961D02*
X-1447346D01*
G01X-1445020D02*
X-1443406D01*
G01X-1441080D02*
X-1439466D01*
G01X-1437141D02*
X-1435526D01*
G01X-1433200D02*
X-1431586D01*
G01X-1453443Y1047706D02*
X-1450743D01*
G01X-1449504D02*
X-1446804D01*
G01X-1445563D02*
X-1442863D01*
G01X-1441623D02*
X-1441223D01*
G01D02*
X-1438923D01*
G01X-1437683D02*
X-1434983D01*
G01X-1433743D02*
X-1431043D01*
G01X-1452900Y1047915D02*
X-1451286D01*
G01X-1448961D02*
X-1447346D01*
G01X-1445020D02*
X-1443406D01*
G01X-1441080D02*
X-1439466D01*
G01X-1437141D02*
X-1435526D01*
G01X-1433200D02*
X-1431586D01*
G01X-1428443Y1048256D02*
X-1441223D01*
G01X-1452900Y1048416D02*
X-1451286D01*
G01X-1448961D02*
X-1447346D01*
G01X-1445020D02*
X-1443406D01*
G01X-1428443Y1048456D02*
X-1441223D01*
G01X-1431065Y1048465D02*
X-1433722D01*
G01X-1435005D02*
X-1437662D01*
G01X-1438945D02*
X-1441602D01*
G01X-1442885D02*
X-1445542D01*
G01X-1446825D02*
X-1449482D01*
G01X-1450765D02*
X-1453422D01*
G01X-1430769Y1048632D02*
X-1431144D01*
G01X-1433643D02*
X-1434018D01*
G01X-1434709D02*
X-1435083D01*
G01X-1438649D02*
X-1439024D01*
G01X-1437583D02*
X-1437958D01*
G01X-1441523D02*
X-1441623D01*
G01X-1442863D02*
X-1442964D01*
G01X-1445463D02*
X-1445563D01*
G01X-1449403D02*
X-1449504D01*
G01X-1446804D02*
X-1446904D01*
G01X-1450743D02*
X-1450844D01*
G01X-1453343D02*
X-1453443D01*
G01X-1431065Y1049015D02*
X-1433722D01*
G01X-1435005D02*
X-1437662D01*
G01X-1438945D02*
X-1441602D01*
G01X-1442885D02*
X-1445542D01*
G01X-1446825D02*
X-1449482D01*
G01X-1450765D02*
X-1453422D01*
G01X-1431126Y1049044D02*
X-1431500D01*
G01X-1433287D02*
X-1433661D01*
G01X-1435065D02*
X-1435440D01*
G01X-1439005D02*
X-1439380D01*
G01X-1437227D02*
X-1437602D01*
G01X-1441167D02*
X-1441541D01*
G01X-1445107D02*
X-1445481D01*
G01X-1442945D02*
X-1443320D01*
G01X-1449047D02*
X-1449421D01*
G01X-1446885D02*
X-1447260D01*
G01X-1450826D02*
X-1451200D01*
G01X-1452987D02*
X-1453361D01*
G01X-1452900Y1049107D02*
X-1451286D01*
G01X-1448961D02*
X-1447346D01*
G01X-1445020D02*
X-1443406D01*
G01X-1441080D02*
X-1439466D01*
G01X-1437141D02*
X-1435526D01*
G01X-1433200D02*
X-1431586D01*
G01X-1433343Y1049156D02*
X-1435383D01*
G01X-1437283D02*
X-1439323D01*
G01X-1441223D02*
X-1443263D01*
G01X-1445163D02*
X-1447204D01*
G01X-1449104D02*
X-1451143D01*
G01X-1431443D02*
X-1428443D01*
G01X-1451143Y1049371D02*
X-1449104D01*
G01X-1447204D02*
X-1445163D01*
G01X-1443263D02*
X-1441223D01*
G01X-1439323D02*
X-1437283D01*
G01X-1435383D02*
X-1433343D01*
G01X-1431443D02*
X-1428443D01*
G01X-1432032Y1049542D02*
X-1432741D01*
G01X-1435972D02*
X-1436681D01*
G01X-1439912D02*
X-1440620D01*
G01X-1443852D02*
X-1444561D01*
G01X-1447792D02*
X-1448500D01*
G01X-1451732D02*
X-1452441D01*
G01X-1452900Y1050881D02*
X-1451286D01*
G01X-1448961D02*
X-1447346D01*
G01X-1445020D02*
X-1443406D01*
G01X-1441080D02*
X-1439466D01*
G01X-1437141D02*
X-1435526D01*
G01X-1433200D02*
X-1431586D01*
G01X-1451143Y1050956D02*
X-1449104D01*
G01X-1447204D02*
X-1445163D01*
G01X-1443263D02*
X-1441223D01*
G01X-1439323D02*
X-1437283D01*
G01X-1435383D02*
X-1433343D01*
G01X-1431443D02*
X-1427165D01*
G01X-1452900Y1051412D02*
X-1451286D01*
G01X-1448961D02*
X-1447346D01*
G01X-1445020D02*
X-1443406D01*
G01X-1441080D02*
X-1439466D01*
G01X-1437141D02*
X-1435526D01*
G01X-1433200D02*
X-1431586D01*
G01X-1453443Y1048465D02*
X-1453422D01*
G01X-1449504D02*
X-1449482D01*
G01X-1445563D02*
X-1445542D01*
G01X-1441623D02*
X-1441602D01*
G01X-1432741Y1049542D02*
X-1432819Y1049520D01*
X-1432900Y1049494D01*
X-1432979Y1049463D01*
X-1433055Y1049428D01*
X-1433129Y1049390D01*
X-1433200Y1049347D01*
G01X-1436681Y1049542D02*
X-1436759Y1049520D01*
X-1436840Y1049494D01*
X-1436919Y1049463D01*
X-1436995Y1049428D01*
X-1437069Y1049390D01*
X-1437141Y1049347D01*
G01X-1440620Y1049542D02*
X-1440699Y1049520D01*
X-1440780Y1049494D01*
X-1440859Y1049463D01*
X-1440935Y1049428D01*
X-1441009Y1049390D01*
X-1441080Y1049347D01*
G01X-1444561Y1049542D02*
X-1444639Y1049520D01*
X-1444720Y1049494D01*
X-1444799Y1049463D01*
X-1444876Y1049428D01*
X-1444949Y1049390D01*
X-1445020Y1049347D01*
G01X-1448500Y1049542D02*
X-1448579Y1049520D01*
X-1448660Y1049494D01*
X-1448739Y1049463D01*
X-1448815Y1049428D01*
X-1448889Y1049390D01*
X-1448961Y1049347D01*
G01X-1452441Y1049542D02*
X-1452519Y1049520D01*
X-1452600Y1049494D01*
X-1452679Y1049463D01*
X-1452755Y1049428D01*
X-1452829Y1049390D01*
X-1452900Y1049347D01*
G01X-1451918Y1041804D02*
X-1452135Y1041759D01*
G01X-1431065Y1048465D02*
X-1430954Y1048484D01*
X-1430853Y1048541D01*
X-1430769Y1048632D01*
G01X-1435005Y1048465D02*
X-1434894Y1048484D01*
X-1434793Y1048541D01*
X-1434709Y1048632D01*
G01X-1438945Y1048465D02*
X-1438834Y1048484D01*
X-1438733Y1048541D01*
X-1438649Y1048632D01*
G01X-1452283Y1046256D02*
G03X-1452783Y1045756I0J-500D01*
G01X-1451283D02*
G03X-1451783Y1046256I-500J0D01*
G01X-1448360D02*
G03X-1448860Y1045756I0J-500D01*
G01X-1447360D02*
G03X-1447860Y1046256I-500J0D01*
G01X-1444436D02*
G03X-1444936Y1045756I0J-500D01*
G01X-1443436D02*
G03X-1443936Y1046256I-500J0D01*
G01X-1460483Y1060079D02*
X-1460624Y1059913D01*
X-1460721Y1059729D01*
X-1460777Y1059541D01*
X-1460793Y1059355D01*
G01X-1460483Y1060677D02*
X-1461966Y1059678D01*
G01X-1454605Y1058256D02*
X-1456631Y1052691D01*
G01X-1462433Y1064456D02*
Y1059926D01*
G01X-1461483Y1052356D02*
Y1056856D01*
G01X-1461276Y1052356D02*
Y1056856D01*
G01X-1461107Y1052356D02*
Y1056856D01*
G01X-1460852Y1052356D02*
Y1056856D01*
G01X-1460793Y1059355D02*
Y1056856D01*
G01X-1460631Y1052356D02*
Y1056856D01*
G01X-1460033Y1065106D02*
Y1061206D01*
G01X-1459983Y1057106D02*
Y1060611D01*
G01X-1459533Y1057106D02*
Y1052106D01*
G01X-1460552Y1060589D02*
X-1460753Y1060581D01*
X-1460905Y1060572D01*
X-1461001Y1060563D01*
X-1461033Y1060555D01*
G01X-1460060Y1060606D02*
X-1460552Y1060589D01*
G01X-1453043Y1051956D02*
X-1455983D01*
G01X-1459533Y1052106D02*
X-1461033D01*
G01X-1460483Y1052356D02*
X-1461033D01*
G01D02*
X-1461483D01*
G01X-1452183Y1056656D02*
X-1455983D01*
G01X-1460483Y1056856D02*
X-1461033D01*
G01X-1461483D02*
X-1461033D01*
G01X-1459533Y1057106D02*
X-1461033D01*
G01X-1451104Y1057256D02*
X-1454969D01*
G01X-1451104Y1058256D02*
X-1454605D01*
G01X-1460793Y1059355D02*
X-1461033D01*
G01Y1060354D02*
X-1460483D01*
G01Y1060555D02*
X-1461033D01*
G01X-1460060Y1060606D02*
X-1460020D01*
G01X-1441223Y1062856D02*
X-1462433D01*
G01X-1441223Y1064456D02*
X-1462433D01*
G01X-1456533Y1065106D02*
X-1460033D01*
G01X-1459983Y1060611D02*
X-1459995Y1060608D01*
X-1460001Y1060607D01*
X-1460007D01*
X-1460013Y1060606D01*
X-1460020D01*
G01X-1459983Y1060611D02*
X-1460008Y1060608D01*
X-1460020Y1060607D01*
X-1460034D01*
X-1460047Y1060606D01*
X-1460060D01*
G01X-1460020D02*
X-1460166Y1060596D01*
X-1460295Y1060586D01*
X-1460396Y1060576D01*
X-1460461Y1060565D01*
X-1460483Y1060555D01*
G01X-1456631Y1052691D02*
G03X-1455983Y1051956I248J-434D01*
G01X-1452833Y1058936D02*
G03I-1250J0D01*
G01X-1462433Y1059926D02*
G03X-1461966Y1059678I300J1D01*
G01X-1459983Y1060611D02*
G03X-1460033Y1061206I-52J295D01*
G01X-1449260Y1060168D02*
X-1448904Y1060580D01*
G01X-1451403D02*
X-1451504Y1060495D01*
G01X-1451047Y1060168D02*
X-1451178Y1060056D01*
G01X-1447463Y1060580D02*
X-1447563Y1060495D01*
G01X-1447107Y1060168D02*
X-1447238Y1060056D01*
G01X-1443523Y1060580D02*
X-1443623Y1060495D01*
G01X-1443167Y1060168D02*
X-1443298Y1060056D01*
G01X-1439583Y1060580D02*
X-1440016Y1060211D01*
G01X-1449346Y1057430D02*
X-1449413Y1057381D01*
X-1449486Y1057334D01*
X-1449562Y1057292D01*
X-1449641Y1057254D01*
X-1449721Y1057221D01*
X-1449806Y1057192D01*
G01X-1445406Y1057430D02*
X-1445472Y1057381D01*
X-1445546Y1057334D01*
X-1445622Y1057292D01*
X-1445700Y1057254D01*
X-1445781Y1057221D01*
X-1445866Y1057192D01*
G01X-1452900Y1051783D02*
X-1452834Y1051831D01*
X-1452761Y1051878D01*
X-1452685Y1051921D01*
X-1452606Y1051959D01*
X-1452526Y1051992D01*
X-1452441Y1052020D01*
G01X-1448885Y1060168D02*
X-1448863Y1060185D01*
X-1448843Y1060195D01*
X-1448825Y1060198D01*
G01X-1444945Y1060168D02*
X-1444922Y1060185D01*
X-1444903Y1060195D01*
X-1444885Y1060198D01*
G01X-1441005Y1060168D02*
X-1440983Y1060185D01*
X-1440963Y1060195D01*
X-1440945Y1060198D01*
G01X-1451403Y1060580D02*
X-1451270Y1060672D01*
X-1451120Y1060729D01*
X-1450961Y1060748D01*
G01X-1447463Y1060580D02*
X-1447330Y1060672D01*
X-1447180Y1060729D01*
X-1447020Y1060748D01*
G01X-1443523Y1060580D02*
X-1443390Y1060672D01*
X-1443240Y1060729D01*
X-1443080Y1060748D01*
G01X-1451047Y1060168D02*
X-1451020Y1060185D01*
X-1450991Y1060195D01*
X-1450961Y1060198D01*
G01X-1447107Y1060168D02*
X-1447081Y1060185D01*
X-1447051Y1060195D01*
X-1447020Y1060198D01*
G01X-1448804Y1060263D02*
X-1448885Y1060168D01*
G01X-1445320D02*
X-1444964Y1060580D01*
G01X-1444863Y1060263D02*
X-1444945Y1060168D01*
G01X-1441380D02*
X-1441024Y1060580D01*
G01X-1440649D02*
X-1441005Y1060168D01*
G01X-1440947Y1059799D02*
X-1440591Y1060211D01*
G01X-1437440Y1060168D02*
X-1437083Y1060580D01*
G01X-1436709D02*
X-1437065Y1060168D01*
G01X-1437007Y1059799D02*
X-1436651Y1060211D01*
G01X-1433500Y1060168D02*
X-1433144Y1060580D01*
G01X-1432769D02*
X-1433126Y1060168D01*
G01X-1433067Y1059799D02*
X-1432711Y1060211D01*
G01X-1439227Y1060168D02*
X-1439659Y1059799D01*
G01X-1435643Y1060580D02*
X-1436076Y1060211D01*
G01X-1435287Y1060168D02*
X-1435720Y1059799D01*
G01X-1441466Y1057430D02*
X-1441533Y1057381D01*
X-1441605Y1057334D01*
X-1441682Y1057292D01*
X-1441760Y1057254D01*
X-1441841Y1057221D01*
X-1441926Y1057192D01*
G01X-1448961Y1051783D02*
X-1448894Y1051831D01*
X-1448821Y1051878D01*
X-1448745Y1051921D01*
X-1448667Y1051959D01*
X-1448585Y1051992D01*
X-1448500Y1052020D01*
G01X-1437526Y1057430D02*
X-1437593Y1057381D01*
X-1437666Y1057334D01*
X-1437742Y1057292D01*
X-1437820Y1057254D01*
X-1437902Y1057221D01*
X-1437986Y1057192D01*
G01X-1445020Y1051783D02*
X-1444954Y1051831D01*
X-1444881Y1051878D01*
X-1444805Y1051921D01*
X-1444726Y1051959D01*
X-1444645Y1051992D01*
X-1444561Y1052020D01*
G01X-1433586Y1057430D02*
X-1433652Y1057381D01*
X-1433726Y1057334D01*
X-1433802Y1057292D01*
X-1433880Y1057254D01*
X-1433961Y1057221D01*
X-1434046Y1057192D01*
G01X-1441080Y1051783D02*
X-1441014Y1051831D01*
X-1440941Y1051878D01*
X-1440865Y1051921D01*
X-1440786Y1051959D01*
X-1440705Y1051992D01*
X-1440620Y1052020D01*
G01X-1437141Y1051783D02*
X-1437074Y1051831D01*
X-1437001Y1051878D01*
X-1436925Y1051921D01*
X-1436846Y1051959D01*
X-1436765Y1051992D01*
X-1436681Y1052020D01*
G01X-1433200Y1051783D02*
X-1433134Y1051831D01*
X-1433061Y1051878D01*
X-1432985Y1051921D01*
X-1432906Y1051959D01*
X-1432826Y1051992D01*
X-1432741Y1052020D01*
G01X-1437065Y1060168D02*
X-1437043Y1060185D01*
X-1437023Y1060195D01*
X-1437005Y1060198D01*
G01X-1433126Y1060168D02*
X-1433103Y1060185D01*
X-1433083Y1060195D01*
X-1433065Y1060198D01*
G01X-1439583Y1060580D02*
X-1439450Y1060672D01*
X-1439300Y1060729D01*
X-1439141Y1060748D01*
G01X-1435643Y1060580D02*
X-1435510Y1060672D01*
X-1435360Y1060729D01*
X-1435200Y1060748D01*
G01X-1443167Y1060168D02*
X-1443141Y1060185D01*
X-1443111Y1060195D01*
X-1443080Y1060198D01*
G01X-1439227Y1060168D02*
X-1439200Y1060185D01*
X-1439171Y1060195D01*
X-1439141Y1060198D01*
G01X-1435287Y1060168D02*
X-1435261Y1060185D01*
X-1435231Y1060195D01*
X-1435200Y1060198D01*
G01X-1449346Y1057111D02*
X-1449413Y1057071D01*
X-1449486Y1057033D01*
X-1449562Y1056998D01*
X-1449641Y1056966D01*
X-1449721Y1056940D01*
X-1449806Y1056916D01*
G01X-1445406Y1057111D02*
X-1445472Y1057071D01*
X-1445546Y1057033D01*
X-1445622Y1056998D01*
X-1445700Y1056966D01*
X-1445781Y1056940D01*
X-1445866Y1056916D01*
G01X-1452900Y1052102D02*
X-1452834Y1052141D01*
X-1452761Y1052180D01*
X-1452685Y1052215D01*
X-1452606Y1052246D01*
X-1452526Y1052273D01*
X-1452441Y1052296D01*
G01X-1441466Y1057111D02*
X-1441533Y1057071D01*
X-1441605Y1057033D01*
X-1441682Y1056998D01*
X-1441760Y1056966D01*
X-1441841Y1056940D01*
X-1441926Y1056916D01*
G01X-1448961Y1052102D02*
X-1448894Y1052141D01*
X-1448821Y1052180D01*
X-1448745Y1052215D01*
X-1448667Y1052246D01*
X-1448585Y1052273D01*
X-1448500Y1052296D01*
G01X-1437526Y1057111D02*
X-1437593Y1057071D01*
X-1437666Y1057033D01*
X-1437742Y1056998D01*
X-1437820Y1056966D01*
X-1437902Y1056940D01*
X-1437986Y1056916D01*
G01X-1445020Y1052102D02*
X-1444954Y1052141D01*
X-1444881Y1052180D01*
X-1444805Y1052215D01*
X-1444726Y1052246D01*
X-1444645Y1052273D01*
X-1444561Y1052296D01*
G01X-1433586Y1057111D02*
X-1433652Y1057071D01*
X-1433726Y1057033D01*
X-1433802Y1056998D01*
X-1433880Y1056966D01*
X-1433961Y1056940D01*
X-1434046Y1056916D01*
G01X-1441080Y1052102D02*
X-1441014Y1052141D01*
X-1440941Y1052180D01*
X-1440865Y1052215D01*
X-1440786Y1052246D01*
X-1440705Y1052273D01*
X-1440620Y1052296D01*
G01X-1437141Y1052102D02*
X-1437074Y1052141D01*
X-1437001Y1052180D01*
X-1436925Y1052215D01*
X-1436846Y1052246D01*
X-1436765Y1052273D01*
X-1436681Y1052296D01*
G01X-1433200Y1052102D02*
X-1433134Y1052141D01*
X-1433061Y1052180D01*
X-1432985Y1052215D01*
X-1432906Y1052246D01*
X-1432826Y1052273D01*
X-1432741Y1052296D01*
G01X-1449806Y1056741D02*
X-1449728Y1056768D01*
X-1449646Y1056800D01*
X-1449568Y1056838D01*
X-1449491Y1056880D01*
X-1449418Y1056927D01*
X-1449346Y1056979D01*
G01X-1445866Y1056741D02*
X-1445788Y1056768D01*
X-1445707Y1056800D01*
X-1445628Y1056838D01*
X-1445552Y1056880D01*
X-1445478Y1056927D01*
X-1445406Y1056979D01*
G01X-1441926Y1056741D02*
X-1441848Y1056768D01*
X-1441767Y1056800D01*
X-1441688Y1056838D01*
X-1441611Y1056880D01*
X-1441538Y1056927D01*
X-1441466Y1056979D01*
G01X-1452441Y1052471D02*
X-1452519Y1052445D01*
X-1452600Y1052412D01*
X-1452679Y1052375D01*
X-1452755Y1052333D01*
X-1452829Y1052286D01*
X-1452900Y1052233D01*
G01X-1437986Y1056741D02*
X-1437908Y1056768D01*
X-1437827Y1056800D01*
X-1437748Y1056838D01*
X-1437671Y1056880D01*
X-1437598Y1056927D01*
X-1437526Y1056979D01*
G01X-1448500Y1052471D02*
X-1448579Y1052445D01*
X-1448660Y1052412D01*
X-1448739Y1052375D01*
X-1448815Y1052333D01*
X-1448889Y1052286D01*
X-1448961Y1052233D01*
G01X-1434046Y1056741D02*
X-1433968Y1056768D01*
X-1433887Y1056800D01*
X-1433808Y1056838D01*
X-1433731Y1056880D01*
X-1433658Y1056927D01*
X-1433586Y1056979D01*
G01X-1444561Y1052471D02*
X-1444639Y1052445D01*
X-1444720Y1052412D01*
X-1444799Y1052375D01*
X-1444876Y1052333D01*
X-1444949Y1052286D01*
X-1445020Y1052233D01*
G01X-1440620Y1052471D02*
X-1440699Y1052445D01*
X-1440780Y1052412D01*
X-1440859Y1052375D01*
X-1440935Y1052333D01*
X-1441009Y1052286D01*
X-1441080Y1052233D01*
G01X-1436681Y1052471D02*
X-1436759Y1052445D01*
X-1436840Y1052412D01*
X-1436919Y1052375D01*
X-1436995Y1052333D01*
X-1437069Y1052286D01*
X-1437141Y1052233D01*
G01X-1432741Y1052471D02*
X-1432819Y1052445D01*
X-1432900Y1052412D01*
X-1432979Y1052375D01*
X-1433055Y1052333D01*
X-1433129Y1052286D01*
X-1433200Y1052233D01*
G01X-1451439Y1060056D02*
X-1451421Y1060168D01*
G01X-1447499Y1060056D02*
X-1447481Y1060168D01*
G01X-1443559Y1060056D02*
X-1443541Y1060168D01*
G01X-1440016Y1060211D02*
X-1439958Y1060580D01*
G01X-1439659Y1059799D02*
X-1439602Y1060168D01*
G01X-1436076Y1060211D02*
X-1436018Y1060580D01*
G01X-1435720Y1059799D02*
X-1435661Y1060168D01*
G01X-1448825Y1060274D02*
X-1448826Y1060263D01*
X-1448838Y1060232D01*
X-1448868Y1060189D01*
G01X-1444885Y1060274D02*
X-1444887Y1060263D01*
X-1444898Y1060232D01*
X-1444928Y1060189D01*
G01X-1440945Y1060274D02*
X-1440946Y1060263D01*
X-1440958Y1060232D01*
X-1440988Y1060189D01*
G01X-1437005Y1060274D02*
X-1437007Y1060263D01*
X-1437018Y1060232D01*
X-1437048Y1060189D01*
G01X-1433065Y1060274D02*
X-1433067Y1060263D01*
X-1433078Y1060232D01*
X-1433108Y1060189D01*
G01X-1452183Y1060756D02*
Y1056656D01*
G01Y1062856D02*
Y1060956D01*
G01X-1451504Y1061506D02*
Y1060056D01*
G01X-1451482Y1060748D02*
Y1060198D01*
G01X-1451354Y1060748D02*
Y1060198D01*
G01X-1451209D02*
Y1060748D01*
G01X-1451104Y1060056D02*
Y1055806D01*
G01X-1451001Y1060748D02*
Y1060198D01*
G01X-1450972Y1060748D02*
Y1060198D01*
G01X-1450961Y1056942D02*
Y1065798D01*
G01X-1450515Y1056707D02*
Y1059670D01*
G01X-1449806D02*
Y1056707D01*
G01X-1449346Y1056954D02*
Y1065798D01*
G01X-1449335Y1060198D02*
Y1060748D01*
G01X-1449306Y1060198D02*
Y1060748D01*
G01X-1449204Y1060056D02*
Y1055806D01*
G01X-1449098Y1060748D02*
Y1060198D01*
G01X-1448954D02*
Y1060748D01*
G01X-1448825Y1060198D02*
Y1060748D01*
G01X-1448804Y1060056D02*
Y1061506D01*
G01X-1447563D02*
Y1060056D01*
G01X-1447542Y1060748D02*
Y1060198D01*
G01X-1447413Y1060748D02*
Y1060198D01*
G01X-1447269D02*
Y1060748D01*
G01X-1447163Y1060056D02*
Y1055806D01*
G01X-1447061Y1060748D02*
Y1060198D01*
G01X-1447031Y1060748D02*
Y1060198D01*
G01X-1447020Y1056942D02*
Y1065798D01*
G01X-1446575Y1056707D02*
Y1059670D01*
G01X-1445866D02*
Y1056707D01*
G01X-1445406Y1056954D02*
Y1065798D01*
G01X-1445395Y1060198D02*
Y1060748D01*
G01X-1445366Y1060198D02*
Y1060748D01*
G01X-1445263Y1060056D02*
Y1055806D01*
G01X-1445158Y1060748D02*
Y1060198D01*
G01X-1445013D02*
Y1060748D01*
G01X-1444885Y1060198D02*
Y1060748D01*
G01X-1444863Y1060056D02*
Y1061506D01*
G01X-1443623D02*
Y1060056D01*
G01X-1443602Y1060748D02*
Y1060198D01*
G01X-1443473Y1060748D02*
Y1060198D01*
G01X-1443329D02*
Y1060748D01*
G01X-1443223Y1060056D02*
Y1055806D01*
G01X-1443121Y1060748D02*
Y1060198D01*
G01X-1443091Y1060748D02*
Y1060198D01*
G01X-1443080Y1056942D02*
Y1065798D01*
G01X-1442635Y1056707D02*
Y1059670D01*
G01X-1441926D02*
Y1056707D01*
G01X-1441466Y1056954D02*
Y1065798D01*
G01X-1441455Y1060198D02*
Y1060748D01*
G01X-1441426Y1060198D02*
Y1060748D01*
G01X-1441323Y1060056D02*
Y1055806D01*
G01X-1441223Y1064456D02*
Y1060756D01*
G01X-1441218Y1060748D02*
Y1060198D01*
G01X-1441073D02*
Y1060748D01*
G01X-1440945Y1060198D02*
Y1060748D01*
G01X-1440923Y1060056D02*
Y1061506D01*
G01X-1439683D02*
Y1060056D01*
G01X-1439662Y1060748D02*
Y1060198D01*
G01X-1439533Y1060748D02*
Y1060198D01*
G01X-1439389D02*
Y1060748D01*
G01X-1439283Y1060056D02*
Y1055806D01*
G01X-1439181Y1060748D02*
Y1060198D01*
G01X-1439152Y1060748D02*
Y1060198D01*
G01X-1439141Y1056942D02*
Y1065798D01*
G01X-1438695Y1056707D02*
Y1059670D01*
G01X-1437986D02*
Y1056707D01*
G01X-1437526Y1056954D02*
Y1065798D01*
G01X-1437515Y1060198D02*
Y1060748D01*
G01X-1437486Y1060198D02*
Y1060748D01*
G01X-1437383Y1060056D02*
Y1055806D01*
G01X-1437278Y1060748D02*
Y1060198D01*
G01X-1437133D02*
Y1060748D01*
G01X-1437005Y1060198D02*
Y1060748D01*
G01X-1436983Y1060056D02*
Y1061506D01*
G01X-1435743D02*
Y1060056D01*
G01X-1435722Y1060748D02*
Y1060198D01*
G01X-1435593Y1060748D02*
Y1060198D01*
G01X-1435449D02*
Y1060748D01*
G01X-1435343Y1060056D02*
Y1055806D01*
G01X-1435241Y1060748D02*
Y1060198D01*
G01X-1435211Y1060748D02*
Y1060198D01*
G01X-1435200Y1056942D02*
Y1065798D01*
G01X-1434755Y1056707D02*
Y1059670D01*
G01X-1434046D02*
Y1056707D01*
G01X-1433586Y1056954D02*
Y1065798D01*
G01X-1433575Y1060198D02*
Y1060748D01*
G01X-1433546Y1060198D02*
Y1060748D01*
G01X-1433443Y1060056D02*
Y1055806D01*
G01X-1433338Y1060748D02*
Y1060198D01*
G01X-1433193D02*
Y1060748D01*
G01X-1433065Y1060198D02*
Y1060748D01*
G01X-1433043Y1060056D02*
Y1061506D01*
G01X-1432243Y1060756D02*
Y1056656D01*
G01Y1062856D02*
Y1060956D01*
G01X-1448885Y1060168D02*
X-1448868Y1060056D01*
G01X-1444945Y1060168D02*
X-1444928Y1060056D01*
G01X-1450961Y1060744D02*
Y1060745D01*
X-1450963Y1060747D01*
X-1450965Y1060748D01*
X-1450972D01*
G01X-1447020Y1060744D02*
X-1447023Y1060747D01*
X-1447025Y1060748D01*
X-1447031D01*
G01X-1443080Y1060744D02*
X-1443081Y1060745D01*
Y1060746D01*
X-1443083Y1060747D01*
X-1443088Y1060748D01*
X-1443091D01*
G01X-1439141Y1060744D02*
Y1060745D01*
X-1439143Y1060747D01*
X-1439145Y1060748D01*
X-1439152D01*
G01X-1441005Y1060168D02*
X-1440947Y1059799D01*
G01X-1440649Y1060580D02*
X-1440591Y1060211D01*
G01X-1437065Y1060168D02*
X-1437007Y1059799D01*
G01X-1436709Y1060580D02*
X-1436651Y1060211D01*
G01X-1433126Y1060168D02*
X-1433067Y1059799D01*
G01X-1432769Y1060580D02*
X-1432711Y1060211D01*
G01X-1435200Y1060744D02*
X-1435203Y1060747D01*
X-1435205Y1060748D01*
X-1435211D01*
G01X-1429822Y1058256D02*
X-1427796Y1052691D01*
G01X-1451439Y1060189D02*
X-1451468Y1060232D01*
X-1451480Y1060263D01*
X-1451482Y1060274D01*
G01X-1447499Y1060189D02*
X-1447529Y1060232D01*
X-1447540Y1060263D01*
X-1447542Y1060274D01*
G01X-1443559Y1060189D02*
X-1443589Y1060232D01*
X-1443600Y1060263D01*
X-1443602Y1060274D01*
G01X-1439619Y1060189D02*
X-1439648Y1060232D01*
X-1439660Y1060263D01*
X-1439662Y1060274D01*
G01X-1435679Y1060189D02*
X-1435709Y1060232D01*
X-1435720Y1060263D01*
X-1435722Y1060274D01*
G01X-1440649Y1060580D02*
X-1440733Y1060672D01*
X-1440834Y1060729D01*
X-1440945Y1060748D01*
G01X-1436709Y1060580D02*
X-1436793Y1060672D01*
X-1436894Y1060729D01*
X-1437005Y1060748D01*
G01X-1432769Y1060580D02*
X-1432853Y1060672D01*
X-1432954Y1060729D01*
X-1433065Y1060748D01*
G01X-1450961Y1060196D02*
X-1450962Y1060197D01*
X-1450965Y1060198D01*
X-1450972D01*
G01X-1447020Y1060196D02*
X-1447022Y1060197D01*
X-1447025Y1060198D01*
X-1447031D01*
G01X-1443080Y1060196D02*
X-1443082Y1060197D01*
X-1443085Y1060198D01*
X-1443091D01*
G01X-1439141Y1060196D02*
X-1439142Y1060197D01*
X-1439145Y1060198D01*
X-1439152D01*
G01X-1435200Y1060196D02*
X-1435202Y1060197D01*
X-1435205Y1060198D01*
X-1435211D01*
G01X-1451421Y1060168D02*
X-1451504Y1060263D01*
G01X-1451403Y1060580D02*
X-1451047Y1060168D01*
G01X-1447481D02*
X-1447563Y1060263D01*
G01X-1447463Y1060580D02*
X-1447107Y1060168D01*
G01X-1443541D02*
X-1443623Y1060263D01*
G01X-1443523Y1060580D02*
X-1443167Y1060168D01*
G01X-1439659Y1059799D02*
X-1440016Y1060211D01*
G01X-1439602Y1060168D02*
X-1439958Y1060580D01*
G01X-1439583D02*
X-1439227Y1060168D01*
G01X-1435720Y1059799D02*
X-1436076Y1060211D01*
G01X-1435661Y1060168D02*
X-1436018Y1060580D01*
G01X-1435643D02*
X-1435287Y1060168D01*
G01X-1449260D02*
X-1449129Y1060056D01*
G01X-1448804Y1060495D02*
X-1448904Y1060580D01*
G01X-1445320Y1060168D02*
X-1445189Y1060056D01*
G01X-1444863Y1060495D02*
X-1444964Y1060580D01*
G01X-1441223Y1060035D02*
X-1440947Y1059799D01*
G01X-1441380Y1060168D02*
X-1441249Y1060056D01*
G01X-1440591Y1060211D02*
X-1441024Y1060580D01*
G01X-1437440Y1060168D02*
X-1437007Y1059799D01*
G01X-1436651Y1060211D02*
X-1437083Y1060580D01*
G01X-1433500Y1060168D02*
X-1433067Y1059799D01*
G01X-1432711Y1060211D02*
X-1433144Y1060580D01*
G01X-1451286Y1052244D02*
X-1451353Y1052292D01*
X-1451423Y1052336D01*
X-1451495Y1052376D01*
X-1451574Y1052413D01*
X-1451650Y1052444D01*
X-1451732Y1052471D01*
G01X-1447346Y1052244D02*
X-1447413Y1052292D01*
X-1447483Y1052336D01*
X-1447555Y1052376D01*
X-1447634Y1052413D01*
X-1447711Y1052444D01*
X-1447792Y1052471D01*
G01X-1450961Y1056968D02*
X-1450894Y1056920D01*
X-1450824Y1056877D01*
X-1450752Y1056837D01*
X-1450673Y1056800D01*
X-1450596Y1056769D01*
X-1450515Y1056741D01*
G01X-1443406Y1052244D02*
X-1443473Y1052292D01*
X-1443543Y1052336D01*
X-1443615Y1052376D01*
X-1443694Y1052413D01*
X-1443770Y1052444D01*
X-1443852Y1052471D01*
G01X-1447020Y1056968D02*
X-1446954Y1056920D01*
X-1446884Y1056877D01*
X-1446812Y1056837D01*
X-1446733Y1056800D01*
X-1446656Y1056769D01*
X-1446575Y1056741D01*
G01X-1439466Y1052244D02*
X-1439533Y1052292D01*
X-1439603Y1052336D01*
X-1439675Y1052376D01*
X-1439754Y1052413D01*
X-1439830Y1052444D01*
X-1439912Y1052471D01*
G01X-1443080Y1056968D02*
X-1443014Y1056920D01*
X-1442944Y1056877D01*
X-1442872Y1056837D01*
X-1442793Y1056800D01*
X-1442717Y1056769D01*
X-1442635Y1056741D01*
G01X-1435526Y1052244D02*
X-1435593Y1052292D01*
X-1435663Y1052336D01*
X-1435735Y1052376D01*
X-1435814Y1052413D01*
X-1435891Y1052444D01*
X-1435972Y1052471D01*
G01X-1439141Y1056968D02*
X-1439074Y1056920D01*
X-1439004Y1056877D01*
X-1438932Y1056837D01*
X-1438853Y1056800D01*
X-1438776Y1056769D01*
X-1438695Y1056741D01*
G01X-1431586Y1052244D02*
X-1431653Y1052292D01*
X-1431723Y1052336D01*
X-1431795Y1052376D01*
X-1431874Y1052413D01*
X-1431950Y1052444D01*
X-1432032Y1052471D01*
G01X-1435200Y1056968D02*
X-1435134Y1056920D01*
X-1435064Y1056877D01*
X-1434992Y1056837D01*
X-1434913Y1056800D01*
X-1434836Y1056769D01*
X-1434755Y1056741D01*
G01X-1450961Y1059856D02*
X-1450894Y1059817D01*
X-1450824Y1059781D01*
X-1450752Y1059749D01*
X-1450673Y1059718D01*
X-1450596Y1059693D01*
X-1450515Y1059670D01*
G01X-1447020Y1059856D02*
X-1446954Y1059817D01*
X-1446884Y1059781D01*
X-1446812Y1059749D01*
X-1446733Y1059718D01*
X-1446656Y1059693D01*
X-1446575Y1059670D01*
G01X-1443080Y1059856D02*
X-1443014Y1059817D01*
X-1442944Y1059781D01*
X-1442872Y1059749D01*
X-1442793Y1059718D01*
X-1442717Y1059693D01*
X-1442635Y1059670D01*
G01X-1439141Y1059856D02*
X-1439074Y1059817D01*
X-1439004Y1059781D01*
X-1438932Y1059749D01*
X-1438853Y1059718D01*
X-1438776Y1059693D01*
X-1438695Y1059670D01*
G01X-1435200Y1059856D02*
X-1435134Y1059817D01*
X-1435064Y1059781D01*
X-1434992Y1059749D01*
X-1434913Y1059718D01*
X-1434836Y1059693D01*
X-1434755Y1059670D01*
G01X-1451732Y1052296D02*
X-1451654Y1052275D01*
X-1451577Y1052250D01*
X-1451502Y1052221D01*
X-1451426Y1052187D01*
X-1451356Y1052151D01*
X-1451286Y1052111D01*
G01X-1447792Y1052296D02*
X-1447714Y1052275D01*
X-1447637Y1052250D01*
X-1447562Y1052221D01*
X-1447485Y1052187D01*
X-1447416Y1052151D01*
X-1447346Y1052111D01*
G01X-1443852Y1052296D02*
X-1443774Y1052275D01*
X-1443697Y1052250D01*
X-1443622Y1052221D01*
X-1443546Y1052187D01*
X-1443476Y1052151D01*
X-1443406Y1052111D01*
G01X-1439912Y1052296D02*
X-1439833Y1052275D01*
X-1439757Y1052250D01*
X-1439682Y1052221D01*
X-1439605Y1052187D01*
X-1439536Y1052151D01*
X-1439466Y1052111D01*
G01X-1435972Y1052296D02*
X-1435894Y1052275D01*
X-1435817Y1052250D01*
X-1435742Y1052221D01*
X-1435666Y1052187D01*
X-1435596Y1052151D01*
X-1435526Y1052111D01*
G01X-1450515Y1056916D02*
X-1450593Y1056938D01*
X-1450670Y1056963D01*
X-1450744Y1056991D01*
X-1450821Y1057026D01*
X-1450891Y1057061D01*
X-1450961Y1057102D01*
G01X-1432032Y1052296D02*
X-1431954Y1052275D01*
X-1431877Y1052250D01*
X-1431802Y1052221D01*
X-1431726Y1052187D01*
X-1431656Y1052151D01*
X-1431586Y1052111D01*
G01X-1446575Y1056916D02*
X-1446653Y1056938D01*
X-1446730Y1056963D01*
X-1446805Y1056991D01*
X-1446881Y1057026D01*
X-1446951Y1057061D01*
X-1447020Y1057102D01*
G01X-1442635Y1056916D02*
X-1442713Y1056938D01*
X-1442790Y1056963D01*
X-1442865Y1056991D01*
X-1442941Y1057026D01*
X-1443011Y1057061D01*
X-1443080Y1057102D01*
G01X-1438695Y1056916D02*
X-1438773Y1056938D01*
X-1438850Y1056963D01*
X-1438925Y1056991D01*
X-1439001Y1057026D01*
X-1439071Y1057061D01*
X-1439141Y1057102D01*
G01X-1434755Y1056916D02*
X-1434833Y1056938D01*
X-1434910Y1056963D01*
X-1434985Y1056991D01*
X-1435061Y1057026D01*
X-1435131Y1057061D01*
X-1435200Y1057102D01*
G01X-1451732Y1052020D02*
X-1451654Y1051994D01*
X-1451577Y1051963D01*
X-1451502Y1051928D01*
X-1451426Y1051887D01*
X-1451356Y1051843D01*
X-1451286Y1051794D01*
G01X-1447792Y1052020D02*
X-1447714Y1051994D01*
X-1447637Y1051963D01*
X-1447562Y1051928D01*
X-1447485Y1051887D01*
X-1447416Y1051843D01*
X-1447346Y1051794D01*
G01X-1443852Y1052020D02*
X-1443774Y1051994D01*
X-1443697Y1051963D01*
X-1443622Y1051928D01*
X-1443546Y1051887D01*
X-1443476Y1051843D01*
X-1443406Y1051794D01*
G01X-1439912Y1052020D02*
X-1439833Y1051994D01*
X-1439757Y1051963D01*
X-1439682Y1051928D01*
X-1439605Y1051887D01*
X-1439536Y1051843D01*
X-1439466Y1051794D01*
G01X-1435972Y1052020D02*
X-1435894Y1051994D01*
X-1435817Y1051963D01*
X-1435742Y1051928D01*
X-1435666Y1051887D01*
X-1435596Y1051843D01*
X-1435526Y1051794D01*
G01X-1450515Y1057192D02*
X-1450593Y1057218D01*
X-1450670Y1057249D01*
X-1450744Y1057284D01*
X-1450821Y1057326D01*
X-1450891Y1057370D01*
X-1450961Y1057419D01*
G01X-1432032Y1052020D02*
X-1431954Y1051994D01*
X-1431877Y1051963D01*
X-1431802Y1051928D01*
X-1431726Y1051887D01*
X-1431656Y1051843D01*
X-1431586Y1051794D01*
G01X-1446575Y1057192D02*
X-1446653Y1057218D01*
X-1446730Y1057249D01*
X-1446805Y1057284D01*
X-1446881Y1057326D01*
X-1446951Y1057370D01*
X-1447020Y1057419D01*
G01X-1442635Y1057192D02*
X-1442713Y1057218D01*
X-1442790Y1057249D01*
X-1442865Y1057284D01*
X-1442941Y1057326D01*
X-1443011Y1057370D01*
X-1443080Y1057419D01*
G01X-1438695Y1057192D02*
X-1438773Y1057218D01*
X-1438850Y1057249D01*
X-1438925Y1057284D01*
X-1439001Y1057326D01*
X-1439071Y1057370D01*
X-1439141Y1057419D01*
G01X-1434755Y1057192D02*
X-1434833Y1057218D01*
X-1434910Y1057249D01*
X-1434985Y1057284D01*
X-1435061Y1057326D01*
X-1435131Y1057370D01*
X-1435200Y1057419D01*
G01X-1449346Y1060198D02*
X-1449315Y1060195D01*
X-1449286Y1060185D01*
X-1449260Y1060168D01*
G01X-1445406Y1060198D02*
X-1445376Y1060195D01*
X-1445346Y1060185D01*
X-1445320Y1060168D01*
G01X-1441466Y1060198D02*
X-1441435Y1060195D01*
X-1441406Y1060185D01*
X-1441380Y1060168D01*
G01X-1437526Y1060198D02*
X-1437496Y1060195D01*
X-1437466Y1060185D01*
X-1437440Y1060168D01*
G01X-1433586Y1060198D02*
X-1433555Y1060195D01*
X-1433526Y1060185D01*
X-1433500Y1060168D01*
G01X-1449346Y1060748D02*
X-1449187Y1060729D01*
X-1449037Y1060672D01*
X-1448904Y1060580D01*
G01X-1445406Y1060748D02*
X-1445247Y1060729D01*
X-1445096Y1060672D01*
X-1444964Y1060580D01*
G01X-1441466Y1060748D02*
X-1441307Y1060729D01*
X-1441156Y1060672D01*
X-1441024Y1060580D01*
G01X-1437526Y1060748D02*
X-1437367Y1060729D01*
X-1437217Y1060672D01*
X-1437083Y1060580D01*
G01X-1433586Y1060748D02*
X-1433427Y1060729D01*
X-1433276Y1060672D01*
X-1433144Y1060580D01*
G01X-1451482Y1060198D02*
X-1451464Y1060195D01*
X-1451444Y1060185D01*
X-1451421Y1060168D01*
G01X-1447542Y1060198D02*
X-1447524Y1060195D01*
X-1447504Y1060185D01*
X-1447481Y1060168D01*
G01X-1443602Y1060198D02*
X-1443584Y1060195D01*
X-1443564Y1060185D01*
X-1443541Y1060168D01*
G01X-1439662Y1060198D02*
X-1439644Y1060195D01*
X-1439624Y1060185D01*
X-1439602Y1060168D01*
G01X-1435722Y1060198D02*
X-1435704Y1060195D01*
X-1435684Y1060185D01*
X-1435661Y1060168D01*
G01X-1433575Y1060198D02*
X-1433581D01*
X-1433585Y1060197D01*
X-1433586Y1060196D01*
G01X-1437515Y1060198D02*
X-1437522D01*
X-1437525Y1060197D01*
X-1437526Y1060196D01*
G01X-1441455Y1060198D02*
X-1441461D01*
X-1441465Y1060197D01*
X-1441466Y1060196D01*
G01X-1445395Y1060198D02*
X-1445402D01*
X-1445405Y1060197D01*
X-1445406Y1060196D01*
G01X-1449335Y1060198D02*
X-1449341D01*
X-1449345Y1060197D01*
X-1449346Y1060196D01*
G01X-1443602Y1060748D02*
X-1443623Y1060747D01*
G01X-1447542Y1060748D02*
X-1447563Y1060747D01*
G01X-1451482Y1060748D02*
X-1451504Y1060747D01*
G01X-1433575Y1060748D02*
X-1433579D01*
X-1433583Y1060747D01*
X-1433585Y1060746D01*
X-1433586D01*
Y1060744D01*
G01X-1437515Y1060748D02*
X-1437521D01*
X-1437524Y1060747D01*
X-1437525Y1060746D01*
X-1437526D01*
Y1060744D01*
G01X-1441455Y1060748D02*
X-1441461D01*
X-1441465Y1060746D01*
X-1441466D01*
Y1060744D01*
G01X-1445395Y1060748D02*
X-1445401D01*
X-1445404Y1060747D01*
X-1445405Y1060746D01*
X-1445406D01*
Y1060744D01*
G01X-1449335Y1060748D02*
X-1449341D01*
X-1449344Y1060747D01*
X-1449346Y1060746D01*
Y1060744D01*
G01X-1452900Y1051862D02*
X-1451286D01*
G01X-1448961D02*
X-1447346D01*
G01X-1445020D02*
X-1443406D01*
G01X-1441080D02*
X-1439466D01*
G01X-1437141D02*
X-1435526D01*
G01X-1433200D02*
X-1431586D01*
G01Y1051941D02*
X-1433200D01*
G01X-1435526D02*
X-1437141D01*
G01X-1439466D02*
X-1441080D01*
G01X-1443406D02*
X-1445020D01*
G01X-1447346D02*
X-1448961D01*
G01X-1451286D02*
X-1452900D01*
G01X-1428443Y1051956D02*
X-1431443D01*
G01X-1433343D02*
X-1435383D01*
G01X-1437283D02*
X-1439323D01*
G01X-1441223D02*
X-1443263D01*
G01X-1445163D02*
X-1447204D01*
G01X-1449104D02*
X-1451143D01*
G01X-1452900D02*
X-1451286D01*
G01X-1448961D02*
X-1447346D01*
G01X-1445020D02*
X-1443406D01*
G01X-1441080D02*
X-1439466D01*
G01X-1437141D02*
X-1435526D01*
G01X-1433200D02*
X-1431586D01*
G01Y1052020D02*
X-1432032D01*
G01X-1432741D02*
X-1433200D01*
G01X-1435526D02*
X-1435972D01*
G01X-1436681D02*
X-1437141D01*
G01X-1439466D02*
X-1439912D01*
G01X-1440620D02*
X-1441080D01*
G01X-1443406D02*
X-1443852D01*
G01X-1444561D02*
X-1445020D01*
G01X-1447346D02*
X-1447792D01*
G01X-1448500D02*
X-1448961D01*
G01X-1451286D02*
X-1451732D01*
G01X-1452441D02*
X-1452900D01*
G01X-1452441Y1052296D02*
X-1451732D01*
G01X-1448500D02*
X-1447792D01*
G01X-1444561D02*
X-1443852D01*
G01X-1440620D02*
X-1439912D01*
G01X-1436681D02*
X-1435972D01*
G01X-1432741D02*
X-1432032D01*
G01Y1052471D02*
X-1432741D01*
G01X-1435972D02*
X-1436681D01*
G01X-1439912D02*
X-1440620D01*
G01X-1443852D02*
X-1444561D01*
G01X-1447792D02*
X-1448500D01*
G01X-1451732D02*
X-1452441D01*
G01Y1052506D02*
X-1451732D01*
G01X-1448500D02*
X-1447792D01*
G01X-1444561D02*
X-1443852D01*
G01X-1440620D02*
X-1439912D01*
G01X-1436681D02*
X-1435972D01*
G01X-1432741D02*
X-1432032D01*
G01X-1431443Y1053406D02*
X-1433343D01*
G01X-1435383D02*
X-1437283D01*
G01X-1439323D02*
X-1441223D01*
G01X-1443263D02*
X-1445163D01*
G01X-1447204D02*
X-1449104D01*
G01X-1451143D02*
X-1453043D01*
G01X-1433443Y1055806D02*
X-1435343D01*
G01X-1437383D02*
X-1439283D01*
G01X-1441323D02*
X-1443223D01*
G01X-1445263D02*
X-1447163D01*
G01X-1449204D02*
X-1451104D01*
G01X-1428443Y1056656D02*
X-1432243D01*
G01X-1434046Y1056706D02*
X-1434755D01*
G01X-1437986D02*
X-1438695D01*
G01X-1441926D02*
X-1442635D01*
G01X-1445866D02*
X-1446575D01*
G01X-1449806D02*
X-1450515D01*
G01Y1056741D02*
X-1449806D01*
G01X-1446575D02*
X-1445866D01*
G01X-1442635D02*
X-1441926D01*
G01X-1438695D02*
X-1437986D01*
G01X-1434755D02*
X-1434046D01*
G01Y1056916D02*
X-1434755D01*
G01X-1437986D02*
X-1438695D01*
G01X-1441926D02*
X-1442635D01*
G01X-1445866D02*
X-1446575D01*
G01X-1449806D02*
X-1450515D01*
G01X-1450961Y1057192D02*
X-1450515D01*
G01X-1449806D02*
X-1449346D01*
G01X-1447020D02*
X-1446575D01*
G01X-1443080D02*
X-1442635D01*
G01X-1445866D02*
X-1445406D01*
G01X-1441926D02*
X-1441466D01*
G01X-1439141D02*
X-1438695D01*
G01X-1437986D02*
X-1437526D01*
G01X-1435200D02*
X-1434755D01*
G01X-1434046D02*
X-1433586D01*
G01Y1057256D02*
X-1435200D01*
G01X-1437526D02*
X-1439141D01*
G01X-1435343D02*
X-1437383D01*
G01X-1443223D02*
X-1445263D01*
G01X-1441466D02*
X-1443080D01*
G01X-1447163D02*
X-1449204D01*
G01X-1445406D02*
X-1447020D01*
G01X-1449346D02*
X-1450961D01*
G01X-1441323D02*
X-1441223D01*
G01D02*
X-1439283D01*
G01X-1433443D02*
X-1429458D01*
G01X-1450961Y1057272D02*
X-1449346D01*
G01X-1447020D02*
X-1445406D01*
G01X-1443080D02*
X-1441466D01*
G01X-1439141D02*
X-1437526D01*
G01X-1435200D02*
X-1433586D01*
G01Y1057351D02*
X-1435200D01*
G01X-1437526D02*
X-1439141D01*
G01X-1441466D02*
X-1443080D01*
G01X-1445406D02*
X-1447020D01*
G01X-1449346D02*
X-1450961D01*
G01X-1433586Y1057800D02*
X-1435200D01*
G01X-1437526D02*
X-1439141D01*
G01X-1441466D02*
X-1443080D01*
G01X-1445406D02*
X-1447020D01*
G01X-1449346D02*
X-1450961D01*
G01X-1429822Y1058256D02*
X-1433443D01*
G01X-1435343D02*
X-1437383D01*
G01X-1441223D02*
X-1441323D01*
G01X-1439283D02*
X-1441223D01*
G01X-1443223D02*
X-1445263D01*
G01X-1447163D02*
X-1449204D01*
G01X-1433586Y1058331D02*
X-1435200D01*
G01X-1437526D02*
X-1439141D01*
G01X-1441466D02*
X-1443080D01*
G01X-1445406D02*
X-1447020D01*
G01X-1449346D02*
X-1450961D01*
G01X-1450515Y1059670D02*
X-1449806D01*
G01X-1446575D02*
X-1445866D01*
G01X-1442635D02*
X-1441926D01*
G01X-1438695D02*
X-1437986D01*
G01X-1434755D02*
X-1434046D01*
G01X-1432243Y1059842D02*
X-1433443D01*
G01X-1435343D02*
X-1437383D01*
G01X-1441223D02*
X-1441323D01*
G01X-1439283D02*
X-1441223D01*
G01X-1443223D02*
X-1445263D01*
G01X-1447163D02*
X-1449204D01*
G01X-1451104D02*
X-1452183D01*
G01X-1443223Y1060056D02*
X-1445263D01*
G01X-1452183D02*
X-1451104D01*
G01X-1449204D02*
X-1447163D01*
G01X-1441323D02*
X-1441223D01*
G01D02*
X-1439283D01*
G01X-1437383D02*
X-1435343D01*
G01X-1433443D02*
X-1432243D01*
G01X-1433586Y1060105D02*
X-1435200D01*
G01X-1437526D02*
X-1439141D01*
G01X-1441466D02*
X-1443080D01*
G01X-1445406D02*
X-1447020D01*
G01X-1449346D02*
X-1450961D01*
G01X-1451421Y1060168D02*
X-1451047D01*
G01X-1447481D02*
X-1447107D01*
G01X-1449260D02*
X-1448885D01*
G01X-1443541D02*
X-1443167D01*
G01X-1445320D02*
X-1444945D01*
G01X-1441380D02*
X-1441005D01*
G01X-1437440D02*
X-1437065D01*
G01X-1439602D02*
X-1439227D01*
G01X-1433500D02*
X-1433126D01*
G01X-1435661D02*
X-1435287D01*
G01X-1433065Y1060198D02*
X-1435722D01*
G01X-1437005D02*
X-1439662D01*
G01X-1440945D02*
X-1443602D01*
G01X-1444885D02*
X-1447542D01*
G01X-1448825D02*
X-1451482D01*
G01X-1451504Y1060580D02*
X-1451403D01*
G01X-1447563D02*
X-1447463D01*
G01X-1448904D02*
X-1448804D01*
G01X-1443623D02*
X-1443523D01*
G01X-1444964D02*
X-1444863D01*
G01X-1441024D02*
X-1440649D01*
G01X-1439958D02*
X-1439583D01*
G01X-1437083D02*
X-1436709D01*
G01X-1433144D02*
X-1432769D01*
G01X-1436018D02*
X-1435643D01*
G01X-1433065Y1060748D02*
X-1435722D01*
G01X-1437005D02*
X-1439662D01*
G01X-1440945D02*
X-1443602D01*
G01X-1444885D02*
X-1447542D01*
G01X-1448825D02*
X-1451482D01*
G01X-1452183Y1060756D02*
X-1441223D01*
G01D02*
X-1432243D01*
G01X-1441466Y1060796D02*
X-1443080D01*
G01X-1445406D02*
X-1447020D01*
G01X-1449346D02*
X-1450961D01*
G01X-1452183Y1060956D02*
X-1441223D01*
G01D02*
X-1432243D01*
G01X-1433586Y1061298D02*
X-1435200D01*
G01X-1437526D02*
X-1439141D01*
G01X-1441466D02*
X-1443080D01*
G01X-1445406D02*
X-1447020D01*
G01X-1449346D02*
X-1450961D01*
G01X-1433043Y1061506D02*
X-1435743D01*
G01X-1436983D02*
X-1439683D01*
G01X-1441223D02*
X-1443623D01*
G01X-1440923D02*
X-1441223D01*
G01X-1444863D02*
X-1447563D01*
G01X-1448804D02*
X-1451504D01*
G01X-1433586Y1061648D02*
X-1435200D01*
G01X-1437526D02*
X-1439141D01*
G01X-1441466D02*
X-1443080D01*
G01X-1445406D02*
X-1447020D01*
G01X-1449346D02*
X-1450961D01*
G01X-1441223Y1061703D02*
X-1452183D01*
G01X-1432243D02*
X-1441223D01*
G01X-1421993Y1062856D02*
X-1441223D01*
G01X-1421993Y1064456D02*
X-1441223D01*
G01X-1433586Y1065798D02*
X-1435200D01*
G01X-1437526D02*
X-1439141D01*
G01X-1441466D02*
X-1443080D01*
G01X-1445406D02*
X-1447020D01*
G01X-1449346D02*
X-1450961D01*
G01X-1448804Y1060747D02*
X-1448825Y1060748D01*
G01X-1444863Y1060747D02*
X-1444885Y1060748D01*
G01X-1434046Y1059670D02*
X-1433968Y1059692D01*
X-1433887Y1059719D01*
X-1433808Y1059750D01*
X-1433731Y1059784D01*
X-1433658Y1059822D01*
X-1433586Y1059865D01*
G01X-1437986Y1059670D02*
X-1437908Y1059692D01*
X-1437827Y1059719D01*
X-1437748Y1059750D01*
X-1437671Y1059784D01*
X-1437598Y1059822D01*
X-1437526Y1059865D01*
G01X-1441926Y1059670D02*
X-1441848Y1059692D01*
X-1441767Y1059719D01*
X-1441688Y1059750D01*
X-1441611Y1059784D01*
X-1441538Y1059822D01*
X-1441466Y1059865D01*
G01X-1435722Y1060748D02*
X-1435833Y1060729D01*
X-1435934Y1060672D01*
X-1436018Y1060580D01*
G01X-1439662Y1060748D02*
X-1439772Y1060729D01*
X-1439874Y1060672D01*
X-1439958Y1060580D01*
G01X-1445866Y1059670D02*
X-1445788Y1059692D01*
X-1445707Y1059719D01*
X-1445628Y1059750D01*
X-1445552Y1059784D01*
X-1445478Y1059822D01*
X-1445406Y1059865D01*
G01X-1449806Y1059670D02*
X-1449728Y1059692D01*
X-1449646Y1059719D01*
X-1449568Y1059750D01*
X-1449491Y1059784D01*
X-1449418Y1059822D01*
X-1449346Y1059865D01*
G01X-1451286Y1052271D02*
G03X-1451732Y1052506I-865J-1101D01*
G01X-1452441D02*
G03X-1452900Y1052260I420J-1335D01*
G01X-1439466Y1052271D02*
G03X-1439912Y1052506I-865J-1101D01*
G01X-1440620D02*
G03X-1441080Y1052260I419J-1336D01*
G01X-1443406Y1052271D02*
G03X-1443852Y1052506I-865J-1101D01*
G01X-1444561D02*
G03X-1445020Y1052260I420J-1335D01*
G01X-1447346Y1052271D02*
G03X-1447792Y1052506I-865J-1101D01*
G01X-1448500D02*
G03X-1448961Y1052260I417J-1336D01*
G01X-1443080Y1056941D02*
G03X-1442635Y1056706I866J1100D01*
G01X-1441926D02*
G03X-1441466Y1056953I-421J1335D01*
G01X-1447020Y1056941D02*
G03X-1446575Y1056706I866J1100D01*
G01X-1445866D02*
G03X-1445406Y1056953I-421J1335D01*
G01X-1450961Y1056941D02*
G03X-1450515Y1056706I865J1101D01*
G01X-1449806D02*
G03X-1449346Y1056953I-421J1335D01*
G01X-1439141Y1056941D02*
G03X-1438695Y1056706I865J1101D01*
G01X-1437986D02*
G03X-1437526Y1056953I-421J1335D01*
G01X-1431586Y1052271D02*
G03X-1432032Y1052506I-865J-1101D01*
G01X-1432741D02*
G03X-1433200Y1052260I420J-1335D01*
G01X-1435526Y1052271D02*
G03X-1435972Y1052506I-865J-1101D01*
G01X-1436681D02*
G03X-1437141Y1052260I419J-1336D01*
G01X-1435200Y1056941D02*
G03X-1434755Y1056706I866J1100D01*
G01X-1434046D02*
G03X-1433586Y1056953I-421J1335D01*
G01X-1429093Y1058936D02*
G03I-1250J0D01*
G01X-1379368Y-837696D02*
Y-856633D01*
G01X-1287465Y-571983D02*
X-1386494D01*
G01X-1409833Y-497384D02*
G03I-6496J0D01*
G01X-1320937Y-441047D02*
X-1380990D01*
G01X-1409440Y-248171D02*
X-1422826D01*
G01X-1409440Y-234785D02*
X-1422826D01*
G01X-1409440Y-248171D02*
G03Y-234785I0J6693D01*
G01X-1391723Y-182620D02*
G03I-18701J0D01*
G01X-1403534D02*
G03I-6890J0D01*
G01X-1342511Y85096D02*
G03I-18700J0D01*
G01X-1354322D02*
G03I-6889J0D01*
G01X-1368454Y374685D02*
Y300276D01*
G01X-1364517Y374685D02*
X-734714D01*
G01X-1364517D02*
X-734714D01*
G01X-1368454Y378622D02*
Y804016D01*
G01Y378622D02*
Y804016D01*
G01Y378622D02*
G03X-1364517Y374685I3937J0D01*
G01X-1261289Y414055D02*
X-1403494D01*
G01X-1351502Y527758D02*
X-1396608Y482448D01*
G01D02*
X-1399757D01*
G01X-1346919Y551063D02*
G03Y513661I0J-18701D01*
G01X-1344163Y532362D02*
X-1403494D01*
G01X-1247706Y563661D02*
X-1403494D01*
G01X-1275039Y791998D02*
G03I-49314J0D01*
G01X-1346722Y806968D02*
G03Y769567I0J-18700D01*
G01X-1423855Y854655D02*
X-1424675Y853817D01*
G01X-1426726Y843346D02*
Y856749D01*
G01X-1424675Y853817D02*
Y843346D01*
G01D02*
X-1426726D01*
G01X-1417703Y854236D02*
X-1418113Y853398D01*
G01X-1420164Y843346D02*
Y853398D01*
G01X-1418113D02*
Y843346D01*
G01X-1413602D02*
Y853398D01*
G01X-1411552D02*
Y843346D01*
G01X-1417293Y854655D02*
X-1417703Y854236D01*
G01X-1416473Y855074D02*
X-1417293Y854655D01*
G01X-1422624Y855074D02*
X-1423855Y854655D01*
G01X-1412372Y855492D02*
X-1411552Y853398D01*
G01X-1420164D02*
X-1420574Y854236D01*
G01X-1413602Y853398D02*
X-1414012Y854236D01*
G01X-1420574D02*
X-1420984Y854655D01*
G01X-1414012Y854236D02*
X-1414422Y854655D01*
G01X-1420984D02*
X-1421804Y855074D01*
G01X-1414422Y854655D02*
X-1415243Y855074D01*
G01X-1411552Y843346D02*
X-1413602D01*
G01X-1418113D02*
X-1420164D01*
G01X-1366880Y884606D02*
Y820354D01*
G01X-1368454Y804016D02*
G03X-1372391Y807953I-3937J0D01*
G01X-1368454Y804016D02*
G03X-1372391Y807953I-3937J0D01*
G01X-1424675Y855492D02*
X-1423855Y856330D01*
G01X-1424675Y856749D02*
Y855492D01*
G01X-1426726Y856749D02*
X-1424675D01*
G01X-1418523Y855074D02*
X-1417293Y856330D01*
G01X-1423855D02*
X-1422624Y856749D01*
G01X-1417293Y856330D02*
X-1416063Y856749D01*
G01X-1419754Y856330D02*
X-1418523Y855074D01*
G01X-1413192Y856330D02*
X-1412372Y855492D01*
G01X-1420984Y856749D02*
X-1419754Y856330D01*
G01X-1414422Y856749D02*
X-1413192Y856330D01*
G01X-1415243Y855074D02*
X-1416473D01*
G01X-1421804D02*
X-1422624D01*
G01Y856749D02*
X-1420984D01*
G01X-1416063D02*
X-1414422D01*
G01X-1383691Y904646D02*
Y1138465D01*
G01Y904646D02*
X-1257706D01*
G01X-1428443Y1062856D02*
Y1046356D01*
G01X-1427893Y1065106D02*
Y1044106D01*
G01X-1424954Y1062856D02*
Y1046356D01*
G01X-1424654Y1064456D02*
Y1044756D01*
G01X-1424443Y1052106D02*
Y1048602D01*
G01X-1424393Y1048006D02*
Y1044106D01*
G01X-1427165Y1050956D02*
X-1427575Y1052082D01*
G01X-1424443Y1048602D02*
X-1424431Y1048604D01*
X-1424407Y1048605D01*
X-1424393Y1048606D01*
X-1424367D01*
G01X-1424407D02*
X-1424261Y1048616D01*
X-1424132Y1048627D01*
X-1424030Y1048637D01*
X-1423966Y1048648D01*
X-1423943Y1048658D01*
G01X-1424367Y1048606D02*
X-1423875Y1048624D01*
G01X-1424393Y1044106D02*
X-1427893D01*
G01X-1424367Y1048606D02*
X-1424407D01*
G01X-1424443Y1048602D02*
X-1424437Y1048604D01*
X-1424426Y1048605D01*
X-1424419Y1048606D01*
X-1424407D01*
G01X-1424443Y1048602D02*
G03X-1424393Y1048006I49J-296D01*
G01X-1423943Y1049133D02*
X-1423803Y1049300D01*
X-1423705Y1049483D01*
X-1423650Y1049672D01*
X-1423633Y1049857D01*
G01X-1422461Y1049535D02*
X-1423943Y1048535D01*
G01Y1060677D02*
Y1048535D01*
G01X-1423633Y1049857D02*
Y1052356D01*
G01X-1423393Y1048658D02*
Y1060555D01*
G01X-1421993Y1049286D02*
Y1044756D01*
G01X-1423875Y1048624D02*
X-1423674Y1048632D01*
X-1423522Y1048641D01*
X-1423426Y1048649D01*
X-1423393Y1048658D01*
G01X-1423943D02*
X-1423393D01*
G01Y1048859D02*
X-1423943D01*
G01X-1423633Y1049857D02*
X-1423393D01*
G01X-1421993Y1049286D02*
G03X-1422461Y1049535I-300J0D01*
G01X-1424893Y1057106D02*
Y1052106D01*
G01X-1424443Y1060611D02*
Y1057106D01*
G01X-1424393Y1065106D02*
Y1061206D01*
G01X-1423943Y1060555D02*
X-1423966Y1060565D01*
X-1424031Y1060576D01*
X-1424132Y1060586D01*
X-1424261Y1060596D01*
X-1424407Y1060606D01*
G01X-1423393Y1060555D02*
X-1423426Y1060563D01*
X-1423522Y1060572D01*
X-1423674Y1060581D01*
X-1423875Y1060589D01*
X-1424367Y1060606D01*
G01X-1424893Y1052106D02*
X-1423393D01*
G01Y1057106D02*
X-1424893D01*
G01X-1424407Y1060606D02*
X-1424367D01*
G01X-1424393Y1065106D02*
X-1427893D01*
G01X-1424367Y1060606D02*
X-1424379D01*
X-1424391Y1060607D01*
X-1424404D01*
X-1424418Y1060608D01*
X-1424430Y1060609D01*
X-1424443Y1060611D01*
G01X-1424407Y1060606D02*
X-1424413D01*
X-1424419Y1060607D01*
X-1424425D01*
X-1424437Y1060609D01*
X-1424443Y1060611D01*
G01X-1428443Y1051956D02*
G03X-1427796Y1052691I400J300D01*
G01X-1424393Y1061206D02*
G03X-1424443Y1060611I1J-300D01*
G01X-1423796Y1056856D02*
Y1052356D01*
G01X-1423633Y1056856D02*
Y1059355D01*
G01X-1423575Y1056856D02*
Y1052356D01*
G01X-1423320Y1056856D02*
Y1052356D01*
G01X-1423151Y1056856D02*
Y1052356D01*
G01X-1422943Y1056856D02*
Y1052356D01*
G01X-1421993Y1064456D02*
Y1059926D01*
G01X-1423943Y1060079D02*
X-1423803Y1059912D01*
X-1423705Y1059728D01*
X-1423650Y1059540D01*
X-1423633Y1059355D01*
G01X-1423943Y1060677D02*
X-1422461Y1059678D01*
G01X-1423943Y1052356D02*
X-1423393D01*
G01D02*
X-1422943D01*
G01X-1423393Y1056856D02*
X-1423943D01*
G01X-1423393D02*
X-1422943D01*
G01X-1423393Y1059355D02*
X-1423633D01*
G01X-1423943Y1060354D02*
X-1423393D01*
G01Y1060555D02*
X-1423943D01*
G01X-1422461Y1059678D02*
G03X-1421993Y1059926I168J248D01*
G01X-1379368Y1340060D02*
Y1321123D01*
G01X-1297880Y-694431D02*
X-1301030D01*
G01X-1301172Y-615691D02*
G03I-18701J0D01*
G01X-1312983D02*
G03I-6890J0D01*
G01X-1317117Y68419D02*
Y-466085D01*
G01D02*
G03X-1313180I1968J0D01*
G01D02*
X-1161211D01*
G01X-1240602Y-487857D02*
X-1317788Y-441047D01*
G01D02*
X-1320937D01*
G01X-1317117Y68419D02*
G03X-1317533Y70180I-3937J0D01*
G01X-1335714Y106542D02*
X-1317533Y70180D01*
G01X-1335714Y106542D02*
G03X-1339235Y108719I-3522J-1760D01*
G01X-1304027Y375009D02*
X-1304303Y375000D01*
G01X-1304084Y376304D02*
X-1304663Y376283D01*
G01X-1304672Y376555D02*
X-1304084Y376576D01*
G01X-1294714Y372520D02*
X-1317234D01*
G01X-1304330Y372913D02*
X-1307618D01*
G01X-1316053Y373110D02*
X-1295895D01*
G01X-1300094Y373425D02*
X-1304610D01*
G01X-1307428Y373504D02*
X-1304520D01*
G01X-1316053Y374488D02*
X-1317234D01*
G01X-1304754Y374606D02*
X-1302509D01*
G01X-1300305Y376835D02*
X-1305974D01*
G01X-1316053Y377488D02*
X-1317234D01*
G01X-1312234Y378031D02*
X-1308966D01*
G01X-1312706D02*
X-1312313D01*
G01X-1309271Y373110D02*
X-1308787Y372773D01*
G01X-1317958Y378531D02*
X-1317635Y378305D01*
G01X-1311226Y379338D02*
X-1310289Y378401D01*
G01X-1311170Y379393D02*
X-1310234Y378457D01*
G01X-1305974Y375787D02*
X-1304610Y373425D01*
G01X-1304330Y372913D02*
X-1304398Y373102D01*
X-1304461Y373298D01*
X-1304520Y373504D01*
G01X-1304659Y376169D02*
X-1304303Y375000D01*
G01X-1318151Y379628D02*
X-1317958Y378531D01*
G01X-1304659Y376169D02*
X-1304872Y382272D01*
G01X-1331958Y489646D02*
Y374685D01*
G01X-1317234Y372520D02*
Y471929D01*
G01X-1316053Y373110D02*
Y471929D01*
G01X-1315462Y426654D02*
Y372520D01*
G01X-1313100Y379606D02*
Y378425D01*
G01X-1312313Y372520D02*
Y378920D01*
G01X-1312234Y372520D02*
Y378920D01*
G01X-1309360Y378819D02*
Y386693D01*
G01X-1309281Y378819D02*
Y386693D01*
G01X-1309271Y372520D02*
Y373110D01*
G01X-1308572Y378425D02*
Y379606D01*
G01X-1305974Y414370D02*
Y375787D01*
G01X-1305383Y382677D02*
Y374765D01*
G01X-1304754Y374016D02*
Y374606D01*
G01X-1307428Y373504D02*
X-1307488Y373298D01*
X-1307551Y373102D01*
X-1307618Y372913D01*
G01X-1314396Y382932D02*
X-1317635Y378305D01*
G01X-1316053Y373110D02*
X-1316643Y372520D01*
G01X-1313100Y378425D02*
G03X-1312706Y378031I394J0D01*
G01X-1307428Y373504D02*
G03X-1309271Y373110I-711J-1180D01*
G01X-1307618Y372913D02*
G03X-1308787Y372773I-522J-589D01*
G01X-1310289Y378401D02*
G03X-1309281Y378819I417J418D01*
G01X-1309271Y372520D02*
G03X-1308787Y372773I0J590D01*
G01X-1310234Y378457D02*
G03X-1309360Y378819I362J362D01*
G01X-1308966Y378031D02*
G03X-1308572Y378425I0J394D01*
G01X-1302677Y373110D02*
G03X-1304520Y373504I-1132J-786D01*
G01X-1303162Y372773D02*
G03X-1304330Y372913I-646J-449D01*
G01X-1304754Y374016D02*
G03X-1304163Y373425I591J0D01*
G01X-1308966Y380000D02*
X-1309281D01*
G01X-1309360D02*
X-1312706D01*
G01X-1304872Y382677D02*
X-1305383D01*
G01X-1302037Y383465D02*
X-1304872D01*
G01X-1302037Y384449D02*
X-1304872D01*
G01X-1312706Y385512D02*
X-1309360D01*
G01X-1309281D02*
X-1308966D01*
G01X-1304005Y385630D02*
X-1304793D01*
G01X-1302824Y385855D02*
X-1304872D01*
G01X-1309126Y392066D02*
X-1309320Y392094D01*
G01X-1308932Y393306D02*
X-1309129Y393359D01*
G01X-1307948D02*
X-1307751Y393306D01*
G01X-1318097Y379705D02*
X-1317129Y379028D01*
G01X-1316315Y380191D02*
X-1316250Y380146D01*
G01X-1316605Y381836D02*
X-1316541Y381791D01*
G01X-1315363Y383610D02*
X-1314331Y382887D01*
G01X-1308966Y387480D02*
X-1312234D01*
G01X-1312313D02*
X-1312706D01*
G01X-1316053Y387528D02*
X-1317234D01*
G01X-1309257Y392542D02*
X-1301510D01*
G01X-1308930Y393320D02*
X-1301838D01*
G01X-1309129Y393554D02*
X-1301639D01*
G01X-1305974Y395499D02*
X-1306171Y395504D01*
G01X-1307944Y392089D02*
X-1308139Y392094D01*
G01X-1316003Y387422D02*
X-1315981Y387402D01*
X-1315966Y387379D01*
X-1315957Y387354D01*
G01X-1316600Y385997D02*
X-1315473Y384870D01*
G01X-1316253Y385705D02*
X-1315445Y384898D01*
G01X-1316141Y385650D02*
X-1315418Y384926D01*
G01X-1315765Y386832D02*
X-1314638Y385705D01*
G01X-1315737Y386860D02*
X-1314610Y385733D01*
G01X-1315709Y386888D02*
X-1314582Y385761D01*
G01X-1305383Y382677D02*
X-1305974Y383268D01*
G01X-1305983Y387928D02*
X-1305974Y387918D01*
G01X-1305980Y387925D02*
X-1305985Y387931D01*
G01X-1305983Y387928D02*
X-1305994Y387940D01*
G01X-1305985Y387931D02*
X-1305994Y387940D01*
G01Y387941D02*
X-1306004Y387953D01*
X-1306013Y387963D01*
G01X-1305999Y387946D02*
X-1306004Y387952D01*
G01X-1316003Y387422D02*
X-1316030Y387453D01*
X-1316047Y387489D01*
X-1316053Y387528D01*
G01X-1306007Y387956D02*
X-1306002Y387950D01*
G01X-1307587Y389838D02*
X-1306013Y387963D01*
G01X-1306984Y390344D02*
X-1305974Y389141D01*
G01X-1307295Y393166D02*
X-1306789Y392563D01*
G01X-1315755Y386937D02*
X-1315855Y387083D01*
G01X-1315785Y386912D02*
X-1315901Y387086D01*
X-1315973Y387268D01*
G01X-1315957Y387107D02*
X-1315815Y386886D01*
G01X-1316012Y387565D02*
X-1316043Y387622D01*
X-1316053Y387685D01*
G01X-1316012Y387565D02*
X-1316043Y387622D01*
G01X-1315854Y387081D02*
X-1315923Y387231D01*
G01X-1315922Y387229D02*
X-1315957Y387353D01*
G01X-1315972Y387460D02*
X-1315984Y387515D01*
X-1316012Y387565D01*
G01X-1315972Y387460D02*
X-1315984Y387515D01*
G01X-1316053Y387528D02*
X-1316031Y387333D01*
X-1315957Y387107D01*
G01X-1316003Y387422D02*
X-1315973Y387267D01*
G01X-1315957Y387354D02*
X-1315969Y387431D01*
X-1315971Y387452D01*
G01X-1316009Y387500D02*
X-1316003Y387422D01*
G01X-1316012Y387549D02*
X-1316009Y387500D01*
G01X-1316012Y387549D02*
Y387565D01*
G01X-1313100Y387087D02*
Y385905D01*
G01X-1312313Y386592D02*
Y408448D01*
G01X-1312234Y386592D02*
Y408448D01*
G01X-1309129Y393554D02*
Y393359D01*
G01X-1308572Y385905D02*
Y387087D01*
G01X-1307948Y393359D02*
Y393554D01*
G01X-1304872Y385855D02*
Y382677D01*
G01X-1304793Y385855D02*
Y385630D01*
G01X-1305976Y403569D02*
X-1306171Y395504D01*
G01X-1309129Y393554D02*
X-1309257Y392542D01*
G01X-1308076D02*
X-1307948Y393554D01*
G01X-1309305Y403392D02*
X-1310880Y392316D01*
G01X-1308124Y403392D02*
X-1309699Y392316D01*
G01X-1309257Y392542D02*
X-1309320Y392094D01*
G01X-1309058Y392542D02*
X-1309126Y392066D01*
G01X-1308076Y392542D02*
X-1308139Y392094D01*
G01X-1308243Y399659D02*
X-1309129Y393554D01*
G01Y393359D02*
X-1308243Y399464D01*
G01X-1308046Y399412D02*
X-1308932Y393306D01*
G01X-1307948Y393554D02*
X-1307062Y399659D01*
G01Y399464D02*
X-1307948Y393359D01*
G01X-1307751Y393306D02*
X-1306863Y399426D01*
G01X-1309257Y392542D02*
X-1309129Y393359D01*
G01X-1307948D02*
X-1307992Y393077D01*
X-1308033Y392804D01*
X-1308069Y392541D01*
G01X-1309058Y392542D02*
X-1308930Y393320D01*
G01X-1307748D02*
X-1307877Y392542D01*
G01X-1307969Y392095D02*
X-1307917Y392318D01*
X-1307877Y392541D01*
G01X-1316617Y379692D02*
X-1316644Y379652D01*
G01D02*
X-1316617Y379692D01*
G01D02*
X-1316538Y379806D01*
X-1316420Y379973D01*
G01X-1315363Y383610D02*
X-1318151Y379628D01*
G01X-1315331Y383587D02*
X-1316889Y381362D01*
G01X-1315298Y383565D02*
X-1316789Y381436D01*
G01X-1314331Y382887D02*
X-1316544Y379726D01*
G01X-1314363Y382910D02*
X-1316539Y379804D01*
G01X-1316744Y379578D02*
X-1316700Y379623D01*
G01X-1316588Y379681D02*
X-1316544Y379726D01*
G01X-1315709Y386888D02*
X-1316600Y385997D01*
G01X-1315835Y385343D02*
X-1315891Y385288D01*
G01X-1314582Y385761D02*
X-1315473Y384870D01*
G01X-1310289Y387111D02*
X-1311226Y386174D01*
G01X-1310234Y387055D02*
X-1311170Y386118D01*
G01X-1315755Y386937D02*
X-1315815Y386886D01*
G01X-1306984Y390344D02*
X-1307587Y389838D01*
G01X-1305974Y387995D02*
X-1306013Y387963D01*
G01X-1316700Y379623D02*
X-1316588Y379681D01*
X-1316544Y379726D01*
G01X-1308647Y391466D02*
X-1308483Y391523D01*
X-1308331Y391608D01*
X-1308199Y391715D01*
X-1308093Y391836D01*
X-1308016Y391965D01*
X-1307944Y392089D01*
G01X-1312706Y380000D02*
G03X-1313100Y379606I0J-394D01*
G01X-1316644Y379652D02*
G03X-1316744Y379578I61J-187D01*
G01X-1316644Y379652D02*
G03X-1316544Y379726I-61J187D01*
G01X-1316889Y381362D02*
G03X-1316789Y381436I-61J187D01*
G01X-1316889Y381362D02*
G03X-1316989Y381288I61J-187D01*
G01X-1314331Y382887D02*
G03X-1314582Y385761I-1838J1287D01*
G01X-1314363Y382910D02*
G03X-1314610Y385733I-1806J1264D01*
G01X-1314396Y382932D02*
G03X-1314638Y385705I-1773J1242D01*
G01X-1315298Y383565D02*
G03X-1315418Y384926I-871J609D01*
G01X-1315331Y383587D02*
G03X-1315445Y384898I-838J588D01*
G01X-1315363Y383610D02*
G03X-1315473Y384870I-806J564D01*
G01X-1316364Y385761D02*
G03X-1316253Y385705I140J139D01*
G01X-1316141Y385650D02*
G03X-1316253Y385705I-138J-140D01*
G01X-1317234Y387528D02*
G03X-1316600Y385997I2165J0D01*
G01X-1316053Y387528D02*
G03X-1315765Y386832I984J0D01*
G01X-1315785Y386912D02*
G03X-1315737Y386860I718J614D01*
G01X-1315972Y387460D02*
G03X-1315709Y386888I903J69D01*
G01X-1316053Y387685D02*
G03X-1316012Y387565I197J0D01*
G01X-1315972Y387460D02*
G03X-1316012Y387565I-196J-15D01*
G01X-1313100Y385905D02*
G03X-1312706Y385512I394J1D01*
G01Y387480D02*
G03X-1313100Y387087I0J-394D01*
G01X-1311170Y379393D02*
G03X-1312313Y378920I-474J-473D01*
G01X-1311226Y379338D02*
G03X-1312234Y378920I-417J-418D01*
G01X-1308572Y379606D02*
G03X-1308966Y380000I-394J0D01*
G01X-1312313Y386592D02*
G03X-1311170Y386118I669J-1D01*
G01X-1312234Y386592D02*
G03X-1311226Y386174I591J0D01*
G01X-1309281Y386693D02*
G03X-1310289Y387111I-591J0D01*
G01X-1309360Y386693D02*
G03X-1310234Y387055I-512J0D01*
G01X-1308966Y385512D02*
G03X-1308572Y385905I0J394D01*
G01Y387087D02*
G03X-1308966Y387480I-394J-1D01*
G01X-1306789Y392563D02*
G03X-1305974Y393504I-2531J3016D01*
G01X-1307295Y393166D02*
G03X-1306171Y395504I-2025J2413D01*
G01X-1310797Y392900D02*
G03X-1309126Y392066I697J-695D01*
G01X-1310880Y392316D02*
G03X-1309320Y392094I780J-111D01*
G01X-1309699Y392316D02*
G03X-1308139Y392094I780J-111D01*
G01X-1303705Y383848D02*
G03X-1304872Y382272I407J-1521D01*
G01X-1307295Y393166D02*
G03X-1307587Y389838I1518J-1810D01*
G01X-1306789Y392563D02*
G03X-1306984Y390344I1012J-1207D01*
G01X-1303973Y375129D02*
X-1304085Y375125D01*
G01X-1300305Y376835D02*
X-1300167Y376824D01*
G01X-1299585Y376533D02*
X-1299438Y376384D01*
X-1299296Y376202D01*
G01X-1299040Y375731D02*
X-1299163Y375985D01*
X-1299296Y376202D01*
X-1299438Y376384D01*
X-1299585Y376533D01*
X-1299734Y376650D01*
X-1299882Y376735D01*
X-1300026Y376792D01*
X-1300167Y376824D01*
X-1300305Y376835D01*
G01X-1299040Y375732D02*
X-1298931Y375440D01*
G01X-1303844Y375410D02*
X-1304085Y382300D01*
G01X-1304084Y377432D02*
Y374606D01*
G01X-1302677Y373110D02*
Y372520D01*
G01X-1302509Y379938D02*
Y374606D01*
G01X-1300305Y414370D02*
Y376835D01*
G01X-1298730Y413583D02*
Y375787D01*
G01X-1303655Y378711D02*
X-1303972Y377978D01*
G01X-1303844Y375410D02*
X-1304027Y375009D01*
G01X-1298730Y375787D02*
X-1300094Y373425D01*
G01X-1303162Y372773D02*
X-1302677Y373110D01*
G01X-1303162Y372773D02*
G03X-1302677Y372520I485J338D01*
G01X-1303330Y379173D02*
G03X-1303655Y378711I941J-1007D01*
G01X-1303972Y377978D02*
G03X-1304084Y377432I1266J-544D01*
G01X-1302120Y391466D02*
X-1302284Y391523D01*
X-1302436Y391608D01*
X-1302568Y391715D01*
X-1302674Y391836D01*
X-1302752Y391965D01*
X-1302824Y392089D01*
G01X-1301275Y383685D02*
X-1303502Y383088D01*
G01X-1301479Y384445D02*
X-1303705Y383848D01*
G01X-1301642Y392066D02*
X-1301446Y392094D01*
G01X-1302824Y392089D02*
X-1302628Y392094D01*
G01X-1300108Y390748D02*
X-1298730D01*
G01X-1301835Y393306D02*
X-1301639Y393359D01*
G01X-1302820D02*
X-1303016Y393306D01*
G01X-1302798Y392095D02*
X-1302850Y392318D01*
X-1302890Y392541D01*
G01X-1303019Y393320D02*
X-1302891Y392542D01*
G01X-1301709D02*
X-1301838Y393320D01*
G01X-1302820Y393359D02*
X-1302775Y393077D01*
X-1302734Y392804D01*
X-1302698Y392541D01*
G01X-1301510Y392542D02*
X-1301639Y393359D01*
G01X-1303016Y393306D02*
X-1303904Y399426D01*
G01X-1303705Y399464D02*
X-1302820Y393359D01*
G01Y393554D02*
X-1303705Y399659D01*
G01X-1302721Y399412D02*
X-1301835Y393306D01*
G01X-1301639Y393359D02*
X-1302524Y399464D01*
G01Y399659D02*
X-1301639Y393554D01*
G01X-1302691Y392542D02*
X-1302628Y392094D01*
G01X-1301709Y392542D02*
X-1301642Y392066D01*
G01X-1301510Y392542D02*
X-1301446Y392094D01*
G01X-1302643Y403392D02*
X-1301068Y392316D01*
G01X-1301462Y403392D02*
X-1299887Y392316D01*
G01X-1302691Y392542D02*
X-1302820Y393554D01*
G01X-1301639D02*
X-1301510Y392542D01*
G01X-1304005Y385855D02*
Y385630D01*
G01X-1302824Y414370D02*
Y385855D01*
G01X-1302820Y393359D02*
Y393554D01*
G01X-1302037Y383465D02*
Y414370D01*
G01X-1301639Y393554D02*
Y393359D01*
G01X-1300895Y385206D02*
Y414370D01*
G01X-1300108Y382520D02*
Y414370D01*
G01X-1299517Y390748D02*
X-1300108Y390157D01*
G01X-1300358Y381944D02*
X-1303330Y379173D01*
G01X-1303502Y383088D02*
G03X-1304085Y382300I204J-761D01*
G01X-1301275Y383685D02*
G03X-1300108Y385206I-408J1521D01*
G01X-1300358Y381944D02*
G03X-1300108Y382520I-537J576D01*
G01X-1301479Y384445D02*
G03X-1300895Y385206I-204J761D01*
G01X-1301642Y392066D02*
G03X-1299970Y392900I975J139D01*
G01X-1302628Y392094D02*
G03X-1301068Y392316I780J111D01*
G01X-1301446Y392094D02*
G03X-1299887Y392316I780J110D01*
G01X-1306924Y399437D02*
X-1306855Y399424D01*
G01X-1308047Y399412D02*
X-1308111Y399424D01*
X-1308176Y399442D01*
X-1308243Y399464D01*
G01X-1307062D02*
X-1306924Y399437D01*
G01X-1308051Y399427D02*
X-1308241Y399488D01*
G01X-1306771Y403418D02*
X-1306896Y403406D01*
X-1307022Y403372D01*
X-1307146Y403313D01*
X-1307270Y403227D01*
X-1307390Y403111D01*
X-1307502Y402960D01*
X-1307603Y402775D01*
X-1307683Y402557D01*
X-1307736Y402311D01*
G01X-1305590Y403663D02*
X-1305727Y403655D01*
X-1305865Y403633D01*
X-1305997Y403594D01*
X-1306120Y403542D01*
X-1306233Y403476D01*
X-1306333Y403398D01*
G01X-1308045Y399425D02*
X-1302722D01*
G01X-1308243Y399659D02*
X-1302524D01*
G01X-1316053Y401138D02*
X-1317234D01*
G01X-1307926Y401276D02*
X-1302841D01*
G01X-1316053Y401382D02*
X-1317234D01*
G01X-1307730Y402013D02*
X-1303037D01*
G01X-1307736Y402311D02*
X-1303031D01*
G01X-1317234Y402441D02*
X-1316053D01*
G01X-1313986Y403150D02*
X-1309714D01*
G01X-1306771Y403418D02*
X-1303996D01*
G01X-1306771Y403663D02*
X-1303996D01*
G01X-1308533Y404331D02*
X-1315167D01*
G01X-1306771Y405591D02*
X-1303996D01*
G01X-1312234Y407559D02*
X-1308966D01*
G01X-1312706D02*
X-1312313D01*
G01X-1305974Y402781D02*
X-1305995Y402782D01*
G01X-1305177Y403663D02*
X-1305040Y403655D01*
X-1304902Y403633D01*
X-1304770Y403594D01*
X-1304647Y403542D01*
X-1304534Y403476D01*
X-1304434Y403398D01*
G01X-1313986Y403150D02*
X-1315954Y405118D01*
G01X-1311226Y408865D02*
X-1310289Y407929D01*
G01X-1311170Y408921D02*
X-1310234Y407985D01*
G01X-1308049Y399419D02*
X-1308046Y399416D01*
Y399421D01*
G01X-1308051Y399427D02*
X-1308046Y399421D01*
G01X-1304434Y403398D02*
X-1304328Y403220D01*
X-1304249Y403047D01*
X-1304202Y402885D01*
G01X-1304213Y402311D02*
X-1304266Y402557D01*
X-1304346Y402775D01*
X-1304446Y402961D01*
X-1304559Y403111D01*
X-1304679Y403227D01*
X-1304802Y403313D01*
X-1304927Y403372D01*
X-1305052Y403406D01*
X-1305177Y403418D01*
G01X-1304434Y403398D02*
X-1304221Y402013D01*
G01X-1315954Y426181D02*
Y405118D01*
G01X-1313100Y409134D02*
Y407953D01*
G01X-1309360Y408346D02*
Y416220D01*
G01X-1309281Y408346D02*
Y416220D01*
G01X-1308572Y407953D02*
Y409134D01*
G01X-1308243Y399464D02*
Y399659D01*
G01X-1307926Y401276D02*
Y401890D01*
G01X-1307746Y409055D02*
Y405118D01*
G01Y402854D02*
Y402265D01*
G01X-1307062Y399659D02*
Y399464D01*
G01X-1306771Y403418D02*
Y403663D01*
G01X-1306745Y401890D02*
Y401276D01*
G01X-1306565Y402265D02*
Y402885D01*
G01X-1305590Y403663D02*
Y403418D01*
G01X-1305177Y403663D02*
Y403418D01*
G01X-1306801Y399970D02*
X-1306855Y399425D01*
G01X-1308047Y399412D02*
X-1308045Y399425D01*
G01X-1308049Y399419D02*
X-1307968Y400080D01*
X-1307886Y400789D01*
G01X-1307804Y401457D02*
X-1307886Y400789D01*
X-1307968Y400081D01*
X-1308051Y399427D01*
G01X-1308243Y399464D02*
X-1308076Y400811D01*
X-1307999Y401392D01*
X-1307926Y401890D01*
G01X-1307804Y401456D02*
X-1307730Y402013D01*
G01X-1306546D02*
X-1306611Y401555D01*
X-1306673Y401052D01*
X-1306801Y399970D01*
G01X-1306745Y401890D02*
X-1306825Y401342D01*
X-1306904Y400736D01*
X-1307062Y399464D01*
G01X-1306333Y403398D02*
X-1306546Y402013D01*
G01X-1306565Y402885D02*
X-1306745Y401890D01*
G01X-1307746Y402265D02*
X-1307926Y401276D01*
G01X-1306745D02*
X-1306565Y402265D01*
G01X-1307062Y399659D02*
X-1306956Y400229D01*
X-1306851Y400783D01*
X-1306745Y401276D01*
G01X-1306565Y402265D02*
X-1306564Y402271D01*
X-1306561Y402287D01*
X-1306557Y402302D01*
X-1306555Y402311D01*
G01X-1307926Y401890D02*
X-1307746Y402854D01*
G01X-1307437Y403461D02*
X-1307529Y403002D01*
X-1307622Y402554D01*
X-1307721Y402112D01*
G01X-1307518Y403063D02*
X-1307595Y402700D01*
X-1307677Y402352D01*
X-1307764Y402013D01*
G01X-1307926Y401276D02*
X-1308032Y400783D01*
X-1308137Y400229D01*
X-1308243Y399659D01*
G01X-1306555Y402311D02*
X-1306502Y402557D01*
X-1306422Y402775D01*
X-1306321Y402961D01*
X-1306208Y403111D01*
X-1306089Y403227D01*
X-1305965Y403313D01*
X-1305840Y403372D01*
X-1305715Y403406D01*
X-1305590Y403418D01*
G01X-1307736Y402311D02*
X-1307737Y402305D01*
X-1307741Y402290D01*
X-1307744Y402274D01*
X-1307746Y402265D01*
G01Y402854D02*
X-1307706Y402993D01*
X-1307636Y403150D01*
X-1307548Y403300D01*
X-1307437Y403461D01*
G01X-1306333Y403398D02*
X-1306440Y403220D01*
X-1306518Y403047D01*
X-1306565Y402885D01*
G01X-1307746Y405118D02*
X-1309714Y403150D01*
G01X-1307437Y403461D02*
X-1307344Y403520D01*
X-1307242Y403570D01*
X-1307130Y403610D01*
X-1307015Y403639D01*
X-1306894Y403657D01*
X-1306771Y403663D01*
G01X-1306546Y402013D02*
X-1306741Y401909D01*
G01X-1313100Y407953D02*
G03X-1312706Y407559I394J0D01*
G01X-1311170Y408921D02*
G03X-1312313Y408448I-474J-473D01*
G01X-1310289Y407929D02*
G03X-1309281Y408346I417J418D01*
G01X-1311226Y408865D02*
G03X-1312234Y408448I-418J-417D01*
G01X-1310234Y407985D02*
G03X-1309360Y408346I362J362D01*
G01X-1308966Y407559D02*
G03X-1308572Y407953I0J394D01*
G01X-1305590Y405591D02*
G03X-1308124Y403392I0J-2559D01*
G01X-1302643D02*
G03X-1305177Y405591I-2534J-360D01*
G01X-1306771D02*
G03X-1309305Y403392I0J-2559D01*
G01X-1315954Y409055D02*
X-1295994D01*
G01X-1308966Y409528D02*
X-1309281D01*
G01X-1309360D02*
X-1312706D01*
G01X-1305974Y411417D02*
X-1306171D01*
G01X-1305974Y413298D02*
X-1306171D01*
G01X-1298730Y413583D02*
X-1305974D01*
G01X-1297175Y414370D02*
X-1314773D01*
G01X-1312706Y415039D02*
X-1309360D01*
G01X-1309281D02*
X-1308966D01*
G01X-1295994Y415551D02*
X-1315954D01*
G01X-1316053D02*
X-1317234D01*
G01X-1316053Y416339D02*
X-1317234D01*
G01X-1308966Y417008D02*
X-1312234D01*
G01X-1312313D02*
X-1312706D01*
G01X-1317234Y418583D02*
X-1312313D01*
G01X-1309911D02*
X-1294714D01*
G01X-1295994Y418701D02*
X-1312332D01*
G01X-1312726D02*
X-1315954D01*
G01X-1316053Y418976D02*
X-1316250D01*
G01X-1317234D02*
X-1317431D01*
G01X-1316053Y420059D02*
X-1317234D01*
G01X-1316053Y420130D02*
X-1317234D01*
G01Y420190D02*
X-1316053D01*
G01X-1312903Y420472D02*
X-1315364D01*
G01X-1316053Y420487D02*
X-1317234D01*
G01X-1315856Y420571D02*
X-1313002D01*
G01X-1317234Y420874D02*
X-1316053D01*
G01Y420945D02*
X-1317234D01*
G01X-1311250D02*
X-1305541D01*
G01X-1316053Y421168D02*
X-1317234D01*
G01X-1306180Y421339D02*
X-1310611D01*
G01X-1314773Y421555D02*
X-1315856D01*
G01X-1304852Y421654D02*
X-1311939D01*
G01X-1316053Y421820D02*
X-1317234D01*
G01X-1309517Y421850D02*
X-1302431D01*
G01X-1315954Y422441D02*
X-1316742D01*
G01X-1316053Y422638D02*
X-1317234D01*
G01X-1302431Y422835D02*
X-1309517D01*
G01X-1313002Y422933D02*
X-1314380D01*
G01X-1314084Y423031D02*
X-1312903D01*
G01X-1316053Y423307D02*
X-1317234D01*
G01X-1316742Y424106D02*
X-1314773D01*
G01X-1314380D02*
X-1314281D01*
G01X-1316053Y425669D02*
X-1317234D01*
G01X-1315954Y426181D02*
X-1295994D01*
G01X-1304990Y426279D02*
X-1314380D01*
G01X-1309911Y426654D02*
X-1317234D01*
G01X-1315462Y429180D02*
X-1315327Y429174D01*
X-1315193Y429154D01*
X-1315062Y429121D01*
X-1314937Y429076D01*
X-1314819Y429018D01*
X-1314707Y428948D01*
G01X-1302923Y430389D02*
X-1308966Y430807D01*
G01X-1303021Y430610D02*
X-1309025Y431026D01*
G01X-1316250Y428554D02*
X-1316441Y428570D01*
X-1316625Y428617D01*
X-1316794Y428694D01*
X-1316946Y428799D01*
X-1317068Y428925D01*
X-1317159Y429068D01*
X-1317215Y429224D01*
X-1317234Y429389D01*
G01X-1302923Y438196D02*
X-1308966Y440650D01*
G01X-1314707Y428322D02*
X-1314816Y428391D01*
X-1314934Y428448D01*
X-1315059Y428494D01*
X-1315189Y428527D01*
X-1315323Y428547D01*
X-1315462Y428554D01*
G01X-1305974Y413583D02*
X-1307155Y414370D01*
G01X-1315954Y415551D02*
X-1314773Y414370D01*
G01X-1316551Y436090D02*
X-1316153Y436159D01*
X-1315970Y436226D01*
X-1315807Y436322D01*
X-1315670Y436444D01*
X-1315564Y436587D01*
X-1315494Y436745D01*
X-1315464Y436912D01*
X-1315473Y437080D01*
X-1315522Y437244D01*
X-1315609Y437395D01*
X-1315731Y437529D01*
X-1315884Y437641D01*
X-1316058Y437723D01*
X-1316248Y437774D01*
X-1316446Y437791D01*
G01X-1308730Y429890D02*
X-1308959Y429871D01*
X-1309180Y429814D01*
X-1309384Y429722D01*
X-1309565Y429596D01*
X-1309711Y429445D01*
X-1309820Y429273D01*
X-1309888Y429086D01*
X-1309911Y428888D01*
G01X-1316840Y438417D02*
X-1317185Y438399D01*
X-1317515Y438346D01*
X-1317821Y438260D01*
X-1318093Y438142D01*
X-1318313Y438000D01*
X-1318476Y437839D01*
X-1318577Y437664D01*
X-1318612Y437478D01*
G01X-1317234Y427157D02*
X-1316053D01*
G01Y428031D02*
X-1317234D01*
G01X-1316053Y428103D02*
X-1317234D01*
G01X-1314707Y428322D02*
X-1309911D01*
G01X-1315462Y428554D02*
X-1316250D01*
G01X-1316053Y428787D02*
X-1317234D01*
G01Y428846D02*
X-1316053D01*
G01Y428917D02*
X-1317234D01*
G01X-1309911Y428948D02*
X-1314707D01*
G01X-1315462Y429180D02*
X-1316250D01*
G01X-1314773Y429331D02*
X-1297175D01*
G01X-1317234Y429513D02*
X-1316053D01*
G01X-1316742Y429530D02*
X-1317234D01*
G01X-1303218Y429890D02*
X-1308730D01*
G01X-1309124Y429902D02*
X-1309911D01*
G01X-1317234Y430064D02*
X-1316742D01*
G01X-1303218Y430516D02*
X-1308730D01*
G01X-1308966Y430807D02*
X-1309950D01*
G01X-1309124Y430905D02*
X-1309911D01*
G01Y430924D02*
X-1309124D01*
G01X-1316446Y431102D02*
X-1316840D01*
G01X-1309911Y431201D02*
X-1309124D01*
G01X-1309911Y432185D02*
X-1309124D01*
G01Y432462D02*
X-1309911D01*
G01X-1309124Y432480D02*
X-1309911D01*
G01X-1308966Y432579D02*
X-1309950D01*
G01X-1309911Y434449D02*
X-1309124D01*
G01Y436535D02*
X-1309911D01*
G01X-1318612Y436687D02*
X-1317431D01*
G01Y437165D02*
X-1318612D01*
G01X-1316446Y437791D02*
X-1316840D01*
G01X-1318612Y438167D02*
X-1317824D01*
G01X-1316446Y438417D02*
X-1316840D01*
G01X-1316446D02*
X-1316249Y438400D01*
X-1316059Y438349D01*
X-1315885Y438268D01*
X-1315734Y438158D01*
X-1315612Y438024D01*
X-1315524Y437873D01*
X-1315474Y437710D01*
X-1315463Y437541D01*
X-1315493Y437374D01*
X-1315562Y437216D01*
X-1315667Y437073D01*
X-1315806Y436948D01*
X-1315969Y436852D01*
X-1316152Y436786D01*
X-1316550Y436716D01*
G01X-1314281Y423228D02*
X-1314084Y423031D01*
G01X-1309517Y419882D02*
X-1308336Y418701D01*
G01X-1304852Y419488D02*
X-1304065Y418701D01*
G01X-1305762Y421166D02*
X-1305320Y420724D01*
G01X-1317431Y437083D02*
X-1317652Y437390D01*
X-1317782Y437759D01*
X-1317824Y438167D01*
G01X-1314707Y428322D02*
X-1314578Y428139D01*
X-1314475Y427961D01*
X-1314395Y427792D01*
X-1314339Y427632D01*
X-1314307Y427483D01*
X-1314298Y427346D01*
X-1314311Y427224D01*
X-1314344Y427115D01*
X-1314398Y427018D01*
X-1314473Y426932D01*
X-1314573Y426854D01*
X-1314701Y426786D01*
X-1314855Y426731D01*
X-1315034Y426691D01*
X-1315237Y426665D01*
X-1315462Y426654D01*
G01X-1314707Y428948D02*
X-1314563Y428663D01*
X-1314453Y428392D01*
X-1314372Y428139D01*
X-1314322Y427903D01*
X-1314299Y427687D01*
X-1314304Y427494D01*
X-1314334Y427325D01*
X-1314386Y427179D01*
X-1314459Y427055D01*
X-1314553Y426947D01*
X-1314672Y426854D01*
X-1314822Y426775D01*
X-1315005Y426713D01*
X-1315219Y426672D01*
X-1315462Y426654D01*
G01X-1316742Y419882D02*
X-1315954Y416943D01*
G01X-1317234Y430015D02*
X-1317215Y429853D01*
X-1317160Y429697D01*
X-1317070Y429553D01*
X-1316946Y429425D01*
X-1316797Y429321D01*
X-1316628Y429244D01*
X-1316444Y429197D01*
X-1316250Y429180D01*
G01X-1316446Y431102D02*
X-1316423Y430892D01*
X-1316352Y430657D01*
X-1316228Y430407D01*
X-1316053Y430147D01*
G01X-1318612Y472129D02*
Y436688D01*
G01X-1317824Y438167D02*
Y466258D01*
G01X-1317431Y472129D02*
Y417205D01*
G01X-1316840Y431102D02*
Y471850D01*
G01X-1316742Y464646D02*
Y428031D01*
G01Y422441D02*
Y419882D01*
G01Y424106D02*
Y425669D01*
G01X-1316446Y471004D02*
Y431102D01*
G01X-1316348Y436752D02*
Y436126D01*
G01X-1316250Y424106D02*
Y417205D01*
G01Y428554D02*
Y429180D01*
G01X-1315856Y471752D02*
Y420571D01*
G01X-1315462Y429180D02*
Y428554D01*
G01Y436956D02*
Y437582D01*
G01X-1315364Y424106D02*
Y420472D01*
G01X-1314773Y414370D02*
Y429331D01*
G01X-1314707Y428948D02*
Y428322D01*
G01X-1314380Y422933D02*
Y426279D01*
G01X-1314298Y427359D02*
Y427624D01*
G01X-1314281Y425984D02*
Y423228D01*
G01X-1313100Y416614D02*
Y415433D01*
G01X-1313002Y420571D02*
Y422933D01*
G01X-1312903Y423031D02*
Y420472D01*
G01X-1312332Y418701D02*
Y414370D01*
G01X-1312313Y416119D02*
Y418583D01*
G01X-1312234Y416119D02*
Y418583D01*
G01X-1311939Y419488D02*
Y421654D01*
G01X-1311643Y420307D02*
Y419173D01*
G01X-1309950Y432579D02*
Y430807D01*
G01X-1309911Y448207D02*
Y429902D01*
G01Y429514D02*
Y420734D01*
G01X-1309517Y419882D02*
Y422835D01*
G01X-1309124Y448207D02*
Y429902D01*
G01X-1309025Y432276D02*
Y431026D01*
G01X-1308730Y429890D02*
Y430516D01*
G01X-1308572Y415433D02*
Y416614D01*
G01X-1306171Y413298D02*
Y411069D01*
G01X-1306072Y413298D02*
Y410899D01*
G01X-1305147Y419173D02*
Y420307D01*
G01X-1304990Y428327D02*
Y426279D01*
G01X-1304852Y419488D02*
Y421654D01*
G01X-1304458Y414370D02*
Y418701D01*
G01X-1316840Y431102D02*
X-1316865Y430888D01*
X-1316937Y430653D01*
X-1317061Y430404D01*
X-1317234Y430147D01*
G01X-1309911Y429514D02*
X-1309889Y429709D01*
X-1309822Y429896D01*
X-1309714Y430068D01*
X-1309565Y430222D01*
X-1309387Y430346D01*
X-1309184Y430439D01*
X-1308963Y430496D01*
X-1308730Y430516D01*
G01X-1317234Y435295D02*
X-1317213Y435469D01*
X-1317149Y435635D01*
X-1317046Y435786D01*
X-1316908Y435916D01*
X-1316742Y436018D01*
X-1316551Y436090D01*
G01X-1317431Y437478D02*
X-1317420Y437539D01*
X-1317386Y437597D01*
X-1317332Y437651D01*
X-1317258Y437699D01*
X-1317169Y437738D01*
X-1317067Y437767D01*
X-1316957Y437785D01*
X-1316840Y437791D01*
G01X-1306525Y414049D02*
X-1306584Y413861D01*
G01X-1314084Y426181D02*
X-1314281Y425984D01*
G01X-1315954Y419882D02*
X-1315364Y420472D01*
G01X-1311029Y421166D02*
X-1311470Y420724D01*
G01X-1311939Y419488D02*
X-1312726Y418701D01*
G01X-1310289Y416638D02*
X-1311226Y415702D01*
G01X-1310234Y416582D02*
X-1311170Y415646D01*
G01X-1302923Y437044D02*
X-1308966Y432579D01*
G01X-1303021Y436713D02*
X-1309025Y432276D01*
G01X-1316550Y436716D02*
X-1316738Y436646D01*
X-1316905Y436544D01*
X-1317043Y436415D01*
X-1317147Y436264D01*
X-1317212Y436096D01*
X-1317234Y435921D01*
G01X-1302923Y429050D02*
X-1304990Y428327D01*
G01X-1312706Y409528D02*
G03X-1313100Y409134I0J-394D01*
G01X-1317431Y417205D02*
G03X-1317234Y416495I1378J0D01*
G01X-1312706Y417008D02*
G03X-1313100Y416614I0J-394D01*
G01Y415433D02*
G03X-1312706Y415039I394J0D01*
G01X-1316250Y417205D02*
G03X-1316053Y417008I197J0D01*
G01X-1308572Y409134D02*
G03X-1308966Y409528I-394J0D01*
G01X-1310305Y420052D02*
G03X-1309911Y420734I-393J682D01*
G01X-1310305Y420052D02*
G03X-1309911Y418583I394J-682D01*
G01X-1312313Y416119D02*
G03X-1311170Y415646I669J0D01*
G01X-1309281Y416220D02*
G03X-1310289Y416638I-591J0D01*
G01X-1312234Y416119D02*
G03X-1311226Y415702I590J0D01*
G01X-1312234Y418583D02*
G03X-1311643Y419173I0J591D01*
G01X-1311470Y420724D02*
G03X-1311643Y420307I417J-417D01*
G01X-1310611Y421339D02*
G03X-1311029Y421166I0J-591D01*
G01X-1309360Y416220D02*
G03X-1310234Y416582I-512J0D01*
G01X-1308966Y415039D02*
G03X-1308572Y415433I0J394D01*
G01Y416614D02*
G03X-1308966Y417008I-394J0D01*
G01X-1306171Y411069D02*
G03X-1306072Y410899I197J1D01*
G01X-1305974Y410728D02*
G03X-1306072Y410899I-197J1D01*
G01X-1306171Y411122D02*
G03X-1306072Y410952I197J1D01*
G01X-1305974Y410781D02*
G03X-1306072Y410952I-197J1D01*
G01X-1305974Y413298D02*
G03X-1306525Y414049I-788J0D01*
G01X-1306072Y413298D02*
G03X-1306555Y413955I-689J-1D01*
G01X-1306171Y413298D02*
G03X-1306584Y413861I-591J0D01*
G01X-1307374Y414370D02*
G03X-1306584Y413861I1320J1182D01*
G01X-1307238Y414370D02*
G03X-1306555Y413955I1185J1181D01*
G01X-1307094Y414370D02*
G03X-1306525Y414049I1041J1181D01*
G01X-1305147Y420307D02*
G03X-1305320Y420724I-591J-1D01*
G01X-1305147Y419173D02*
G03X-1304557Y418583I590J0D01*
G01X-1305762Y421166D02*
G03X-1306180Y421339I-418J-418D01*
G01X-1303021Y438484D02*
X-1309025Y440921D01*
G01X-1302923Y446065D02*
X-1308966Y448524D01*
G01X-1303021Y446358D02*
X-1309025Y448800D01*
G01X-1306589Y442136D02*
X-1306402Y442152D01*
X-1306220Y442198D01*
X-1306054Y442274D01*
X-1305905Y442377D01*
X-1305785Y442501D01*
X-1305695Y442642D01*
X-1305640Y442795D01*
X-1305621Y442958D01*
G01X-1306330Y443262D02*
X-1306307Y443264D01*
X-1306285Y443270D01*
X-1306264Y443279D01*
X-1306246Y443292D01*
X-1306231Y443307D01*
X-1306220Y443324D01*
X-1306214Y443343D01*
X-1306211Y443363D01*
G01X-1305503Y444544D02*
X-1305526Y444542D01*
X-1305548Y444537D01*
X-1305568Y444528D01*
X-1305586Y444515D01*
X-1305601Y444500D01*
X-1305612Y444483D01*
X-1305618Y444464D01*
X-1305621Y444444D01*
G01X-1305243Y445462D02*
X-1305431Y445446D01*
X-1305612Y445400D01*
X-1305779Y445324D01*
X-1305928Y445221D01*
X-1306048Y445097D01*
X-1306137Y444956D01*
X-1306193Y444803D01*
X-1306211Y444641D01*
G01X-1305503Y448731D02*
X-1305526Y448729D01*
X-1305548Y448724D01*
X-1305568Y448715D01*
X-1305586Y448702D01*
X-1305601Y448687D01*
X-1305612Y448670D01*
X-1305618Y448651D01*
X-1305621Y448631D01*
G01X-1306861Y448731D02*
X-1306884Y448729D01*
X-1306906Y448724D01*
X-1306926Y448715D01*
X-1306944Y448702D01*
X-1306959Y448687D01*
X-1306970Y448670D01*
X-1306977Y448651D01*
X-1306979Y448631D01*
G01X-1306861Y449649D02*
X-1307049Y449633D01*
X-1307230Y449587D01*
X-1307397Y449511D01*
X-1307546Y449408D01*
X-1307666Y449284D01*
X-1307755Y449143D01*
X-1307811Y448990D01*
X-1307830Y448827D01*
G01X-1304971Y452768D02*
X-1304948Y452770D01*
X-1304926Y452776D01*
X-1304906Y452785D01*
X-1304888Y452797D01*
X-1304873Y452812D01*
X-1304862Y452829D01*
X-1304855Y452848D01*
X-1304853Y452868D01*
G01X-1304971Y454657D02*
X-1304783Y454672D01*
X-1304602Y454719D01*
X-1304435Y454794D01*
X-1304287Y454897D01*
X-1304167Y455021D01*
X-1304077Y455163D01*
X-1304022Y455316D01*
X-1304003Y455478D01*
G01X-1305326Y455783D02*
X-1305303Y455785D01*
X-1305281Y455790D01*
X-1305260Y455800D01*
X-1305242Y455812D01*
X-1305228Y455827D01*
X-1305217Y455844D01*
X-1305210Y455863D01*
X-1305207Y455883D01*
G01X-1306507Y457105D02*
X-1306530Y457103D01*
X-1306552Y457097D01*
X-1306572Y457088D01*
X-1306590Y457076D01*
X-1306605Y457061D01*
X-1306616Y457043D01*
X-1306622Y457024D01*
X-1306625Y457005D01*
G01X-1316742Y439961D02*
X-1317234D01*
G01X-1308966Y440650D02*
X-1309950D01*
G01X-1309124Y440748D02*
X-1309911D01*
G01X-1316742D02*
X-1317234D01*
G01X-1309911Y440766D02*
X-1309124D01*
G01X-1309911Y441043D02*
X-1309124D01*
G01X-1309911Y442028D02*
X-1309124D01*
G01X-1304003Y442136D02*
X-1304853D01*
G01X-1306589D02*
X-1306861D01*
G01X-1306589Y442241D02*
X-1306861D01*
G01X-1304003D02*
X-1304853D01*
G01X-1309124Y442305D02*
X-1309911D01*
G01X-1309124Y442323D02*
X-1309911D01*
G01X-1308966Y442421D02*
X-1309950D01*
G01X-1306861Y443158D02*
X-1306330D01*
G01X-1306861Y443262D02*
X-1306330D01*
G01X-1309911Y443506D02*
X-1309124D01*
G01Y444204D02*
X-1309911D01*
G01X-1304971Y444440D02*
X-1305503D01*
G01X-1304971Y444544D02*
X-1305503D01*
G01X-1307830Y445462D02*
X-1306979D01*
G01X-1305243D02*
X-1304971D01*
G01X-1307830Y445566D02*
X-1306979D01*
G01X-1305243D02*
X-1304971D01*
G01X-1304003Y446283D02*
X-1304853D01*
G01X-1306979D02*
X-1307830D01*
G01X-1304003Y446387D02*
X-1304853D01*
G01X-1306979D02*
X-1307830D01*
G01X-1305621Y446684D02*
X-1306211D01*
G01X-1305621Y446788D02*
X-1306211D01*
G01X-1316742Y447652D02*
X-1317234D01*
G01X-1309124Y448207D02*
X-1309911D01*
G01X-1317234Y448334D02*
X-1316742D01*
G01X-1308966Y448524D02*
X-1309950D01*
G01X-1309124Y448622D02*
X-1309911D01*
G01X-1304971Y448627D02*
X-1305503D01*
G01X-1306330D02*
X-1306861D01*
G01X-1309911Y448640D02*
X-1309124D01*
G01X-1306330Y448731D02*
X-1306861D01*
G01X-1304971D02*
X-1305503D01*
G01X-1309911Y448917D02*
X-1309124D01*
G01X-1316742Y449606D02*
X-1316840D01*
G01X-1306861Y449649D02*
X-1304971D01*
G01X-1306861Y449753D02*
X-1304971D01*
G01X-1316742Y449803D02*
X-1317234D01*
G01X-1309911Y449902D02*
X-1309124D01*
G01Y450179D02*
X-1309911D01*
G01X-1309124Y450197D02*
X-1309911D01*
G01X-1308966Y450295D02*
X-1309950D01*
G01X-1304003Y450470D02*
X-1304853D01*
G01X-1304003Y450574D02*
X-1304853D01*
G01X-1304971Y451642D02*
X-1307830D01*
G01X-1304971Y451746D02*
X-1307830D01*
G01Y452663D02*
X-1304971D01*
G01X-1307830Y452768D02*
X-1304971D01*
G01X-1304853Y453835D02*
X-1304003D01*
G01X-1304853Y453940D02*
X-1304003D01*
G01X-1317234Y454409D02*
X-1317431D01*
G01X-1318021Y454413D02*
X-1318612D01*
G01X-1304971Y454657D02*
X-1306861D01*
G01X-1304971Y454761D02*
X-1306861D01*
G01X-1305326Y455678D02*
X-1306507D01*
G01X-1305326Y455783D02*
X-1306507D01*
G01X-1316742Y456185D02*
X-1317234D01*
G01X-1317431Y456381D02*
X-1318612D01*
G01X-1317234Y456747D02*
X-1316742D01*
G01Y456972D02*
X-1317234D01*
G01X-1306507Y457001D02*
X-1305326D01*
G01X-1306507Y457105D02*
X-1305326D01*
G01X-1316742Y457169D02*
X-1317234D01*
G01X-1306861Y458022D02*
X-1304971D01*
G01X-1306861Y458127D02*
X-1304971D01*
G01X-1317431Y458153D02*
X-1318612D01*
G01X-1308966Y458366D02*
X-1309950D01*
G01X-1309124Y458465D02*
X-1309911D01*
G01Y458483D02*
X-1309124D01*
G01X-1316742Y458547D02*
X-1317234D01*
G01X-1318612D02*
X-1317431D01*
G01X-1309911Y458760D02*
X-1309124D01*
G01X-1306979Y458844D02*
X-1307830D01*
G01X-1312106Y458937D02*
X-1312194D01*
G01X-1311353D02*
X-1311442D01*
G01X-1317431Y458941D02*
X-1318612D01*
G01X-1306979Y458948D02*
X-1307830D01*
G01X-1316742Y459137D02*
X-1317234D01*
G01X-1317628D02*
X-1318809D01*
G01X-1311840Y459254D02*
X-1312106D01*
G01Y459344D02*
X-1311826D01*
G01Y459570D02*
X-1312106D01*
G01X-1312194Y459646D02*
X-1311840D01*
G01X-1311442D02*
X-1311353D01*
G01X-1309911Y459744D02*
X-1309124D01*
G01Y460021D02*
X-1309911D01*
G01X-1309124Y460039D02*
X-1309911D01*
G01X-1308966Y460138D02*
X-1309950D01*
G01X-1306860Y461108D02*
X-1304003Y460896D01*
G01Y461000D02*
X-1306860Y461213D01*
G01X-1306861Y442241D02*
X-1307049Y442256D01*
X-1307230Y442303D01*
X-1307397Y442378D01*
X-1307546Y442481D01*
X-1307666Y442605D01*
X-1307755Y442746D01*
X-1307811Y442900D01*
X-1307830Y443062D01*
G01X-1306861Y443158D02*
X-1306884Y443160D01*
X-1306906Y443166D01*
X-1306926Y443175D01*
X-1306944Y443187D01*
X-1306959Y443202D01*
X-1306970Y443220D01*
X-1306977Y443239D01*
X-1306979Y443258D01*
G01X-1304971Y444440D02*
X-1304948Y444438D01*
X-1304926Y444433D01*
X-1304906Y444423D01*
X-1304888Y444411D01*
X-1304873Y444396D01*
X-1304862Y444378D01*
X-1304855Y444360D01*
X-1304853Y444340D01*
G01X-1304971Y445566D02*
X-1304783Y445550D01*
X-1304602Y445504D01*
X-1304435Y445429D01*
X-1304287Y445326D01*
X-1304167Y445202D01*
X-1304077Y445061D01*
X-1304022Y444907D01*
X-1304003Y444745D01*
G01X-1306330Y448627D02*
X-1306307Y448625D01*
X-1306285Y448619D01*
X-1306264Y448610D01*
X-1306246Y448598D01*
X-1306231Y448583D01*
X-1306220Y448565D01*
X-1306214Y448546D01*
X-1306211Y448527D01*
G01X-1304971Y448627D02*
X-1304948Y448625D01*
X-1304926Y448619D01*
X-1304906Y448610D01*
X-1304888Y448598D01*
X-1304873Y448583D01*
X-1304862Y448565D01*
X-1304855Y448546D01*
X-1304853Y448527D01*
G01X-1304971Y449753D02*
X-1304783Y449737D01*
X-1304602Y449691D01*
X-1304435Y449616D01*
X-1304287Y449512D01*
X-1304167Y449389D01*
X-1304077Y449247D01*
X-1304022Y449094D01*
X-1304003Y448931D01*
G01X-1304971Y451642D02*
X-1304948Y451640D01*
X-1304926Y451634D01*
X-1304906Y451625D01*
X-1304888Y451613D01*
X-1304873Y451598D01*
X-1304862Y451580D01*
X-1304855Y451561D01*
X-1304853Y451542D01*
G01X-1306861Y454761D02*
X-1307049Y454777D01*
X-1307230Y454823D01*
X-1307397Y454898D01*
X-1307546Y455002D01*
X-1307666Y455126D01*
X-1307755Y455267D01*
X-1307811Y455420D01*
X-1307830Y455582D01*
G01X-1306507Y455678D02*
X-1306530Y455680D01*
X-1306552Y455686D01*
X-1306572Y455695D01*
X-1306590Y455708D01*
X-1306605Y455723D01*
X-1306616Y455740D01*
X-1306622Y455759D01*
X-1306625Y455779D01*
G01X-1305326Y457001D02*
X-1305303Y456999D01*
X-1305281Y456993D01*
X-1305260Y456984D01*
X-1305242Y456971D01*
X-1305228Y456956D01*
X-1305217Y456939D01*
X-1305210Y456920D01*
X-1305207Y456900D01*
G01X-1304971Y458127D02*
X-1304783Y458111D01*
X-1304602Y458065D01*
X-1304435Y457989D01*
X-1304287Y457886D01*
X-1304167Y457762D01*
X-1304077Y457621D01*
X-1304022Y457468D01*
X-1304003Y457305D01*
G01X-1311840Y459646D02*
X-1311767Y459631D01*
G01X-1311781Y459555D02*
X-1311826Y459570D01*
G01X-1308966Y458366D02*
X-1302923Y453878D01*
G01X-1309025Y458691D02*
X-1303021Y454232D01*
G01X-1311767Y459631D02*
X-1311707Y459585D01*
G01X-1311752Y459525D02*
X-1311781Y459555D01*
G01X-1306860Y461213D02*
X-1306920Y461198D01*
X-1306963Y461162D01*
X-1306979Y461112D01*
G01X-1311767Y459269D02*
X-1311840Y459254D01*
G01X-1306861Y458022D02*
X-1307049Y458007D01*
X-1307230Y457960D01*
X-1307397Y457885D01*
X-1307546Y457782D01*
X-1307666Y457658D01*
X-1307755Y457516D01*
X-1307811Y457363D01*
X-1307830Y457201D01*
G01X-1303021Y460335D02*
X-1309025Y459942D01*
G01X-1302923Y460533D02*
X-1308966Y460138D01*
G01X-1311707Y459585D02*
X-1311663Y459525D01*
G01X-1316840Y443449D02*
X-1316742Y443238D01*
G01X-1311737Y459480D02*
X-1311752Y459525D01*
G01X-1311663D02*
X-1311648Y459480D01*
G01X-1318809Y461529D02*
Y459137D01*
G01X-1317628D02*
Y461529D01*
G01X-1312194Y458937D02*
Y459646D01*
G01X-1312106Y459254D02*
Y458937D01*
G01Y459570D02*
Y459344D01*
G01X-1311737Y459435D02*
Y459480D01*
G01X-1311648D02*
Y459420D01*
G01X-1311530D02*
Y459540D01*
G01X-1311442Y458937D02*
Y459525D01*
G01X-1311353Y459646D02*
Y458937D01*
G01X-1309950Y460138D02*
Y458366D01*
G01Y450295D02*
Y448524D01*
G01Y442421D02*
Y440650D01*
G01X-1309911Y448622D02*
Y450197D01*
G01Y458465D02*
Y460039D01*
G01X-1307830Y442958D02*
X-1307811Y442798D01*
X-1307757Y442645D01*
X-1307668Y442503D01*
X-1307546Y442377D01*
X-1307400Y442275D01*
X-1307233Y442200D01*
X-1307053Y442153D01*
X-1306861Y442136D01*
G01X-1306979Y443363D02*
X-1306977Y443343D01*
X-1306970Y443324D01*
X-1306959Y443307D01*
X-1306944Y443292D01*
X-1306927Y443279D01*
X-1306907Y443270D01*
X-1306885Y443264D01*
X-1306861Y443262D01*
G01X-1307830Y455478D02*
X-1307811Y455318D01*
X-1307757Y455165D01*
X-1307668Y455024D01*
X-1307546Y454897D01*
X-1307400Y454796D01*
X-1307233Y454720D01*
X-1307053Y454673D01*
X-1306861Y454657D01*
G01X-1306211Y448631D02*
X-1306214Y448650D01*
X-1306220Y448669D01*
X-1306231Y448687D01*
X-1306246Y448702D01*
X-1306264Y448714D01*
X-1306284Y448724D01*
X-1306306Y448729D01*
X-1306330Y448731D01*
G01X-1306625Y455883D02*
X-1306623Y455863D01*
X-1306616Y455845D01*
X-1306605Y455828D01*
X-1306590Y455812D01*
X-1306572Y455800D01*
X-1306552Y455791D01*
X-1306530Y455785D01*
X-1306507Y455783D01*
G01X-1304853Y444444D02*
X-1304855Y444464D01*
X-1304862Y444482D01*
X-1304873Y444500D01*
X-1304888Y444515D01*
X-1304905Y444528D01*
X-1304926Y444537D01*
X-1304948Y444542D01*
X-1304971Y444544D01*
G01X-1304853Y448631D02*
X-1304855Y448650D01*
X-1304862Y448669D01*
X-1304873Y448687D01*
X-1304888Y448702D01*
X-1304905Y448714D01*
X-1304926Y448724D01*
X-1304948Y448729D01*
X-1304971Y448731D01*
G01X-1304853Y451646D02*
X-1304855Y451665D01*
X-1304862Y451684D01*
X-1304873Y451702D01*
X-1304888Y451717D01*
X-1304905Y451729D01*
X-1304926Y451739D01*
X-1304948Y451744D01*
X-1304971Y451746D01*
G01X-1304003Y444641D02*
X-1304021Y444800D01*
X-1304076Y444954D01*
X-1304165Y445095D01*
X-1304287Y445221D01*
X-1304433Y445323D01*
X-1304599Y445399D01*
X-1304780Y445446D01*
X-1304971Y445462D01*
G01X-1305207Y457005D02*
X-1305210Y457024D01*
X-1305217Y457043D01*
X-1305227Y457060D01*
X-1305242Y457076D01*
X-1305260Y457088D01*
X-1305280Y457097D01*
X-1305302Y457103D01*
X-1305326Y457105D01*
G01X-1304003Y448827D02*
X-1304021Y448987D01*
X-1304076Y449140D01*
X-1304165Y449282D01*
X-1304287Y449408D01*
X-1304433Y449510D01*
X-1304599Y449585D01*
X-1304780Y449632D01*
X-1304971Y449649D01*
G01X-1304003Y457201D02*
X-1304021Y457361D01*
X-1304076Y457514D01*
X-1304165Y457655D01*
X-1304287Y457782D01*
X-1304433Y457883D01*
X-1304599Y457959D01*
X-1304780Y458006D01*
X-1304971Y458022D01*
G01X-1309124Y448622D02*
Y450197D01*
G01Y458465D02*
Y460039D01*
G01X-1309025Y459942D02*
Y458691D01*
G01Y450046D02*
Y448800D01*
G01Y442167D02*
Y440921D01*
G01X-1307830Y461873D02*
Y458844D01*
G01Y457305D02*
Y455478D01*
G01Y452768D02*
Y451642D01*
G01Y448931D02*
Y446283D01*
G01Y445566D02*
Y442958D01*
G01X-1306979Y461112D02*
Y458844D01*
G01Y448631D02*
Y446283D01*
G01Y445566D02*
Y443258D01*
G01X-1306861Y454761D02*
Y454657D01*
G01Y448731D02*
Y448627D01*
G01Y442241D02*
Y442136D01*
G01Y443158D02*
Y443262D01*
G01Y449649D02*
Y449753D01*
G01Y458022D02*
Y458127D01*
G01X-1306851Y461212D02*
Y461107D01*
G01X-1306625Y457005D02*
Y455779D01*
G01X-1306589Y442136D02*
Y442241D01*
G01X-1306507Y457105D02*
Y457001D01*
G01Y455678D02*
Y455783D01*
G01X-1306330Y443262D02*
Y443158D01*
G01Y448627D02*
Y448731D01*
G01X-1306211Y448631D02*
Y446684D01*
G01Y444745D02*
Y443258D01*
G01X-1305621Y448631D02*
Y446684D01*
G01Y444444D02*
Y442958D01*
G01X-1305503Y448731D02*
Y448627D01*
G01Y444544D02*
Y444440D01*
G01X-1305326Y455783D02*
Y455678D01*
G01Y457001D02*
Y457105D01*
G01X-1305243Y445462D02*
Y445566D01*
G01X-1305207Y457005D02*
Y455779D01*
G01X-1304971Y458127D02*
Y458022D01*
G01Y452768D02*
Y452663D01*
G01Y449753D02*
Y449649D01*
G01Y445566D02*
Y445462D01*
G01Y444440D02*
Y444544D01*
G01Y448627D02*
Y448731D01*
G01Y451642D02*
Y451746D01*
G01Y454657D02*
Y454761D01*
G01X-1304853Y453940D02*
Y452764D01*
G01Y451646D02*
Y450470D01*
G01Y448631D02*
Y446283D01*
G01Y444444D02*
Y442136D01*
G01X-1307830Y457305D02*
X-1307811Y457465D01*
X-1307757Y457618D01*
X-1307668Y457760D01*
X-1307546Y457886D01*
X-1307400Y457988D01*
X-1307233Y458063D01*
X-1307053Y458110D01*
X-1306861Y458127D01*
G01X-1307830Y448931D02*
X-1307811Y449091D01*
X-1307757Y449244D01*
X-1307668Y449386D01*
X-1307546Y449512D01*
X-1307400Y449614D01*
X-1307233Y449690D01*
X-1307053Y449737D01*
X-1306861Y449753D01*
G01X-1306625Y456900D02*
X-1306623Y456920D01*
X-1306616Y456939D01*
X-1306605Y456956D01*
X-1306590Y456971D01*
X-1306572Y456984D01*
X-1306552Y456993D01*
X-1306530Y456999D01*
X-1306507Y457001D01*
G01X-1306979Y448527D02*
X-1306977Y448546D01*
X-1306970Y448565D01*
X-1306959Y448582D01*
X-1306944Y448598D01*
X-1306927Y448610D01*
X-1306907Y448619D01*
X-1306885Y448625D01*
X-1306861Y448627D01*
G01X-1305207Y455779D02*
X-1305210Y455759D01*
X-1305217Y455741D01*
X-1305227Y455723D01*
X-1305242Y455708D01*
X-1305260Y455695D01*
X-1305280Y455686D01*
X-1305302Y455680D01*
X-1305326Y455678D01*
G01X-1306211Y444745D02*
X-1306193Y444904D01*
X-1306139Y445058D01*
X-1306050Y445199D01*
X-1305928Y445326D01*
X-1305782Y445427D01*
X-1305615Y445503D01*
X-1305435Y445550D01*
X-1305243Y445566D01*
G01X-1305621Y448527D02*
X-1305619Y448546D01*
X-1305612Y448565D01*
X-1305601Y448582D01*
X-1305586Y448598D01*
X-1305568Y448610D01*
X-1305548Y448619D01*
X-1305526Y448625D01*
X-1305503Y448627D01*
G01X-1306211Y443258D02*
X-1306214Y443239D01*
X-1306220Y443220D01*
X-1306231Y443203D01*
X-1306246Y443187D01*
X-1306264Y443175D01*
X-1306284Y443166D01*
X-1306306Y443160D01*
X-1306330Y443158D01*
G01X-1304853Y452764D02*
X-1304855Y452744D01*
X-1304862Y452726D01*
X-1304873Y452708D01*
X-1304888Y452693D01*
X-1304905Y452680D01*
X-1304926Y452671D01*
X-1304948Y452665D01*
X-1304971Y452663D01*
G01X-1305621Y444340D02*
X-1305619Y444359D01*
X-1305612Y444378D01*
X-1305601Y444395D01*
X-1305586Y444411D01*
X-1305568Y444423D01*
X-1305548Y444432D01*
X-1305526Y444438D01*
X-1305503Y444440D01*
G01X-1305621Y443062D02*
X-1305639Y442902D01*
X-1305694Y442749D01*
X-1305783Y442607D01*
X-1305905Y442481D01*
X-1306051Y442379D01*
X-1306217Y442304D01*
X-1306398Y442257D01*
X-1306589Y442241D01*
G01X-1304003Y455582D02*
X-1304021Y455423D01*
X-1304076Y455269D01*
X-1304165Y455128D01*
X-1304287Y455002D01*
X-1304433Y454900D01*
X-1304599Y454824D01*
X-1304780Y454777D01*
X-1304971Y454761D01*
G01X-1306979Y461007D02*
X-1306963Y461058D01*
X-1306920Y461094D01*
X-1306860Y461108D01*
G01X-1311752Y459389D02*
X-1311737Y459435D01*
G01X-1311648Y459420D02*
X-1311663Y459374D01*
G01X-1317431Y455436D02*
X-1318021Y454413D01*
G01X-1311663Y459374D02*
X-1311707Y459314D01*
G01X-1311530Y459540D02*
X-1311442Y459646D01*
G01Y459525D02*
X-1311530Y459420D01*
G01X-1311781Y459359D02*
X-1311752Y459389D01*
G01X-1311707Y459314D02*
X-1311767Y459269D01*
G01X-1302923Y444857D02*
X-1308966Y442421D01*
G01X-1303021Y444587D02*
X-1309025Y442167D01*
G01X-1302923Y452726D02*
X-1308966Y450295D01*
G01X-1303021Y452461D02*
X-1309025Y450046D01*
G01X-1311826Y459344D02*
X-1311781Y459359D01*
G01X-1318443Y463430D02*
G03X-1318809Y461529I4752J-1901D01*
G01X-1317346Y462991D02*
G03X-1317628Y461529I3655J-1463D01*
G01X-1317234Y456891D02*
G03X-1317431Y456181I1181J-710D01*
G01X-1308139Y459252D02*
G03I-1378J0D01*
G01X-1303705Y399464D02*
X-1303843Y399437D01*
X-1303912Y399424D01*
G01X-1302720Y399412D02*
X-1302656Y399424D01*
X-1302591Y399442D01*
X-1302524Y399464D01*
G01X-1299872Y403150D02*
X-1297962D01*
G01X-1296781Y404331D02*
X-1301053D01*
G01X-1303996Y403418D02*
X-1303871Y403406D01*
X-1303746Y403372D01*
X-1303621Y403313D01*
X-1303498Y403227D01*
X-1303378Y403111D01*
X-1303265Y402960D01*
X-1303165Y402775D01*
X-1303085Y402557D01*
X-1303031Y402311D01*
G01X-1304221Y402013D02*
X-1304026Y401909D01*
G01X-1303330Y403461D02*
X-1303424Y403520D01*
X-1303525Y403570D01*
X-1303637Y403610D01*
X-1303752Y403639D01*
X-1303873Y403657D01*
X-1303996Y403663D01*
G01X-1299872Y403150D02*
X-1301840Y405118D01*
G01X-1303021Y402854D02*
X-1303061Y402993D01*
X-1303131Y403150D01*
X-1303219Y403300D01*
X-1303330Y403461D01*
G01X-1303031Y402311D02*
X-1303030Y402305D01*
X-1303026Y402290D01*
X-1303023Y402274D01*
X-1303021Y402265D01*
G01X-1302841Y401276D02*
X-1302735Y400783D01*
X-1302630Y400229D01*
X-1302524Y399659D01*
G01X-1303250Y403063D02*
X-1303172Y402700D01*
X-1303091Y402352D01*
X-1303004Y402013D01*
G01X-1303330Y403461D02*
X-1303239Y403002D01*
X-1303145Y402554D01*
X-1303046Y402112D01*
G01X-1304202Y402265D02*
X-1304204Y402271D01*
X-1304207Y402287D01*
X-1304211Y402302D01*
X-1304213Y402311D01*
G01X-1303705Y399659D02*
X-1303811Y400229D01*
X-1303917Y400783D01*
X-1304022Y401276D01*
G01X-1302841Y401890D02*
X-1303021Y402854D01*
G01X-1304022Y401276D02*
X-1304202Y402265D01*
G01X-1303021D02*
X-1302841Y401276D01*
G01X-1304202Y402885D02*
X-1304022Y401890D01*
G01D02*
X-1303943Y401342D01*
X-1303863Y400736D01*
G01X-1304221Y402013D02*
X-1304157Y401555D01*
X-1304094Y401052D01*
G01X-1302963Y401457D02*
X-1303037Y402013D01*
G01X-1302691Y400811D02*
X-1302768Y401392D01*
X-1302841Y401890D01*
G01X-1302524Y399464D02*
X-1302691Y400811D01*
G01X-1303863Y400736D02*
X-1303705Y399464D01*
G01X-1302963Y401457D02*
X-1302881Y400789D01*
X-1302799Y400081D01*
X-1302717Y399427D01*
G01X-1302718Y399419D02*
X-1302799Y400080D01*
X-1302881Y400789D01*
X-1302963Y401456D01*
G01X-1304094Y401052D02*
X-1303967Y399970D01*
X-1303912Y399425D01*
G01X-1302722D02*
X-1302720Y399412D01*
G01X-1304202Y402265D02*
Y402885D01*
G01X-1304022Y401890D02*
Y401276D01*
G01X-1303996Y403418D02*
Y403663D01*
G01X-1303705Y399659D02*
Y399464D01*
G01X-1303021Y402854D02*
Y402265D01*
G01X-1302841Y401276D02*
Y401890D01*
G01X-1302524Y399464D02*
Y399659D01*
G01X-1301840Y409055D02*
Y405118D01*
G01X-1302717Y399427D02*
X-1302722Y399421D01*
G01X-1302718Y399419D02*
X-1302721Y399416D01*
G01X-1302717Y399427D02*
X-1302527Y399488D01*
G01X-1301462Y403392D02*
G03X-1303996Y405591I-2534J-360D01*
G01X-1300108Y412402D02*
X-1300895D01*
G01X-1300108Y412849D02*
X-1300895D01*
G01X-1300108Y412902D02*
X-1300895D01*
G01X-1300108Y413197D02*
X-1300895D01*
G01X-1300108Y413243D02*
X-1300895D01*
G01X-1300108Y414254D02*
X-1300895D01*
G01X-1296584Y420472D02*
X-1299045D01*
G01X-1298946Y420571D02*
X-1296092D01*
G01X-1297568Y422933D02*
X-1298946D01*
G01X-1299045Y423031D02*
X-1297864D01*
G01X-1297568Y426279D02*
X-1303809D01*
G01X-1302037Y426654D02*
X-1294714D01*
G01X-1303218Y430516D02*
X-1302989Y430497D01*
X-1302768Y430440D01*
X-1302565Y430348D01*
X-1302383Y430222D01*
X-1302237Y430071D01*
X-1302128Y429899D01*
X-1302061Y429712D01*
X-1302037Y429514D01*
G01Y428322D02*
X-1297242D01*
G01X-1302037Y428839D02*
X-1303021D01*
G01X-1302037Y428926D02*
X-1302824D01*
G01Y428944D02*
X-1302037D01*
G01X-1297242Y428948D02*
X-1302037D01*
G01X-1302824Y429221D02*
X-1302037D01*
G01X-1302824Y430205D02*
X-1302037D01*
G01X-1303809Y430216D02*
X-1296092D01*
G01X-1302037Y430483D02*
X-1302824D01*
G01X-1302037Y430501D02*
X-1302824D01*
G01X-1302037Y430610D02*
X-1303021D01*
G01X-1301840Y432612D02*
X-1296092D01*
G01X-1302824Y433192D02*
X-1302037D01*
G01X-1296092Y433366D02*
X-1303809D01*
G01X-1302037Y435278D02*
X-1302824D01*
G01X-1302037Y436713D02*
X-1303021D01*
G01X-1302037Y436800D02*
X-1302824D01*
G01Y436818D02*
X-1302037D01*
G01X-1302824Y437095D02*
X-1302037D01*
G01X-1302824Y438079D02*
X-1302037D01*
G01Y438357D02*
X-1302824D01*
G01X-1302037Y438375D02*
X-1302824D01*
G01X-1302037Y438484D02*
X-1303021D01*
G01X-1302037Y428888D02*
X-1302060Y429083D01*
X-1302126Y429270D01*
X-1302235Y429442D01*
X-1302383Y429596D01*
X-1302561Y429720D01*
X-1302765Y429813D01*
X-1302985Y429870D01*
X-1303218Y429890D01*
G01X-1303809Y433366D02*
Y430216D01*
G01Y428138D02*
Y426279D01*
G01X-1303415Y433366D02*
Y430216D01*
G01X-1303218Y430516D02*
Y429890D01*
G01X-1302923Y429050D02*
Y430389D01*
G01Y437044D02*
Y438196D01*
G01X-1302824Y458374D02*
Y428926D01*
G01X-1302431Y422835D02*
Y419882D01*
G01X-1302037Y420734D02*
Y458374D01*
G01X-1301840Y452661D02*
Y430216D01*
G01X-1299281D02*
Y429331D01*
G01X-1299045Y420472D02*
Y423031D01*
G01X-1298946Y422933D02*
Y420571D01*
G01X-1302431Y419882D02*
X-1303612Y418701D01*
G01X-1303021Y428839D02*
X-1303809Y428138D01*
G01X-1297549Y414370D02*
X-1298730Y413583D01*
G01X-1302037Y418583D02*
G03X-1301643Y420052I0J787D01*
G01X-1302037Y420734D02*
G03X-1301643Y420052I787J0D01*
G01X-1302037Y444587D02*
X-1303021D01*
G01X-1302037Y444674D02*
X-1302824D01*
G01Y444692D02*
X-1302037D01*
G01X-1302824Y444969D02*
X-1302037D01*
G01X-1302824Y445954D02*
X-1302037D01*
G01Y446231D02*
X-1302824D01*
G01X-1302037Y446249D02*
X-1302824D01*
G01X-1302037Y446358D02*
X-1303021D01*
G01X-1301840Y447065D02*
X-1296092D01*
G01X-1301840Y448329D02*
X-1296092D01*
G01X-1302824Y449128D02*
X-1302037D01*
G01Y449572D02*
X-1302824D01*
G01X-1301840Y450353D02*
X-1303415D01*
G01X-1296092Y451095D02*
X-1301840D01*
G01Y451239D02*
X-1303809D01*
G01X-1302037Y452461D02*
X-1303021D01*
G01X-1302037Y452548D02*
X-1302824D01*
G01Y452566D02*
X-1302037D01*
G01X-1301840Y452661D02*
X-1296092D01*
G01X-1302824Y452843D02*
X-1302037D01*
G01X-1302824Y453828D02*
X-1302037D01*
G01Y454105D02*
X-1302824D01*
G01X-1302037Y454123D02*
X-1302824D01*
G01X-1302037Y454232D02*
X-1303021D01*
G01X-1301840Y455858D02*
X-1296092D01*
G01X-1301840Y456596D02*
X-1296092D01*
G01X-1302037Y458374D02*
X-1302824D01*
G01X-1303415Y460105D02*
X-1301840D01*
G01X-1302037Y460335D02*
X-1303021D01*
G01X-1302037Y460422D02*
X-1302824D01*
G01Y460440D02*
X-1302037D01*
G01X-1302824Y460717D02*
X-1302037D01*
G01X-1303415Y450353D02*
X-1303809Y450606D01*
G01X-1303415Y460105D02*
X-1303809Y461715D01*
G01X-1304003Y462026D02*
Y460896D01*
G01Y457305D02*
Y455478D01*
G01Y453940D02*
Y450470D01*
G01Y448931D02*
Y446283D01*
G01Y444745D02*
Y442136D01*
G01X-1303809Y450606D02*
Y464862D01*
G01X-1303415Y460105D02*
Y450353D01*
G01X-1302923Y444857D02*
Y446065D01*
G01Y452726D02*
Y453878D01*
G01Y460533D02*
Y461729D01*
G01X-1302824Y461997D02*
Y460422D01*
G01X-1302037Y462106D02*
Y460335D01*
G01X-1301840Y460105D02*
Y455858D01*
G01X-1301053Y461209D02*
G03I-1378J0D01*
G01X-1346919Y521732D02*
Y483752D01*
G01X-1303612Y513661D02*
X-1346919D01*
G01X-1340423Y532362D02*
G03I-6496J0D01*
G01X-1315850Y462303D02*
X-1308179D01*
G01X-1316742Y462613D02*
X-1317234D01*
G01X-1316742Y463147D02*
X-1317234D01*
G01X-1316053Y464646D02*
X-1317234D01*
G01Y464713D02*
X-1316053D01*
G01X-1306171Y464862D02*
X-1308179D01*
G01X-1305777D02*
X-1303809D01*
G01X-1316053Y465475D02*
X-1317234D01*
G01Y466235D02*
X-1316053D01*
G01X-1317824Y466258D02*
X-1318612D01*
G01X-1316053Y466993D02*
X-1317234D01*
G01X-1307357Y462273D02*
X-1307331D01*
X-1307324Y462272D01*
X-1307316D01*
G01Y462167D02*
X-1307322Y462168D01*
X-1307336D01*
X-1307343Y462169D01*
X-1307357D01*
G01X-1304003Y461922D02*
X-1307316Y462167D01*
G01Y462272D02*
X-1304003Y462026D01*
G01X-1306171Y464978D02*
X-1302923Y461729D01*
G01X-1305777Y464862D02*
X-1303021Y462106D01*
G01X-1307357Y462169D02*
X-1307449Y462161D01*
X-1307537Y462139D01*
X-1307618Y462102D01*
X-1307691Y462052D01*
X-1307750Y461991D01*
X-1307793Y461922D01*
X-1307820Y461848D01*
X-1307830Y461768D01*
G01X-1317234Y467754D02*
X-1316053D01*
G01X-1314380Y467815D02*
X-1312017D01*
G01X-1317431Y467996D02*
X-1318612D01*
G01X-1316053Y468516D02*
X-1317234D01*
G01X-1316053Y468583D02*
X-1317234D01*
G01X-1317431Y468783D02*
X-1318612D01*
G01X-1316742Y470866D02*
Y468583D01*
G01X-1315265Y463427D02*
Y471752D01*
G01X-1314380D02*
Y467815D01*
G01X-1312017D02*
Y471752D01*
G01X-1308179Y464862D02*
Y462303D01*
G01X-1307316Y462167D02*
Y462272D01*
G01X-1306171Y471752D02*
Y464862D01*
G01X-1305777Y471752D02*
Y464862D01*
G01X-1317824Y466258D02*
X-1317782Y466711D01*
X-1317652Y467219D01*
X-1317431Y467760D01*
G01X-1307830Y461873D02*
X-1307820Y461950D01*
X-1307794Y462025D01*
X-1307751Y462094D01*
X-1307691Y462156D01*
X-1307620Y462205D01*
X-1307539Y462242D01*
X-1307451Y462265D01*
X-1307357Y462273D01*
G01X-1315850Y462303D02*
X-1315265Y464552D01*
G01X-1318443Y463430D02*
X-1317234Y466452D01*
G01X-1316742Y464502D02*
X-1317346Y462991D01*
G01X-1315265Y463427D02*
X-1315850Y462303D01*
G01X-1309911Y471015D02*
X-1310067Y471028D01*
X-1310219Y471068D01*
X-1310358Y471133D01*
X-1310478Y471219D01*
X-1310576Y471325D01*
X-1310647Y471446D01*
X-1310688Y471574D01*
X-1310698Y471709D01*
X-1310676Y471842D01*
X-1310624Y471967D01*
X-1310542Y472083D01*
X-1310434Y472182D01*
X-1310305Y472261D01*
G01X-1314570Y472720D02*
X-1314435Y472705D01*
X-1314335Y472664D01*
X-1314268Y472602D01*
X-1314231Y472524D01*
X-1314219Y472431D01*
X-1314233Y472327D01*
X-1314272Y472212D01*
X-1314339Y472085D01*
X-1314437Y471946D01*
X-1314570Y471795D01*
G01Y473901D02*
X-1314349Y473825D01*
X-1314236Y473616D01*
X-1314231Y473285D01*
X-1314344Y472874D01*
X-1314570Y472421D01*
G01X-1316053Y471224D02*
X-1315779Y471240D01*
X-1315504Y471290D01*
X-1315240Y471373D01*
X-1314998Y471484D01*
X-1314772Y471626D01*
X-1314570Y471795D01*
G01X-1316840Y471224D02*
X-1316955Y471218D01*
X-1317065Y471200D01*
X-1317167Y471172D01*
X-1317258Y471132D01*
X-1317331Y471085D01*
X-1317385Y471031D01*
X-1317419Y470973D01*
X-1317431Y470911D01*
G01X-1315265Y469394D02*
X-1306171D01*
G01X-1305777Y469901D02*
X-1296683D01*
G01X-1316742Y470081D02*
X-1317234D01*
G01X-1302037Y470389D02*
X-1309911D01*
G01X-1318612Y470598D02*
X-1317431D01*
G01X-1317234Y470615D02*
X-1316742D01*
G01Y470866D02*
X-1313297D01*
G01X-1306171D02*
X-1305777D01*
G01X-1316840Y471004D02*
X-1316446D01*
G01X-1302037Y471015D02*
X-1309911D01*
G01X-1316840Y471224D02*
X-1316053D01*
G01X-1296092Y471752D02*
X-1305777D01*
G01X-1315856D02*
X-1306171D01*
G01X-1310085Y471795D02*
X-1314570D01*
G01X-1316840Y471850D02*
X-1316053D01*
G01Y471929D02*
X-1317234D01*
G01X-1314570Y472421D02*
X-1310085D01*
G01X-1316840Y472720D02*
X-1295108D01*
G01X-1316840Y473901D02*
X-1295108D01*
G01X-1318572Y489646D02*
X-1331958D01*
G01X-1316840Y471004D02*
X-1316882Y471324D01*
X-1317014Y471597D01*
X-1317234Y471797D01*
G01X-1318572Y513661D02*
Y489646D01*
G01X-1316446Y473901D02*
Y472720D01*
G01X-1315934D02*
Y473901D01*
G01X-1315462D02*
Y472720D01*
G01X-1315423D02*
Y473901D01*
G01X-1315003Y472720D02*
Y473901D01*
G01X-1314570D02*
Y472720D01*
G01Y471795D02*
Y472421D01*
G01X-1314320Y473901D02*
Y472720D01*
G01X-1314219Y472436D02*
Y473447D01*
G01X-1313297Y471752D02*
Y470866D01*
G01X-1310698Y471057D02*
Y471683D01*
G01X-1310305Y472261D02*
Y471635D01*
G01X-1310085Y472421D02*
Y471795D01*
G01X-1309911Y473901D02*
Y472096D01*
G01Y471015D02*
Y470389D01*
G01X-1309124Y473901D02*
Y472720D01*
G01X-1308730D02*
Y473901D01*
G01X-1318612Y470911D02*
X-1318578Y471093D01*
X-1318478Y471269D01*
X-1318316Y471430D01*
X-1318093Y471575D01*
X-1317826Y471691D01*
X-1317521Y471778D01*
X-1317191Y471831D01*
X-1316840Y471850D01*
G01X-1310085Y472421D02*
X-1310059Y472498D01*
X-1310030Y472582D01*
X-1310000Y472665D01*
X-1309970Y472746D01*
X-1309941Y472825D01*
X-1309911Y472902D01*
G01Y472096D02*
X-1309939Y472051D01*
X-1309967Y472005D01*
X-1309998Y471951D01*
X-1310026Y471903D01*
X-1310054Y471853D01*
X-1310085Y471795D01*
G01D02*
X-1310116Y471765D01*
X-1310150Y471735D01*
X-1310184Y471708D01*
X-1310223Y471681D01*
X-1310263Y471657D01*
X-1310305Y471635D01*
G01X-1316053Y471797D02*
X-1316276Y471593D01*
X-1316406Y471318D01*
X-1316446Y471004D01*
G01X-1314570Y472421D02*
X-1314765Y472256D01*
X-1314991Y472114D01*
X-1315238Y472000D01*
X-1315495Y471918D01*
X-1315770Y471867D01*
X-1316053Y471850D01*
G01X-1310305Y471635D02*
X-1310432Y471558D01*
X-1310540Y471459D01*
X-1310622Y471343D01*
X-1310675Y471218D01*
X-1310698Y471085D01*
X-1310689Y470950D01*
X-1310648Y470822D01*
X-1310578Y470701D01*
X-1310480Y470595D01*
X-1310361Y470509D01*
X-1310221Y470443D01*
X-1310070Y470403D01*
X-1309911Y470389D01*
G01X-1310305Y472261D02*
X-1310265Y472282D01*
X-1310225Y472306D01*
X-1310188Y472331D01*
X-1310152Y472359D01*
X-1310117Y472389D01*
X-1310085Y472421D01*
G01X-1316840Y473901D02*
G03X-1318612Y472129I0J-1772D01*
G01X-1316840Y472720D02*
G03X-1317431Y472129I0J-591D01*
G01X-1302824Y461702D02*
X-1302037D01*
G01Y461979D02*
X-1302824D01*
G01X-1302037Y461997D02*
X-1302824D01*
G01X-1302037Y462106D02*
X-1303021D01*
G01X-1299931Y467815D02*
X-1297568D01*
G01X-1299931Y471752D02*
Y467815D01*
G01X-1301643Y471635D02*
X-1301683Y471656D01*
X-1301724Y471680D01*
X-1301760Y471705D01*
X-1301797Y471733D01*
X-1301831Y471763D01*
X-1301863Y471795D01*
G01X-1301643Y472261D02*
X-1301517Y472184D01*
X-1301408Y472085D01*
X-1301326Y471969D01*
X-1301273Y471844D01*
X-1301250Y471711D01*
X-1301260Y471576D01*
X-1301300Y471448D01*
X-1301371Y471327D01*
X-1301469Y471220D01*
X-1301588Y471135D01*
X-1301727Y471069D01*
X-1301879Y471029D01*
X-1302037Y471015D01*
G01Y470389D02*
X-1301881Y470402D01*
X-1301730Y470442D01*
X-1301590Y470507D01*
X-1301471Y470593D01*
X-1301372Y470699D01*
X-1301301Y470820D01*
X-1301260Y470948D01*
X-1301250Y471083D01*
X-1301272Y471216D01*
X-1301325Y471341D01*
X-1301407Y471457D01*
X-1301515Y471556D01*
X-1301643Y471635D01*
G01X-1297378Y471795D02*
X-1301863D01*
G01Y472421D02*
X-1297378D01*
G01X-1301863D02*
X-1301833Y472391D01*
X-1301798Y472361D01*
X-1301764Y472334D01*
X-1301726Y472307D01*
X-1301685Y472283D01*
X-1301643Y472261D01*
G01X-1301863Y471795D02*
X-1301891Y471846D01*
X-1301918Y471895D01*
X-1301950Y471950D01*
X-1301978Y471998D01*
X-1302005Y472044D01*
X-1302037Y472096D01*
G01Y472902D02*
X-1302011Y472834D01*
X-1301981Y472755D01*
X-1301952Y472675D01*
X-1301922Y472592D01*
X-1301893Y472508D01*
X-1301863Y472421D01*
G01X-1303218Y473901D02*
Y472720D01*
G01X-1302824D02*
Y473901D01*
G01X-1302037D02*
Y472096D01*
G01Y470389D02*
Y471015D01*
G01X-1301863Y471795D02*
Y472421D01*
G01X-1301643Y472261D02*
Y471635D01*
G01X-1301250Y471057D02*
Y471683D01*
G01X-1303612Y551063D02*
Y513661D01*
G01X-1337495Y538740D02*
X-1338454D01*
G01X-1333017Y542334D02*
X-1337495D01*
G01Y543314D02*
X-1333017D01*
G01X-1338454Y546417D02*
X-1337495D01*
G01X-1339832Y557362D02*
X-1341407Y558271D01*
G01X-1361880Y563760D02*
Y556378D01*
G01X-1355777Y558445D02*
Y557657D01*
G01X-1354005Y555197D02*
Y554409D01*
G01X-1351446Y557657D02*
Y558445D01*
G01X-1350069Y558401D02*
Y559578D01*
G01Y555541D02*
Y556717D01*
G01X-1346919Y551063D02*
X-1303612D01*
G01X-1340226Y554409D02*
X-1346131D01*
G01X-1354005D02*
X-1359911D01*
G01X-1346131Y555197D02*
X-1354005D01*
G01X-1339045Y556772D02*
X-1342194D01*
G01X-1351446Y557657D02*
X-1355777D01*
G01Y558445D02*
X-1351446D01*
G01X-1346131Y555197D02*
Y554409D01*
G01X-1342194Y559921D02*
Y556772D01*
G01X-1339832Y559181D02*
Y557362D01*
G01X-1339045Y559921D02*
Y556772D01*
G01X-1338454Y538740D02*
Y546417D01*
G01X-1338257Y556378D02*
Y563760D01*
G01X-1337495Y546417D02*
Y543314D01*
G01Y542334D02*
Y538740D01*
G01X-1350068Y556717D02*
X-1349745Y556782D01*
X-1349473Y556964D01*
X-1349292Y557234D01*
X-1349227Y557556D01*
X-1349289Y557878D01*
X-1349470Y558151D01*
X-1349743Y558335D01*
X-1350068Y558401D01*
G01X-1339832Y559181D02*
X-1341407Y558271D01*
G01X-1347903Y557559D02*
G03I-2166J0D01*
G01X-1348050D02*
G03I-2019J0D01*
G01X-1361880Y556378D02*
G03X-1359911Y554409I1969J0D01*
G01X-1340226D02*
G03X-1338257Y556378I0J1969D01*
G01X-1351446Y557657D02*
G03X-1349872Y559221I-1J1575D01*
G01X-1357352Y559232D02*
G03X-1355777Y557657I1575J0D01*
G01X-1350068Y558401D02*
G03Y556717I-1J-842D01*
G01X-1351447Y558445D02*
G03X-1350659Y559227I1J787D01*
G01X-1356565Y559232D02*
G03X-1355777Y558445I787J0D01*
G01X-1347824Y563405D02*
X-1347037Y562618D01*
G01X-1339881Y567087D02*
X-1339959Y567103D01*
G01X-1339943Y567183D02*
X-1339896Y567166D01*
G01X-1339959Y567103D02*
X-1340021Y567151D01*
G01X-1339974Y567215D02*
X-1339943Y567183D01*
G01X-1340021Y567151D02*
X-1340068Y567215D01*
G01X-1340567Y567087D02*
X-1340956Y567724D01*
G01X-1340909Y567835D02*
X-1340520Y567183D01*
G01X-1360895Y586890D02*
Y585709D01*
G01Y580591D02*
Y579409D01*
G01Y583740D02*
Y582559D01*
G01Y577441D02*
Y576260D01*
G01Y574291D02*
Y573110D01*
G01Y571142D02*
Y569961D01*
G01Y567992D02*
Y566811D01*
G01X-1357352Y559232D02*
Y761398D01*
G01X-1356565D02*
Y559232D01*
G01X-1353100Y562618D02*
Y758012D01*
G01X-1353021Y586890D02*
Y585709D01*
G01Y583740D02*
Y582559D01*
G01Y580591D02*
Y579409D01*
G01Y577441D02*
Y576260D01*
G01Y574291D02*
Y573110D01*
G01Y571142D02*
Y569961D01*
G01Y567992D02*
Y566811D01*
G01X-1352313Y757224D02*
Y563405D01*
G01X-1357352Y559232D02*
X-1356565D01*
G01X-1339045Y559921D02*
X-1342194D01*
G01X-1344360Y560394D02*
X-1348691D01*
G01Y561181D02*
X-1344360D01*
G01X-1343572Y561968D02*
X-1342785D01*
G01X-1338257Y562185D02*
X-1361880D01*
G01X-1347037Y562618D02*
X-1353100D01*
G01X-1347824Y563405D02*
X-1352313D01*
G01X-1338257Y563760D02*
X-1343572D01*
G01X-1356565D02*
X-1361880D01*
G01X-1339242Y566811D02*
X-1347116D01*
G01X-1353021D02*
X-1360895D01*
G01X-1339507Y567087D02*
X-1339881D01*
G01X-1340208D02*
X-1340302D01*
G01X-1340956D02*
X-1341050D01*
G01X-1340426D02*
X-1340567D01*
G01X-1341268D02*
X-1341361D01*
G01X-1339896Y567166D02*
X-1339600D01*
G01Y567405D02*
X-1339896D01*
G01X-1339881Y567501D02*
X-1339600D01*
G01X-1341050Y567835D02*
X-1340909D01*
G01X-1340520D02*
X-1340426D01*
G01X-1341361D02*
X-1341268D01*
G01X-1339600D02*
X-1339507D01*
G01X-1340302D02*
X-1340208D01*
G01X-1339242Y567992D02*
X-1347116D01*
G01X-1353021D02*
X-1360895D01*
G01X-1339242Y569961D02*
X-1347116D01*
G01X-1353021D02*
X-1360895D01*
G01X-1339242Y571142D02*
X-1347116D01*
G01X-1353021D02*
X-1360895D01*
G01X-1339242Y573110D02*
X-1347116D01*
G01X-1353021D02*
X-1360895D01*
G01X-1339242Y574291D02*
X-1347116D01*
G01X-1353021D02*
X-1360895D01*
G01X-1339242Y576260D02*
X-1347116D01*
G01X-1353021D02*
X-1360895D01*
G01X-1339242Y577441D02*
X-1347116D01*
G01X-1353021D02*
X-1360895D01*
G01X-1339242Y579409D02*
X-1347116D01*
G01X-1353021D02*
X-1360895D01*
G01X-1339242Y580591D02*
X-1347116D01*
G01X-1353021D02*
X-1360895D01*
G01X-1339242Y582559D02*
X-1347116D01*
G01X-1353021D02*
X-1360895D01*
G01X-1339242Y583740D02*
X-1347116D01*
G01X-1353021D02*
X-1360895D01*
G01X-1339242Y585709D02*
X-1347116D01*
G01X-1353021D02*
X-1360895D01*
G01X-1339242Y586890D02*
X-1347116D01*
G01X-1353021D02*
X-1360895D01*
G01X-1349872Y559221D02*
X-1350659Y559227D01*
G01X-1340068Y567215D02*
X-1340083Y567262D01*
G01X-1339990D02*
X-1339974Y567215D01*
G01X-1348691Y561181D02*
Y560394D01*
G01X-1347824Y757224D02*
Y563405D01*
G01X-1347116Y586890D02*
Y585709D01*
G01Y583740D02*
Y582559D01*
G01Y580591D02*
Y579409D01*
G01Y577441D02*
Y576260D01*
G01Y574291D02*
Y573110D01*
G01Y571142D02*
Y569961D01*
G01Y567992D02*
Y566811D01*
G01X-1347037Y758012D02*
Y562618D01*
G01X-1344360Y560394D02*
Y561181D01*
G01X-1343572Y561968D02*
Y758661D01*
G01X-1342785Y561968D02*
Y758661D01*
G01X-1341361Y567087D02*
Y567835D01*
G01X-1341268D02*
Y567215D01*
G01X-1341174Y567326D02*
Y567198D01*
G01X-1341050Y567087D02*
Y567835D01*
G01X-1340956Y567724D02*
Y567087D01*
G01X-1340520Y567183D02*
Y567835D01*
G01X-1340426D02*
Y567087D01*
G01X-1340302D02*
Y567835D01*
G01X-1340208D02*
Y567087D01*
G01X-1340083Y567262D02*
Y567326D01*
G01X-1339990Y567310D02*
Y567262D01*
G01X-1339600Y567501D02*
Y567835D01*
G01Y567166D02*
Y567405D01*
G01X-1339507Y567835D02*
Y567087D01*
G01X-1339242Y586890D02*
Y585709D01*
G01Y583740D02*
Y582559D01*
G01Y580591D02*
Y579409D01*
G01Y577441D02*
Y576260D01*
G01Y574291D02*
Y573110D01*
G01Y571142D02*
Y569961D01*
G01Y567992D02*
Y566811D01*
G01X-1339959Y567485D02*
X-1339881Y567501D01*
G01X-1340083Y567326D02*
X-1340068Y567374D01*
G01X-1339974Y567358D02*
X-1339990Y567310D01*
G01X-1340068Y567374D02*
X-1340021Y567437D01*
G01X-1341268Y567215D02*
X-1341174Y567326D01*
G01Y567198D02*
X-1341268Y567087D01*
G01X-1339943Y567389D02*
X-1339974Y567358D01*
G01X-1353100Y562618D02*
X-1352313Y563405D01*
G01X-1340021Y567437D02*
X-1339959Y567485D01*
G01X-1339896Y567405D02*
X-1339943Y567389D01*
G01X-1348691Y561181D02*
G03X-1350659Y559227I0J-1968D01*
G01X-1344360Y560394D02*
G03X-1342785Y561968I0J1575D01*
G01X-1348691Y560394D02*
G03X-1349872Y559221I0J-1181D01*
G01X-1344360Y561181D02*
G03X-1343572Y561968I0J788D01*
G01X-1360895Y593189D02*
Y592008D01*
G01Y590039D02*
Y588858D01*
G01X-1353021Y593189D02*
Y592008D01*
G01Y590039D02*
Y588858D01*
G01X-1339242D02*
X-1347116D01*
G01X-1353021D02*
X-1360895D01*
G01X-1347116Y593189D02*
Y592008D01*
G01Y590039D02*
Y588858D01*
G01X-1339242Y593189D02*
Y592008D01*
G01Y590039D02*
Y588858D01*
G01Y590039D02*
X-1347116D01*
G01X-1353021D02*
X-1360895D01*
G01X-1339242Y592008D02*
X-1347116D01*
G01X-1353021D02*
X-1360895D01*
G01X-1325819Y539394D02*
X-1325019Y538904D01*
G01X-1322300Y545764D02*
X-1323100Y546254D01*
G01X-1325339Y540047D02*
X-1324859Y539720D01*
G01X-1322780Y545111D02*
X-1323260Y545437D01*
G01X-1326299Y539883D02*
X-1325819Y539394D01*
G01X-1306786Y538740D02*
X-1307586D01*
G01X-1309345D02*
X-1310145D01*
G01X-1311904D02*
X-1312704D01*
G01X-1313983D02*
X-1314783D01*
G01X-1319102D02*
X-1319901D01*
G01X-1316543D02*
X-1317342D01*
G01X-1332057D02*
X-1333017D01*
G01X-1328218Y541354D02*
X-1330777D01*
G01Y542007D02*
X-1328218D01*
G01X-1308226Y543314D02*
X-1308705D01*
G01X-1310785D02*
X-1311105D01*
G01X-1315423D02*
X-1315903D01*
G01X-1317982D02*
X-1318302D01*
G01X-1328218D02*
X-1330777D01*
G01Y543967D02*
X-1328218D01*
G01X-1319901D02*
X-1319102D01*
G01X-1318302D02*
X-1317662D01*
G01X-1315743D02*
X-1315103D01*
G01X-1312704D02*
X-1311904D01*
G01X-1311105D02*
X-1310465D01*
G01X-1308546D02*
X-1307906D01*
G01X-1333017Y546417D02*
X-1332057D01*
G01X-1325019Y538904D02*
X-1324060Y538740D01*
G01X-1323100Y546254D02*
X-1324060Y546417D01*
G01X-1324859Y539720D02*
X-1324060Y539557D01*
G01X-1323260Y545437D02*
X-1324060Y545601D01*
G01X-1317662Y543967D02*
X-1317182Y543804D01*
G01X-1315103Y543967D02*
X-1314623Y543804D01*
G01X-1310465Y543967D02*
X-1309985Y543804D01*
G01X-1307906Y543967D02*
X-1307426Y543804D01*
G01X-1317662Y543150D02*
X-1317982Y543314D01*
G01X-1315103Y543150D02*
X-1315423Y543314D01*
G01X-1310465Y543150D02*
X-1310785Y543314D01*
G01X-1307906Y543150D02*
X-1308226Y543314D01*
G01X-1321820Y545274D02*
X-1322300Y545764D01*
G01X-1317502Y542987D02*
X-1317662Y543150D01*
G01X-1317182Y543804D02*
X-1316702Y543314D01*
G01X-1314943Y542987D02*
X-1315103Y543150D01*
G01X-1314623Y543804D02*
X-1314304Y543477D01*
G01X-1310305Y542987D02*
X-1310465Y543150D01*
G01X-1309985Y543804D02*
X-1309505Y543314D01*
G01X-1307746Y542987D02*
X-1307906Y543150D01*
G01X-1307426Y543804D02*
X-1307106Y543477D01*
G01X-1325979Y541027D02*
X-1325339Y540047D01*
G01X-1322141Y544131D02*
X-1322780Y545111D01*
G01X-1326619Y540537D02*
X-1326299Y539883D01*
G01X-1321501Y544620D02*
X-1321820Y545274D01*
G01X-1317342Y542661D02*
X-1317502Y542987D01*
G01X-1314783Y542661D02*
X-1314943Y542987D01*
G01X-1324060Y539557D02*
X-1323260Y539720D01*
G01X-1324060Y545601D02*
X-1324859Y545437D01*
G01X-1324060Y538740D02*
X-1323100Y538904D01*
G01X-1324060Y546417D02*
X-1325019Y546254D01*
G01X-1310145Y542661D02*
X-1310305Y542987D01*
G01X-1307586Y542661D02*
X-1307746Y542987D01*
G01X-1314304Y543477D02*
X-1313983Y542661D01*
G01X-1307106Y543477D02*
X-1306786Y542661D01*
G01X-1326779Y541027D02*
X-1326619Y540537D01*
G01X-1321341Y544131D02*
X-1321501Y544620D01*
G01X-1326939Y541844D02*
X-1326779Y541027D01*
G01X-1321181Y543314D02*
X-1321341Y544131D01*
G01X-1326139Y542007D02*
X-1325979Y541027D01*
G01X-1321981Y543150D02*
X-1322141Y544131D01*
G01X-1333017Y538740D02*
Y542334D01*
G01Y543314D02*
Y546417D01*
G01X-1332057D02*
Y538740D01*
G01X-1330777Y543314D02*
Y543967D01*
G01Y541354D02*
Y542007D01*
G01X-1328218Y543967D02*
Y543314D01*
G01Y542007D02*
Y541354D01*
G01X-1326939Y543314D02*
Y541844D01*
G01X-1326139Y543150D02*
Y542007D01*
G01X-1321981D02*
Y543150D01*
G01X-1321181Y541844D02*
Y543314D01*
G01X-1319901Y538740D02*
Y543967D01*
G01X-1319102D02*
Y543477D01*
G01Y542824D02*
Y538740D01*
G01X-1318572Y769567D02*
Y551063D01*
G01X-1317342Y538740D02*
Y542661D01*
G01X-1316543D02*
Y538740D01*
G01X-1314783D02*
Y542661D01*
G01X-1313983D02*
Y538740D01*
G01X-1312704D02*
Y543967D01*
G01X-1311904D02*
Y543477D01*
G01Y542824D02*
Y538740D01*
G01X-1310145D02*
Y542661D01*
G01X-1309345D02*
Y538740D01*
G01X-1307586D02*
Y542661D01*
G01X-1306786D02*
Y538740D01*
G01X-1325979Y544131D02*
X-1326139Y543150D01*
G01X-1322141Y541027D02*
X-1321981Y542007D01*
G01X-1326779Y544131D02*
X-1326939Y543314D01*
G01X-1321341Y541027D02*
X-1321181Y541844D01*
G01X-1326619Y544620D02*
X-1326779Y544131D01*
G01X-1321501Y540537D02*
X-1321341Y541027D01*
G01X-1326299Y545274D02*
X-1326619Y544620D01*
G01X-1321820Y539883D02*
X-1321501Y540537D01*
G01X-1316383Y542987D02*
X-1316543Y542661D01*
G01X-1309185Y542987D02*
X-1309345Y542661D01*
G01X-1325339Y545111D02*
X-1325979Y544131D01*
G01X-1322780Y540047D02*
X-1322141Y541027D01*
G01X-1325819Y545764D02*
X-1326299Y545274D01*
G01X-1319102Y543477D02*
X-1318782Y543804D01*
G01Y543150D02*
X-1319102Y542824D01*
G01X-1322300Y539394D02*
X-1321820Y539883D01*
G01X-1316702Y543314D02*
X-1316223Y543804D01*
G01Y543150D02*
X-1316383Y542987D01*
G01X-1311904Y543477D02*
X-1311584Y543804D01*
G01Y543150D02*
X-1311904Y542824D01*
G01X-1309505Y543314D02*
X-1309025Y543804D01*
G01Y543150D02*
X-1309185Y542987D01*
G01X-1324859Y545437D02*
X-1325339Y545111D01*
G01X-1323260Y539720D02*
X-1322780Y540047D01*
G01X-1325019Y546254D02*
X-1325819Y545764D01*
G01X-1323100Y538904D02*
X-1322300Y539394D01*
G01X-1315903Y543314D02*
X-1316223Y543150D01*
G01X-1308705Y543314D02*
X-1309025Y543150D01*
G01X-1318782Y543804D02*
X-1318302Y543967D01*
G01Y543314D02*
X-1318782Y543150D01*
G01X-1316223Y543804D02*
X-1315743Y543967D01*
G01X-1311584Y543804D02*
X-1311105Y543967D01*
G01Y543314D02*
X-1311584Y543150D01*
G01X-1309025Y543804D02*
X-1308546Y543967D01*
G01X-1360895Y618386D02*
Y617205D01*
G01Y615236D02*
Y614055D01*
G01Y612087D02*
Y610905D01*
G01Y608937D02*
Y607756D01*
G01Y605787D02*
Y604606D01*
G01Y602638D02*
Y601457D01*
G01Y599488D02*
Y598307D01*
G01Y596339D02*
Y595157D01*
G01X-1353021Y618386D02*
Y617205D01*
G01Y615236D02*
Y614055D01*
G01Y612087D02*
Y610905D01*
G01Y608937D02*
Y607756D01*
G01Y605787D02*
Y604606D01*
G01Y602638D02*
Y601457D01*
G01Y599488D02*
Y598307D01*
G01Y596339D02*
Y595157D01*
G01X-1347116Y618386D02*
Y617205D01*
G01Y615236D02*
Y614055D01*
G01Y612087D02*
Y610905D01*
G01Y608937D02*
Y607756D01*
G01Y605787D02*
Y604606D01*
G01Y602638D02*
Y601457D01*
G01Y599488D02*
Y598307D01*
G01Y596339D02*
Y595157D01*
G01X-1339242Y618386D02*
Y617205D01*
G01Y615236D02*
Y614055D01*
G01Y612087D02*
Y610905D01*
G01Y608937D02*
Y607756D01*
G01Y605787D02*
Y604606D01*
G01Y602638D02*
Y601457D01*
G01Y599488D02*
Y598307D01*
G01Y596339D02*
Y595157D01*
G01Y593189D02*
X-1347116D01*
G01X-1353021D02*
X-1360895D01*
G01X-1339242Y595157D02*
X-1347116D01*
G01X-1353021D02*
X-1360895D01*
G01X-1339242Y596339D02*
X-1347116D01*
G01X-1353021D02*
X-1360895D01*
G01X-1339242Y598307D02*
X-1347116D01*
G01X-1353021D02*
X-1360895D01*
G01X-1339242Y599488D02*
X-1347116D01*
G01X-1353021D02*
X-1360895D01*
G01X-1339242Y601457D02*
X-1347116D01*
G01X-1353021D02*
X-1360895D01*
G01X-1339242Y602638D02*
X-1347116D01*
G01X-1353021D02*
X-1360895D01*
G01X-1339242Y604606D02*
X-1347116D01*
G01X-1353021D02*
X-1360895D01*
G01X-1339242Y605787D02*
X-1347116D01*
G01X-1353021D02*
X-1360895D01*
G01X-1339242Y607756D02*
X-1347116D01*
G01X-1353021D02*
X-1360895D01*
G01X-1339242Y608937D02*
X-1347116D01*
G01X-1353021D02*
X-1360895D01*
G01X-1339242Y610905D02*
X-1347116D01*
G01X-1353021D02*
X-1360895D01*
G01X-1339242Y612087D02*
X-1347116D01*
G01X-1353021D02*
X-1360895D01*
G01X-1339242Y614055D02*
X-1347116D01*
G01X-1353021D02*
X-1360895D01*
G01X-1339242Y615236D02*
X-1347116D01*
G01X-1353021D02*
X-1360895D01*
G01X-1339242Y617205D02*
X-1347116D01*
G01X-1353021D02*
X-1360895D01*
G01X-1339242Y618386D02*
X-1347116D01*
G01X-1353021D02*
X-1360895D01*
G01Y649882D02*
Y648701D01*
G01Y643583D02*
Y642402D01*
G01Y646732D02*
Y645551D01*
G01Y640433D02*
Y639252D01*
G01Y637283D02*
Y636102D01*
G01Y634134D02*
Y632953D01*
G01Y630984D02*
Y629803D01*
G01Y627835D02*
Y626654D01*
G01Y624685D02*
Y623504D01*
G01Y621535D02*
Y620354D01*
G01X-1353021Y649882D02*
Y648701D01*
G01Y646732D02*
Y645551D01*
G01Y643583D02*
Y642402D01*
G01Y640433D02*
Y639252D01*
G01Y637283D02*
Y636102D01*
G01Y634134D02*
Y632953D01*
G01Y630984D02*
Y629803D01*
G01Y627835D02*
Y626654D01*
G01Y624685D02*
Y623504D01*
G01Y621535D02*
Y620354D01*
G01X-1347116Y649882D02*
Y648701D01*
G01Y646732D02*
Y645551D01*
G01Y643583D02*
Y642402D01*
G01Y640433D02*
Y639252D01*
G01Y637283D02*
Y636102D01*
G01Y634134D02*
Y632953D01*
G01Y630984D02*
Y629803D01*
G01Y627835D02*
Y626654D01*
G01Y624685D02*
Y623504D01*
G01Y621535D02*
Y620354D01*
G01X-1339242Y649882D02*
Y648701D01*
G01Y646732D02*
Y645551D01*
G01Y643583D02*
Y642402D01*
G01Y640433D02*
Y639252D01*
G01Y637283D02*
Y636102D01*
G01Y634134D02*
Y632953D01*
G01Y630984D02*
Y629803D01*
G01Y627835D02*
Y626654D01*
G01Y624685D02*
Y623504D01*
G01Y621535D02*
Y620354D01*
G01D02*
X-1347116D01*
G01X-1353021D02*
X-1360895D01*
G01X-1342785Y620945D02*
X-1343572D01*
G01X-1356565D02*
X-1357352D01*
G01X-1339242Y621535D02*
X-1347116D01*
G01X-1353021D02*
X-1360895D01*
G01X-1339242Y623504D02*
X-1347116D01*
G01X-1353021D02*
X-1360895D01*
G01X-1339242Y624685D02*
X-1347116D01*
G01X-1353021D02*
X-1360895D01*
G01X-1339242Y626654D02*
X-1347116D01*
G01X-1353021D02*
X-1360895D01*
G01X-1342785Y627244D02*
X-1343572D01*
G01X-1356565D02*
X-1357352D01*
G01X-1339242Y627835D02*
X-1347116D01*
G01X-1353021D02*
X-1360895D01*
G01X-1339242Y629803D02*
X-1347116D01*
G01X-1353021D02*
X-1360895D01*
G01X-1339242Y630984D02*
X-1347116D01*
G01X-1353021D02*
X-1360895D01*
G01X-1339242Y632953D02*
X-1347116D01*
G01X-1353021D02*
X-1360895D01*
G01X-1339242Y634134D02*
X-1347116D01*
G01X-1353021D02*
X-1360895D01*
G01X-1339242Y636102D02*
X-1347116D01*
G01X-1353021D02*
X-1360895D01*
G01X-1342785Y636693D02*
X-1343572D01*
G01X-1356565D02*
X-1357352D01*
G01X-1339242Y637283D02*
X-1347116D01*
G01X-1353021D02*
X-1360895D01*
G01X-1339242Y639252D02*
X-1347116D01*
G01X-1353021D02*
X-1360895D01*
G01X-1339242Y640433D02*
X-1347116D01*
G01X-1353021D02*
X-1360895D01*
G01X-1339242Y642402D02*
X-1347116D01*
G01X-1353021D02*
X-1360895D01*
G01X-1342785Y642992D02*
X-1343572D01*
G01X-1356565D02*
X-1357352D01*
G01X-1339242Y643583D02*
X-1347116D01*
G01X-1353021D02*
X-1360895D01*
G01X-1339242Y645551D02*
X-1347116D01*
G01X-1353021D02*
X-1360895D01*
G01X-1339242Y646732D02*
X-1347116D01*
G01X-1353021D02*
X-1360895D01*
G01X-1339242Y648701D02*
X-1347116D01*
G01X-1353021D02*
X-1360895D01*
G01Y659331D02*
Y658150D01*
G01Y656181D02*
Y655000D01*
G01Y653031D02*
Y651850D01*
G01X-1356525Y660987D02*
Y656349D01*
G01Y655398D02*
Y654684D01*
G01X-1353021Y659331D02*
Y658150D01*
G01Y656181D02*
Y655000D01*
G01Y653031D02*
Y651850D01*
G01X-1347116Y659331D02*
Y658150D01*
G01Y656181D02*
Y655000D01*
G01Y653031D02*
Y651850D01*
G01X-1339242Y659331D02*
Y658150D01*
G01Y656181D02*
Y655000D01*
G01Y653031D02*
Y651850D01*
G01Y649882D02*
X-1347116D01*
G01X-1353021D02*
X-1360895D01*
G01X-1339242Y651850D02*
X-1347116D01*
G01X-1353021D02*
X-1360895D01*
G01X-1339242Y653031D02*
X-1347116D01*
G01X-1353021D02*
X-1360895D01*
G01X-1356525Y654684D02*
X-1356565D01*
G01X-1339242Y655000D02*
X-1347116D01*
G01X-1353021D02*
X-1360895D01*
G01X-1356525Y655398D02*
X-1356565D01*
G01X-1339242Y656181D02*
X-1347116D01*
G01X-1353021D02*
X-1360895D01*
G01X-1356525Y656349D02*
X-1356565D01*
G01X-1356525Y656468D02*
X-1356565D01*
G01X-1356525Y656944D02*
X-1356565D01*
G01X-1356525Y657063D02*
X-1356565D01*
G01X-1356525Y657182D02*
X-1356565D01*
G01X-1356525Y657420D02*
X-1356565D01*
G01X-1356525Y657539D02*
X-1356565D01*
G01X-1356525Y658014D02*
X-1356565D01*
G01X-1339242Y658150D02*
X-1347116D01*
G01X-1353021D02*
X-1360895D01*
G01Y678228D02*
Y677047D01*
G01Y675079D02*
Y673898D01*
G01Y671929D02*
Y670748D01*
G01Y668779D02*
Y667598D01*
G01Y665630D02*
Y664449D01*
G01Y662480D02*
Y661299D01*
G01X-1356525Y666220D02*
Y661939D01*
G01X-1353021Y678228D02*
Y677047D01*
G01Y675079D02*
Y673898D01*
G01Y671929D02*
Y670748D01*
G01Y668779D02*
Y667598D01*
G01Y665630D02*
Y664449D01*
G01Y662480D02*
Y661299D01*
G01X-1347116Y678228D02*
Y677047D01*
G01Y675079D02*
Y673898D01*
G01Y671929D02*
Y670748D01*
G01Y668779D02*
Y667598D01*
G01Y665630D02*
Y664449D01*
G01Y662480D02*
Y661299D01*
G01X-1339242Y678228D02*
Y677047D01*
G01Y675079D02*
Y673898D01*
G01Y671929D02*
Y670748D01*
G01Y668779D02*
Y667598D01*
G01Y665630D02*
Y664449D01*
G01Y662480D02*
Y661299D01*
G01X-1356525Y659085D02*
X-1356565D01*
G01X-1339242Y659331D02*
X-1347116D01*
G01X-1353021D02*
X-1360895D01*
G01X-1356525Y659560D02*
X-1356565D01*
G01X-1356525Y659679D02*
X-1356565D01*
G01X-1356525Y659917D02*
X-1356565D01*
G01X-1356525Y660155D02*
X-1356565D01*
G01X-1356525Y660274D02*
X-1356565D01*
G01X-1356525Y660631D02*
X-1356565D01*
G01X-1356525Y660868D02*
X-1356565D01*
G01X-1356525Y660987D02*
X-1356565D01*
G01X-1339242Y661299D02*
X-1347116D01*
G01X-1353021D02*
X-1360895D01*
G01X-1356525Y661939D02*
X-1356565D01*
G01X-1356525Y662415D02*
X-1356565D01*
G01X-1339242Y662480D02*
X-1347116D01*
G01X-1353021D02*
X-1360895D01*
G01X-1339242Y664449D02*
X-1347116D01*
G01X-1353021D02*
X-1360895D01*
G01X-1356525Y665507D02*
X-1356565D01*
G01X-1339242Y665630D02*
X-1347116D01*
G01X-1353021D02*
X-1360895D01*
G01X-1356525Y666220D02*
X-1356565D01*
G01X-1339242Y667598D02*
X-1347116D01*
G01X-1353021D02*
X-1360895D01*
G01X-1339242Y668779D02*
X-1347116D01*
G01X-1353021D02*
X-1360895D01*
G01X-1339242Y670748D02*
X-1347116D01*
G01X-1353021D02*
X-1360895D01*
G01X-1339242Y671929D02*
X-1347116D01*
G01X-1353021D02*
X-1360895D01*
G01X-1339242Y673898D02*
X-1347116D01*
G01X-1353021D02*
X-1360895D01*
G01X-1339242Y675079D02*
X-1347116D01*
G01X-1353021D02*
X-1360895D01*
G01X-1339242Y677047D02*
X-1347116D01*
G01X-1353021D02*
X-1360895D01*
G01X-1356565Y677638D02*
X-1357352D01*
G01X-1343572D02*
X-1342785D01*
G01X-1339242Y678228D02*
X-1347116D01*
G01X-1353021D02*
X-1360895D01*
G01Y709724D02*
Y708543D01*
G01Y706575D02*
Y705394D01*
G01Y703425D02*
Y702244D01*
G01Y700276D02*
Y699094D01*
G01Y697126D02*
Y695945D01*
G01Y693976D02*
Y692795D01*
G01Y690827D02*
Y689646D01*
G01Y687677D02*
Y686496D01*
G01Y684528D02*
Y683346D01*
G01Y681378D02*
Y680197D01*
G01X-1353021Y709724D02*
Y708543D01*
G01Y706575D02*
Y705394D01*
G01Y703425D02*
Y702244D01*
G01Y700276D02*
Y699094D01*
G01Y697126D02*
Y695945D01*
G01Y693976D02*
Y692795D01*
G01Y690827D02*
Y689646D01*
G01Y687677D02*
Y686496D01*
G01Y684528D02*
Y683346D01*
G01Y681378D02*
Y680197D01*
G01X-1347116Y709724D02*
Y708543D01*
G01Y706575D02*
Y705394D01*
G01Y703425D02*
Y702244D01*
G01Y700276D02*
Y699094D01*
G01Y697126D02*
Y695945D01*
G01Y693976D02*
Y692795D01*
G01Y690827D02*
Y689646D01*
G01Y687677D02*
Y686496D01*
G01Y684528D02*
Y683346D01*
G01Y681378D02*
Y680197D01*
G01X-1339242Y709724D02*
Y708543D01*
G01Y706575D02*
Y705394D01*
G01Y703425D02*
Y702244D01*
G01Y700276D02*
Y699094D01*
G01Y697126D02*
Y695945D01*
G01Y693976D02*
Y692795D01*
G01Y690827D02*
Y689646D01*
G01Y687677D02*
Y686496D01*
G01Y684528D02*
Y683346D01*
G01Y681378D02*
Y680197D01*
G01D02*
X-1347116D01*
G01X-1353021D02*
X-1360895D01*
G01X-1339242Y681378D02*
X-1347116D01*
G01X-1353021D02*
X-1360895D01*
G01X-1339242Y683346D02*
X-1347116D01*
G01X-1353021D02*
X-1360895D01*
G01X-1342785Y683937D02*
X-1343572D01*
G01X-1356565D02*
X-1357352D01*
G01X-1339242Y684528D02*
X-1347116D01*
G01X-1353021D02*
X-1360895D01*
G01X-1339242Y686496D02*
X-1347116D01*
G01X-1353021D02*
X-1360895D01*
G01X-1339242Y687677D02*
X-1347116D01*
G01X-1353021D02*
X-1360895D01*
G01X-1339242Y689646D02*
X-1347116D01*
G01X-1353021D02*
X-1360895D01*
G01X-1339242Y690827D02*
X-1347116D01*
G01X-1353021D02*
X-1360895D01*
G01X-1339242Y692795D02*
X-1347116D01*
G01X-1353021D02*
X-1360895D01*
G01X-1356565Y693386D02*
X-1357352D01*
G01X-1343572D02*
X-1342785D01*
G01X-1339242Y693976D02*
X-1347116D01*
G01X-1353021D02*
X-1360895D01*
G01X-1339242Y695945D02*
X-1347116D01*
G01X-1353021D02*
X-1360895D01*
G01X-1339242Y697126D02*
X-1347116D01*
G01X-1353021D02*
X-1360895D01*
G01X-1339242Y699094D02*
X-1347116D01*
G01X-1353021D02*
X-1360895D01*
G01X-1342785Y699685D02*
X-1343572D01*
G01X-1357352D02*
X-1356565D01*
G01X-1339242Y700276D02*
X-1347116D01*
G01X-1353021D02*
X-1360895D01*
G01X-1339242Y702244D02*
X-1347116D01*
G01X-1353021D02*
X-1360895D01*
G01X-1339242Y703425D02*
X-1347116D01*
G01X-1353021D02*
X-1360895D01*
G01X-1339242Y705394D02*
X-1347116D01*
G01X-1353021D02*
X-1360895D01*
G01X-1339242Y706575D02*
X-1347116D01*
G01X-1353021D02*
X-1360895D01*
G01X-1339242Y708543D02*
X-1347116D01*
G01X-1353021D02*
X-1360895D01*
G01Y722323D02*
Y721142D01*
G01Y719173D02*
Y717992D01*
G01Y716024D02*
Y714842D01*
G01Y712874D02*
Y711693D01*
G01X-1353021Y722323D02*
Y721142D01*
G01Y719173D02*
Y717992D01*
G01Y716024D02*
Y714842D01*
G01Y712874D02*
Y711693D01*
G01X-1347116Y722323D02*
Y721142D01*
G01Y719173D02*
Y717992D01*
G01Y716024D02*
Y714842D01*
G01Y712874D02*
Y711693D01*
G01X-1339242Y722323D02*
Y721142D01*
G01Y719173D02*
Y717992D01*
G01Y716024D02*
Y714842D01*
G01Y712874D02*
Y711693D01*
G01Y709724D02*
X-1347116D01*
G01X-1353021D02*
X-1360895D01*
G01X-1339242Y711693D02*
X-1347116D01*
G01X-1353021D02*
X-1360895D01*
G01X-1339242Y712874D02*
X-1347116D01*
G01X-1353021D02*
X-1360895D01*
G01X-1339242Y714842D02*
X-1347116D01*
G01X-1353021D02*
X-1360895D01*
G01X-1339242Y716024D02*
X-1347116D01*
G01X-1353021D02*
X-1360895D01*
G01X-1339242Y717992D02*
X-1347116D01*
G01X-1353021D02*
X-1360895D01*
G01X-1339242Y719173D02*
X-1347116D01*
G01X-1353021D02*
X-1360895D01*
G01X-1339242Y721142D02*
X-1347116D01*
G01X-1353021D02*
X-1360895D01*
G01X-1339242Y722323D02*
X-1347116D01*
G01X-1353021D02*
X-1360895D01*
G01Y738071D02*
Y736890D01*
G01Y734921D02*
Y733740D01*
G01Y731772D02*
Y730591D01*
G01Y728622D02*
Y727441D01*
G01Y725472D02*
Y724291D01*
G01X-1353021Y738071D02*
Y736890D01*
G01Y734921D02*
Y733740D01*
G01Y731772D02*
Y730591D01*
G01Y728622D02*
Y727441D01*
G01Y725472D02*
Y724291D01*
G01X-1347116Y738071D02*
Y736890D01*
G01Y734921D02*
Y733740D01*
G01Y731772D02*
Y730591D01*
G01Y728622D02*
Y727441D01*
G01Y725472D02*
Y724291D01*
G01X-1339242Y738071D02*
Y736890D01*
G01Y734921D02*
Y733740D01*
G01Y731772D02*
Y730591D01*
G01Y728622D02*
Y727441D01*
G01Y725472D02*
Y724291D01*
G01D02*
X-1347116D01*
G01X-1353021D02*
X-1360895D01*
G01X-1339242Y725472D02*
X-1347116D01*
G01X-1353021D02*
X-1360895D01*
G01X-1339242Y727441D02*
X-1347116D01*
G01X-1353021D02*
X-1360895D01*
G01X-1339242Y728622D02*
X-1347116D01*
G01X-1353021D02*
X-1360895D01*
G01X-1339242Y730591D02*
X-1347116D01*
G01X-1353021D02*
X-1360895D01*
G01X-1339242Y731772D02*
X-1347116D01*
G01X-1353021D02*
X-1360895D01*
G01X-1339242Y733740D02*
X-1347116D01*
G01X-1353021D02*
X-1360895D01*
G01X-1339242Y734921D02*
X-1347116D01*
G01X-1353021D02*
X-1360895D01*
G01X-1339242Y736890D02*
X-1347116D01*
G01X-1353021D02*
X-1360895D01*
G01X-1339242Y738071D02*
X-1347116D01*
G01X-1353021D02*
X-1360895D01*
G01X-1361880Y764252D02*
Y756870D01*
G01X-1360895Y753819D02*
Y752638D01*
G01Y750669D02*
Y749488D01*
G01Y747520D02*
Y746339D01*
G01Y744370D02*
Y743189D01*
G01Y741220D02*
Y740039D01*
G01X-1355777Y762972D02*
Y762185D01*
G01X-1354005Y766220D02*
Y765433D01*
G01X-1353021Y753819D02*
Y752638D01*
G01Y750669D02*
Y749488D01*
G01Y747520D02*
Y746339D01*
G01Y744370D02*
Y743189D01*
G01Y741220D02*
Y740039D01*
G01X-1351446Y762185D02*
Y762972D01*
G01X-1348691Y760236D02*
Y759449D01*
G01X-1347116Y753819D02*
Y752638D01*
G01Y750669D02*
Y749488D01*
G01Y747520D02*
Y746339D01*
G01Y744370D02*
Y743189D01*
G01Y741220D02*
Y740039D01*
G01X-1346131Y766220D02*
Y765433D01*
G01X-1344360Y759449D02*
Y760236D01*
G01X-1339242Y753819D02*
Y752638D01*
G01Y750669D02*
Y749488D01*
G01Y747520D02*
Y746339D01*
G01Y744370D02*
Y743189D01*
G01Y741220D02*
Y740039D01*
G01X-1338257Y756870D02*
Y764252D01*
G01X-1347037Y758012D02*
X-1347824Y757224D01*
G01X-1352313D02*
X-1353100Y758012D01*
G01X-1339242Y740039D02*
X-1347116D01*
G01X-1353021D02*
X-1360895D01*
G01X-1339242Y741220D02*
X-1347116D01*
G01X-1353021D02*
X-1360895D01*
G01X-1339242Y743189D02*
X-1347116D01*
G01X-1353021D02*
X-1360895D01*
G01X-1339242Y744370D02*
X-1347116D01*
G01X-1353021D02*
X-1360895D01*
G01X-1339242Y746339D02*
X-1347116D01*
G01X-1353021D02*
X-1360895D01*
G01X-1339242Y747520D02*
X-1347116D01*
G01X-1353021D02*
X-1360895D01*
G01X-1339242Y749488D02*
X-1347116D01*
G01X-1353021D02*
X-1360895D01*
G01X-1339242Y750669D02*
X-1347116D01*
G01X-1353021D02*
X-1360895D01*
G01X-1350659Y761403D02*
X-1349872Y761409D01*
G01X-1339242Y752638D02*
X-1347116D01*
G01X-1353021D02*
X-1360895D01*
G01X-1339242Y753819D02*
X-1347116D01*
G01X-1353021D02*
X-1360895D01*
G01X-1338257Y756870D02*
X-1343572D01*
G01X-1356565D02*
X-1361880D01*
G01X-1347824Y757224D02*
X-1352313D01*
G01X-1353100Y758012D02*
X-1347037D01*
G01X-1338257Y758445D02*
X-1361880D01*
G01X-1342785Y758661D02*
X-1343572D01*
G01X-1344360Y759449D02*
X-1348691D01*
G01X-1344360Y760236D02*
X-1348691D01*
G01X-1356565Y761398D02*
X-1357352D01*
G01X-1351446Y762185D02*
X-1355777D01*
G01X-1351446Y762972D02*
X-1355777D01*
G01X-1346131Y765433D02*
X-1354005D01*
G01X-1340226Y766220D02*
X-1346131D01*
G01X-1354005D02*
X-1359911D01*
G01D02*
G03X-1361880Y764252I-1J-1968D01*
G01X-1338257D02*
G03X-1340226Y766220I-1969J-1D01*
G01X-1348100Y763071D02*
G03I-1969J0D01*
G01X-1350659Y761403D02*
G03X-1348691Y759449I1968J14D01*
G01X-1349872Y761409D02*
G03X-1351446Y762972I-1575J-12D01*
G01X-1355777D02*
G03X-1357352Y761398I0J-1575D01*
G01X-1342785Y758661D02*
G03X-1344360Y760236I-1575J0D01*
G01X-1348691Y763071D02*
G03I-1378J0D01*
G01X-1348852D02*
G03I-1217J0D01*
G01X-1349872Y761409D02*
G03X-1348691Y760236I1181J8D01*
G01X-1350659Y761403D02*
G03X-1351447Y762185I-787J-5D01*
G01X-1355777D02*
G03X-1356565Y761398I-1J-787D01*
G01X-1343572Y758661D02*
G03X-1344360Y759449I-788J0D01*
G01X-1336092Y788268D02*
X-1199375D01*
G01X-1291013Y769567D02*
X-1346722D01*
G01X-1340029Y781575D02*
X-1353415D01*
G01X-1340029D02*
G03Y794961I0J6693D01*
G01X-1353415D02*
G03Y781575I0J-6693D01*
G01X-1340108Y796693D02*
Y804370D01*
G01X-1339148Y800287D02*
Y796693D01*
G01X-1334670D02*
Y800287D01*
G01X-1340029Y794961D02*
X-1353415D01*
G01X-1333710Y796693D02*
X-1334670D01*
G01X-1339148D02*
X-1340108D01*
G01X-1346722Y798898D02*
Y913294D01*
G01X-1339148Y804370D02*
Y801266D01*
G01X-1334670D02*
Y804370D01*
G01Y800287D02*
X-1339148D01*
G01Y801266D02*
X-1334670D01*
G01X-1340108Y804370D02*
X-1339148D01*
G01X-1334670D02*
X-1333710D01*
G01X-1346722Y806968D02*
X-1291013D01*
G01X-1322313Y847126D02*
G03I-18701J0D01*
G01X-1337076D02*
X-1315470D01*
G01X-1341013Y851063D02*
Y876716D01*
G01X-1334124Y847126D02*
G03I-6890J0D01*
G01X-1333710Y804370D02*
Y796693D01*
G01X-1321555D02*
Y801920D01*
G01X-1320755Y800776D02*
Y796693D01*
G01X-1318996D02*
Y800613D01*
G01X-1318196D02*
Y796693D01*
G01X-1316437D02*
Y800613D01*
G01X-1315637D02*
Y796693D01*
G01X-1314357D02*
Y801920D01*
G01X-1313558Y800776D02*
Y796693D01*
G01X-1311798D02*
Y800613D01*
G01X-1310999D02*
Y796693D01*
G01X-1323154Y798490D02*
X-1322994Y798980D01*
G01X-1323474Y797836D02*
X-1323154Y798490D01*
G01X-1324434Y798000D02*
X-1323794Y798980D01*
G01X-1323954Y797346D02*
X-1323474Y797836D01*
G01X-1324914Y797673D02*
X-1324434Y798000D01*
G01X-1309239Y796693D02*
Y800613D01*
G01X-1308440D02*
Y796693D01*
G01X-1324754Y796856D02*
X-1323954Y797346D01*
G01X-1327633Y798980D02*
X-1326993Y798000D01*
G01X-1328272Y798490D02*
X-1327952Y797836D01*
G01X-1328432Y798980D02*
X-1328272Y798490D01*
G01X-1327952Y797836D02*
X-1327473Y797346D01*
G01D02*
X-1326673Y796856D01*
G01X-1326993Y798000D02*
X-1326513Y797673D01*
G01X-1326673Y796856D02*
X-1325713Y796693D01*
G01X-1326513Y797673D02*
X-1325713Y797510D01*
G01D02*
X-1324914Y797673D01*
G01X-1325713Y796693D02*
X-1324754Y796856D01*
G01X-1308440Y796693D02*
X-1309239D01*
G01X-1310999D02*
X-1311798D01*
G01X-1315637D02*
X-1316437D01*
G01X-1313558D02*
X-1314357D01*
G01X-1318196D02*
X-1318996D01*
G01X-1320755D02*
X-1321555D01*
G01X-1332431Y801266D02*
Y801920D01*
G01Y799306D02*
Y799960D01*
G01X-1329872Y801920D02*
Y801266D01*
G01Y799960D02*
Y799306D01*
G01X-1328592Y801266D02*
Y799796D01*
G01X-1327793Y801103D02*
Y799960D01*
G01X-1323634D02*
Y801103D01*
G01X-1322834Y799796D02*
Y801266D01*
G01X-1320755Y801920D02*
Y801430D01*
G01X-1318572Y819764D02*
Y806968D01*
G01X-1313558Y801920D02*
Y801430D01*
G01X-1327633Y802083D02*
X-1327793Y801103D01*
G01X-1323794Y798980D02*
X-1323634Y799960D01*
G01X-1328432Y802083D02*
X-1328592Y801266D01*
G01X-1322994Y798980D02*
X-1322834Y799796D01*
G01X-1328272Y802573D02*
X-1328432Y802083D01*
G01X-1327952Y803227D02*
X-1328272Y802573D01*
G01X-1318036Y800940D02*
X-1318196Y800613D01*
G01X-1310839Y800940D02*
X-1310999Y800613D01*
G01X-1326993Y803063D02*
X-1327633Y802083D01*
G01X-1327473Y803716D02*
X-1327952Y803227D01*
G01X-1320755Y801430D02*
X-1320435Y801757D01*
G01Y801103D02*
X-1320755Y800776D01*
G01X-1318356Y801266D02*
X-1317876Y801757D01*
G01Y801103D02*
X-1318036Y800940D01*
G01X-1313558Y801430D02*
X-1313238Y801757D01*
G01Y801103D02*
X-1313558Y800776D01*
G01X-1311159Y801266D02*
X-1310679Y801757D01*
G01Y801103D02*
X-1310839Y800940D01*
G01X-1326513Y803390D02*
X-1326993Y803063D01*
G01X-1326673Y804207D02*
X-1327473Y803716D01*
G01X-1328592Y799796D02*
X-1328432Y798980D01*
G01X-1322834Y801266D02*
X-1322994Y802083D01*
G01X-1327793Y799960D02*
X-1327633Y798980D01*
G01X-1323634Y801103D02*
X-1323794Y802083D01*
G01X-1317556Y801266D02*
X-1317876Y801103D01*
G01X-1310359Y801266D02*
X-1310679Y801103D01*
G01X-1320435Y801757D02*
X-1319955Y801920D01*
G01Y801266D02*
X-1320435Y801103D01*
G01X-1317876Y801757D02*
X-1317396Y801920D01*
G01X-1313238Y801757D02*
X-1312758Y801920D01*
G01Y801266D02*
X-1313238Y801103D01*
G01X-1310679Y801757D02*
X-1310199Y801920D01*
G01X-1323794Y802083D02*
X-1324434Y803063D01*
G01X-1323154Y802573D02*
X-1323474Y803227D01*
G01X-1318996Y800613D02*
X-1319156Y800940D01*
G01X-1316437Y800613D02*
X-1316597Y800940D01*
G01X-1311798Y800613D02*
X-1311958Y800940D01*
G01X-1309239Y800613D02*
X-1309399Y800940D01*
G01X-1315957Y801430D02*
X-1315637Y800613D01*
G01X-1308759Y801430D02*
X-1308440Y800613D01*
G01X-1322994Y802083D02*
X-1323154Y802573D01*
G01X-1323474Y803227D02*
X-1323954Y803716D01*
G01X-1319156Y800940D02*
X-1319316Y801103D01*
G01X-1318836Y801757D02*
X-1318356Y801266D01*
G01X-1316597Y800940D02*
X-1316757Y801103D01*
G01X-1316277Y801757D02*
X-1315957Y801430D01*
G01X-1311958Y800940D02*
X-1312118Y801103D01*
G01X-1311639Y801757D02*
X-1311159Y801266D01*
G01X-1309399Y800940D02*
X-1309559Y801103D01*
G01X-1309080Y801757D02*
X-1308759Y801430D01*
G01X-1319316Y801103D02*
X-1319635Y801266D01*
G01X-1316757Y801103D02*
X-1317076Y801266D01*
G01X-1312118Y801103D02*
X-1312438Y801266D01*
G01X-1309559Y801103D02*
X-1309879Y801266D01*
G01X-1323954Y803716D02*
X-1324754Y804207D01*
G01X-1324434Y803063D02*
X-1324914Y803390D01*
G01X-1324754Y804207D02*
X-1325713Y804370D01*
G01X-1324914Y803390D02*
X-1325713Y803554D01*
G01X-1319316Y801920D02*
X-1318836Y801757D01*
G01X-1316757Y801920D02*
X-1316277Y801757D01*
G01X-1312118Y801920D02*
X-1311639Y801757D01*
G01X-1309559Y801920D02*
X-1309080Y801757D01*
G01X-1325713Y803554D02*
X-1326513Y803390D01*
G01X-1325713Y804370D02*
X-1326673Y804207D01*
G01X-1329872Y799306D02*
X-1332431D01*
G01Y799960D02*
X-1329872D01*
G01X-1309879Y801266D02*
X-1310359D01*
G01X-1312438D02*
X-1312758D01*
G01X-1317076D02*
X-1317556D01*
G01X-1319635D02*
X-1319955D01*
G01X-1329872D02*
X-1332431D01*
G01Y801920D02*
X-1329872D01*
G01X-1321555D02*
X-1320755D01*
G01X-1319955D02*
X-1319316D01*
G01X-1317396D02*
X-1316757D01*
G01X-1314357D02*
X-1313558D01*
G01X-1312758D02*
X-1312118D01*
G01X-1310199D02*
X-1309559D01*
G01X-1341013Y876716D02*
X-1327856Y910421D01*
G01D02*
Y913369D01*
G01X-1339728Y976084D02*
Y987895D01*
G01X-1338252Y981613D02*
Y976084D01*
G01D02*
X-1339728D01*
G01X-1338252Y987895D02*
Y983120D01*
G01X-1331362Y981613D02*
X-1338252D01*
G01Y983120D02*
X-1331362D01*
G01Y976084D02*
Y981613D01*
G01X-1329885Y987895D02*
Y976084D01*
G01X-1314876D02*
Y979602D01*
G01X-1313399D02*
Y976084D01*
G01X-1308970D02*
Y984126D01*
G01X-1307740Y982366D02*
Y976084D01*
G01X-1305033D02*
Y982115D01*
G01X-1303803Y976084D02*
X-1305033D01*
G01X-1307740D02*
X-1308970D01*
G01X-1313399D02*
X-1314876D01*
G01X-1329885D02*
X-1331362D01*
G01X-1320781Y981110D02*
X-1314876Y987895D01*
G01X-1319059Y981110D02*
X-1314876Y985885D01*
G01X-1307740Y983372D02*
X-1307248Y983874D01*
G01Y982869D02*
X-1307740Y982366D01*
G01X-1327917Y982115D02*
X-1323242Y984628D01*
G01X-1322750Y983874D02*
X-1326194Y982115D01*
G01X-1307248Y983874D02*
X-1306509Y984126D01*
G01Y983120D02*
X-1307248Y982869D01*
G01X-1322750Y980356D02*
X-1323242Y979602D01*
G01X-1331362Y983120D02*
Y987895D01*
G01X-1320781Y979602D02*
Y981110D01*
G01X-1314876Y985885D02*
Y981110D01*
G01X-1313399Y987895D02*
Y981110D01*
G01X-1310939D02*
Y979602D01*
G01X-1307740Y984126D02*
Y983372D01*
G01X-1305033Y982115D02*
X-1305279Y982618D01*
G01X-1323242Y984628D02*
X-1322750Y983874D01*
G01X-1305279Y982618D02*
X-1305525Y982869D01*
G01X-1304787Y983874D02*
X-1304049Y983120D01*
G01X-1326194Y982115D02*
X-1322750Y980356D01*
G01X-1305525Y982869D02*
X-1306017Y983120D01*
G01X-1323242Y979602D02*
X-1327917Y982115D01*
G01X-1305525Y984126D02*
X-1304787Y983874D01*
G01X-1310939Y979602D02*
X-1313399D01*
G01X-1314876D02*
X-1320781D01*
G01X-1314876Y981110D02*
X-1319059D01*
G01X-1313399D02*
X-1310939D01*
G01X-1306017Y983120D02*
X-1306509D01*
G01X-1308970Y984126D02*
X-1307740D01*
G01X-1306509D02*
X-1305525D01*
G01X-1303803Y982115D02*
Y976084D01*
G01X-1301096D02*
Y982115D01*
G01X-1299866D02*
Y976084D01*
G01D02*
X-1301096D01*
G01X-1304049Y983120D02*
X-1303311Y983874D01*
G01Y982869D02*
X-1303557Y982618D01*
G01X-1302818Y983120D02*
X-1303311Y982869D01*
G01Y983874D02*
X-1302572Y984126D01*
G01X-1303557Y982618D02*
X-1303803Y982115D01*
G01X-1300358Y983372D02*
X-1299866Y982115D01*
G01X-1301096D02*
X-1301342Y982618D01*
G01D02*
X-1301588Y982869D01*
G01X-1300850Y983874D02*
X-1300358Y983372D01*
G01X-1301588Y982869D02*
X-1302080Y983120D01*
G01X-1301588Y984126D02*
X-1300850Y983874D01*
G01X-1302080Y983120D02*
X-1302818D01*
G01X-1302572Y984126D02*
X-1301588D01*
G01X-1339728Y987895D02*
X-1338252D01*
G01X-1331362D02*
X-1329885D01*
G01X-1314876D02*
X-1313399D01*
G01X-1273100Y1114843D02*
G03I-18701J0D01*
G01X-1284911D02*
G03I-6890J0D01*
G01X-1239775Y-527134D02*
X-1297880Y-694431D01*
G01X-1236546Y-494254D02*
Y-690100D01*
G01X-1239866Y-521601D02*
X-1284316Y-571983D01*
G01D02*
X-1287465D01*
G01X-1226703Y-517837D02*
G03I-9843J0D01*
G01X-1231526D02*
G03I-5020J0D01*
G01X-1240483D02*
X-1291147D01*
G01X-1240483Y-490317D02*
X-1294583D01*
G01X-1231802D02*
G03I-4744J0D01*
G01X-1250462Y410118D02*
Y300276D01*
G01X-1294714Y374488D02*
X-1295895D01*
G01X-1294714Y377488D02*
X-1295895D01*
G01Y373110D02*
X-1295305Y372520D01*
G01X-1297553Y382932D02*
X-1294313Y378305D01*
G01X-1296486Y426654D02*
Y372520D01*
G01X-1295895Y373110D02*
Y471929D01*
G01X-1294714Y372520D02*
Y471929D01*
G01X-1293797Y379628D02*
X-1293991Y378531D01*
G01D02*
X-1294313Y378305D01*
G01X-1295895Y380276D02*
X-1294714D01*
G01Y380994D02*
X-1295895D01*
G01X-1294714Y381131D02*
X-1295895D01*
G01X-1295361Y379681D02*
X-1295248Y379623D01*
X-1295204Y379578D01*
G01X-1294714Y387528D02*
X-1295895D01*
G01X-1294714Y389051D02*
X-1295895D01*
G01X-1294714Y394751D02*
X-1295895D01*
G01X-1296193Y386937D02*
X-1296133Y386886D01*
G01X-1297366Y385761D02*
X-1296475Y384870D01*
G01X-1296113Y385343D02*
X-1296057Y385288D01*
G01X-1296239Y386888D02*
X-1295348Y385997D01*
G01X-1296435Y393251D02*
X-1295600Y392416D01*
G01X-1295481Y394205D02*
X-1294646Y393370D01*
G01X-1294846Y394840D02*
X-1294568Y394562D01*
G01X-1295404Y379726D02*
X-1295361Y379681D01*
G01X-1295404Y379726D02*
X-1295361Y379681D01*
G01X-1297617Y382887D02*
X-1295404Y379726D01*
G01X-1297585Y382910D02*
X-1295409Y379804D01*
G01X-1296650Y383565D02*
X-1295159Y381436D01*
G01X-1296618Y383587D02*
X-1295059Y381362D01*
G01X-1296585Y383610D02*
X-1293797Y379628D01*
G01X-1296678Y390478D02*
X-1296074Y389615D01*
G01X-1295710Y391155D02*
X-1295106Y390293D01*
G01X-1295332Y379692D02*
X-1295410Y379805D01*
G01X-1295409Y379804D02*
X-1295331Y379692D01*
G01X-1295304Y379652D02*
X-1295332Y379692D01*
G01X-1295331D02*
X-1295304Y379652D01*
G01X-1294568Y394562D02*
Y393448D01*
G01X-1295936Y387565D02*
X-1295937Y387549D01*
X-1295939Y387500D01*
G01X-1295937Y387549D02*
X-1295939Y387500D01*
G01D02*
X-1295945Y387422D01*
G01X-1295977Y387452D02*
X-1295979Y387431D01*
X-1295991Y387354D01*
G01X-1295895Y387528D02*
X-1295901Y387490D01*
X-1295918Y387454D01*
X-1295945Y387422D01*
G01X-1295895Y387685D02*
X-1295906Y387622D01*
X-1295936Y387565D01*
G01X-1295975Y387268D02*
X-1295945Y387422D01*
G01X-1295991Y387354D02*
X-1296026Y387229D01*
G01X-1295992Y387107D02*
X-1295917Y387333D01*
X-1295895Y387528D01*
G01X-1295991Y387354D02*
X-1295983Y387379D01*
X-1295967Y387402D01*
X-1295945Y387422D01*
G01X-1295976Y387267D02*
X-1296047Y387087D01*
X-1296163Y386912D01*
G01X-1296047Y387086D02*
X-1295975Y387268D01*
G01X-1295976Y387267D02*
X-1296047Y387086D01*
X-1296163Y386912D01*
G01X-1296026Y387231D02*
X-1296093Y387082D01*
X-1296193Y386937D01*
G01X-1295906Y387622D02*
X-1295936Y387565D01*
G01D02*
X-1295964Y387515D01*
X-1295977Y387460D01*
G01X-1295936Y387565D02*
X-1295964Y387515D01*
X-1295977Y387460D01*
G01X-1296133Y386886D02*
X-1295992Y387107D01*
G01X-1294846Y394840D02*
X-1296435Y393251D01*
G01X-1294568Y393448D02*
X-1295600Y392416D01*
G01X-1296239Y386888D02*
X-1297366Y385761D01*
G01X-1296211Y386860D02*
X-1297338Y385733D01*
G01X-1296184Y386832D02*
X-1297310Y385705D01*
G01X-1295807Y385650D02*
X-1296531Y384926D01*
G01X-1295696Y385705D02*
X-1296503Y384898D01*
G01X-1295348Y385997D02*
X-1296475Y384870D01*
G01X-1295710Y391155D02*
X-1296678Y390478D01*
G01X-1295106Y390293D02*
X-1296074Y389615D01*
G01X-1296585Y383610D02*
X-1297617Y382887D01*
G01X-1295343Y381836D02*
X-1295408Y381791D01*
G01X-1295698Y380146D02*
X-1295633Y380191D01*
G01X-1293852Y379705D02*
X-1294819Y379028D01*
G01X-1295204Y379578D02*
G03X-1295304Y379652I-161J-113D01*
G01X-1295404Y379726D02*
G03X-1295304Y379652I161J113D01*
G01X-1295159Y381436D02*
G03X-1295059Y381362I161J113D01*
G01X-1294959Y381288D02*
G03X-1295059Y381362I-161J-113D01*
G01X-1295348Y385997D02*
G03X-1294714Y387528I-1532J1531D01*
G01X-1296184Y386832D02*
G03X-1295895Y387528I-695J697D01*
G01X-1296211Y386860D02*
G03X-1296163Y386912I-670J667D01*
G01X-1296239Y386888D02*
G03X-1295977Y387460I-641J640D01*
G01X-1295936Y387565D02*
G03X-1295895Y387685I-156J120D01*
G01X-1294714Y389051D02*
G03X-1295106Y390293I-2166J-1D01*
G01X-1295895Y389051D02*
G03X-1296074Y389615I-984J-2D01*
G01X-1297366Y385761D02*
G03X-1297617Y382887I1587J-1587D01*
G01X-1297338Y385733D02*
G03X-1297585Y382910I1559J-1559D01*
G01X-1297310Y385705D02*
G03X-1297553Y382932I1531J-1531D01*
G01X-1296531Y384926D02*
G03X-1296650Y383565I752J-751D01*
G01X-1296503Y384898D02*
G03X-1296618Y383587I724J-724D01*
G01X-1296475Y384870D02*
G03X-1296585Y383610I696J-696D01*
G01X-1295936Y387565D02*
G03X-1295977Y387460I155J-121D01*
G01X-1295696Y385705D02*
G03X-1295584Y385761I-28J195D01*
G01X-1295696Y385705D02*
G03X-1295807Y385650I27J-195D01*
G01X-1296435Y393251D02*
G03X-1296678Y390478I1531J-1531D01*
G01X-1295600Y392416D02*
G03X-1295710Y391155I696J-696D01*
G01X-1231761Y414055D02*
G03I-18701J0D01*
G01X-1294714Y397087D02*
X-1295895D01*
G01X-1294714Y401138D02*
X-1295895D01*
G01X-1294714Y401382D02*
X-1295895D01*
G01Y402441D02*
X-1294714D01*
G01X-1295994Y405118D02*
Y426181D01*
G01Y405118D02*
X-1297962Y403150D01*
G01X-1294714Y415551D02*
X-1295895D01*
G01X-1294714Y416339D02*
X-1295895D01*
G01X-1295698Y418976D02*
X-1295895D01*
G01X-1294517D02*
X-1294714D01*
G01Y420487D02*
X-1295895D01*
G01X-1294714Y421168D02*
X-1295895D01*
G01X-1296092Y421555D02*
X-1297175D01*
G01X-1295206Y422441D02*
X-1295994D01*
G01X-1294714Y422520D02*
X-1295895D01*
G01Y422587D02*
X-1294714D01*
G01Y422638D02*
X-1295895D01*
G01X-1294714Y423349D02*
X-1295895D01*
G01X-1297667Y424106D02*
X-1297568D01*
G01X-1297175D02*
X-1295698D01*
G01X-1295895Y424109D02*
X-1294714D01*
G01Y424867D02*
X-1295895D01*
G01Y425628D02*
X-1294714D01*
G01X-1296092Y426279D02*
X-1297175D01*
G01X-1294714Y426390D02*
X-1295895D01*
G01X-1294714Y426457D02*
X-1295895D01*
G01X-1295796Y436160D02*
X-1295399Y436090D01*
X-1295210Y436020D01*
X-1295043Y435918D01*
X-1294905Y435789D01*
X-1294801Y435638D01*
X-1294736Y435470D01*
X-1294714Y435295D01*
G01X-1295795Y436785D02*
X-1295978Y436852D01*
X-1296141Y436948D01*
X-1296279Y437070D01*
X-1296384Y437213D01*
X-1296454Y437371D01*
X-1296485Y437538D01*
X-1296475Y437706D01*
X-1296426Y437870D01*
X-1296339Y438021D01*
X-1296218Y438155D01*
X-1296064Y438267D01*
X-1295891Y438349D01*
X-1295701Y438400D01*
X-1295502Y438417D01*
G01X-1296486Y426654D02*
X-1296672Y426727D01*
X-1296839Y426800D01*
X-1296987Y426874D01*
X-1297117Y426947D01*
X-1297230Y427022D01*
X-1297326Y427098D01*
X-1297403Y427174D01*
X-1297473Y427266D01*
X-1297530Y427352D01*
X-1297593Y427460D01*
X-1297653Y427587D01*
X-1297704Y427735D01*
X-1297738Y427902D01*
X-1297743Y428073D01*
X-1297719Y428240D01*
X-1297663Y428410D01*
X-1297568Y428586D01*
X-1297429Y428767D01*
X-1297242Y428948D01*
G01X-1295502Y437791D02*
X-1295700Y437774D01*
X-1295889Y437724D01*
X-1296063Y437642D01*
X-1296215Y437532D01*
X-1296337Y437398D01*
X-1296424Y437247D01*
X-1296474Y437084D01*
X-1296485Y436915D01*
X-1296455Y436749D01*
X-1296386Y436591D01*
X-1296281Y436447D01*
X-1296142Y436322D01*
X-1295979Y436226D01*
X-1295796Y436160D01*
G01X-1295698Y429180D02*
X-1295507Y429196D01*
X-1295324Y429243D01*
X-1295154Y429320D01*
X-1295003Y429425D01*
X-1294881Y429551D01*
X-1294790Y429694D01*
X-1294734Y429850D01*
X-1294714Y430015D01*
G01X-1296486Y428554D02*
X-1296622Y428548D01*
X-1296756Y428528D01*
X-1296886Y428495D01*
X-1297011Y428450D01*
X-1297129Y428393D01*
X-1297242Y428322D01*
G01X-1295088Y427926D02*
X-1294714D01*
G01X-1295698Y428554D02*
X-1296486D01*
G01X-1295088Y428608D02*
X-1294714D01*
G01X-1295698Y429180D02*
X-1296486D01*
G01X-1294714Y429513D02*
X-1295895D01*
G01X-1295108Y431102D02*
X-1295502D01*
G01X-1293336Y436687D02*
X-1294517D01*
G01X-1293336Y437165D02*
X-1294517D01*
G01X-1295108Y437791D02*
X-1295502D01*
G01X-1294124Y438167D02*
X-1293336D01*
G01X-1295108Y438417D02*
X-1295502D01*
G01X-1295108Y437791D02*
X-1294993Y437785D01*
X-1294883Y437767D01*
X-1294781Y437739D01*
X-1294691Y437699D01*
X-1294617Y437652D01*
X-1294563Y437598D01*
X-1294529Y437540D01*
X-1294517Y437478D01*
G01X-1296584Y420472D02*
X-1295994Y419882D01*
G01X-1297864Y426181D02*
X-1297667Y425984D01*
G01X-1293336Y437478D02*
X-1293370Y437660D01*
X-1293470Y437836D01*
X-1293632Y437998D01*
X-1293855Y438142D01*
X-1294122Y438258D01*
X-1294427Y438345D01*
X-1294758Y438398D01*
X-1295108Y438417D01*
G01X-1294714Y435921D02*
X-1294736Y436095D01*
X-1294800Y436261D01*
X-1294902Y436412D01*
X-1295040Y436541D01*
X-1295206Y436644D01*
X-1295398Y436716D01*
X-1295795Y436785D01*
G01X-1295108Y431102D02*
X-1295085Y430892D01*
X-1295013Y430657D01*
X-1294890Y430407D01*
X-1294714Y430147D01*
G01X-1297744Y428020D02*
Y427647D01*
G01X-1297667Y423228D02*
Y425984D01*
G01X-1297568Y426279D02*
Y422933D01*
G01X-1297242Y428322D02*
Y428948D01*
G01X-1297175Y414370D02*
Y429331D01*
G01X-1296584Y420472D02*
Y424106D01*
G01X-1296486Y428554D02*
Y429180D01*
G01Y436956D02*
Y437582D01*
G01X-1296092Y471752D02*
Y420571D01*
G01X-1295698Y429180D02*
Y428554D01*
G01Y424106D02*
Y417205D01*
G01X-1295600Y436126D02*
Y436752D01*
G01X-1295502Y431102D02*
Y471004D01*
G01X-1295206Y419882D02*
Y422441D01*
G01X-1295108Y471850D02*
Y431102D01*
G01X-1295088Y426457D02*
Y464206D01*
G01X-1294517Y472129D02*
Y417205D01*
G01X-1294124Y466258D02*
Y438167D01*
G01X-1293336Y436688D02*
Y472129D01*
G01X-1294124Y438167D02*
X-1294166Y437759D01*
X-1294297Y437389D01*
X-1294517Y437083D01*
G01X-1295502Y431102D02*
X-1295526Y430888D01*
X-1295599Y430653D01*
X-1295722Y430404D01*
X-1295895Y430147D01*
G01X-1294714Y429389D02*
X-1294733Y429227D01*
X-1294789Y429071D01*
X-1294879Y428927D01*
X-1295003Y428799D01*
X-1295151Y428695D01*
X-1295320Y428618D01*
X-1295504Y428571D01*
X-1295698Y428554D01*
G01X-1295206Y419882D02*
X-1295994Y416943D01*
G01X-1297667Y423228D02*
X-1297864Y423031D01*
G01X-1295994Y415551D02*
X-1297175Y414370D01*
G01X-1297242Y428322D02*
X-1297398Y428215D01*
X-1297526Y428104D01*
X-1297624Y427989D01*
X-1297692Y427877D01*
X-1297731Y427766D01*
X-1297744Y427657D01*
X-1297735Y427546D01*
X-1297702Y427434D01*
X-1297650Y427328D01*
X-1297591Y427238D01*
X-1297534Y427166D01*
X-1297468Y427093D01*
X-1297397Y427027D01*
X-1297324Y426975D01*
X-1297243Y426928D01*
X-1297149Y426881D01*
X-1297042Y426835D01*
X-1296922Y426789D01*
X-1296789Y426744D01*
X-1296644Y426698D01*
X-1296486Y426654D01*
G01X-1297242Y428948D02*
X-1297132Y429017D01*
X-1297014Y429074D01*
X-1296889Y429120D01*
X-1296759Y429153D01*
X-1296625Y429173D01*
X-1296486Y429180D01*
G01X-1294714Y416495D02*
G03X-1294517Y417205I-1181J710D01*
G01X-1295895Y417008D02*
G03X-1295698Y417205I0J197D01*
G01X-1294714Y439961D02*
X-1295088D01*
G01X-1294714Y440748D02*
X-1295088D01*
G01X-1294714Y447652D02*
X-1295088D01*
G01Y448334D02*
X-1294714D01*
G01Y449803D02*
X-1295088D01*
G01X-1294517Y454409D02*
X-1294714D01*
G01X-1293336Y454413D02*
X-1293927D01*
G01X-1294714Y456185D02*
X-1295088D01*
G01X-1293336Y456381D02*
X-1294517D01*
G01X-1294714Y456747D02*
X-1295088D01*
G01X-1294714Y456972D02*
X-1295088D01*
G01X-1294714Y457169D02*
X-1295088D01*
G01X-1294517Y458153D02*
X-1293336D01*
G01Y458547D02*
X-1294517D01*
G01X-1294714D02*
X-1295088D01*
G01X-1293336Y458941D02*
X-1294517D01*
G01X-1294714Y459137D02*
X-1295088D01*
G01X-1293139D02*
X-1294320D01*
G01X-1294714Y460920D02*
X-1295088D01*
G01X-1294517Y455436D02*
X-1293927Y454413D01*
G01X-1294320Y459137D02*
Y461529D01*
G01X-1293139D02*
Y459137D01*
G01Y461529D02*
G03X-1293505Y463430I-5119J0D01*
G01X-1294320Y461529D02*
G03X-1294602Y462991I-3937J-1D01*
G01X-1294517Y456181D02*
G03X-1294714Y456891I-1378J0D01*
G01X-1243572Y414055D02*
G03I-6890J0D01*
G01X-1295088Y461602D02*
X-1294714D01*
G01X-1295895Y462185D02*
X-1294714D01*
G01Y462256D02*
X-1295895D01*
G01Y462316D02*
X-1294714D01*
G01X-1295895Y463000D02*
X-1294714D01*
G01Y463071D02*
X-1295895D01*
G01X-1294714Y463946D02*
X-1295895D01*
G01X-1294714Y465433D02*
X-1295895D01*
G01X-1293336Y466258D02*
X-1294124D01*
G01X-1294714Y467795D02*
X-1295895D01*
G01X-1293336Y467996D02*
X-1294517D01*
G01X-1293336Y468783D02*
X-1294517D01*
G01X-1296092Y467841D02*
X-1296683Y468786D01*
G01X-1296092Y462291D02*
X-1296683Y463427D01*
G01X-1294517Y467760D02*
X-1294296Y467218D01*
X-1294166Y466711D01*
X-1294124Y466258D01*
G01X-1295088Y464206D02*
X-1294602Y462991D01*
G01X-1293505Y463430D02*
X-1294714Y466452D01*
G01X-1297568Y467815D02*
Y471752D01*
G01X-1296683Y463427D02*
Y471752D01*
G01X-1295088Y467795D02*
Y465433D01*
G01X-1295108Y471850D02*
X-1294764Y471832D01*
X-1294433Y471779D01*
X-1294128Y471693D01*
X-1293855Y471575D01*
X-1293636Y471433D01*
X-1293472Y471272D01*
X-1293371Y471096D01*
X-1293336Y470911D01*
G01X-1295895Y471850D02*
X-1296169Y471866D01*
X-1296444Y471916D01*
X-1296709Y471999D01*
X-1296950Y472110D01*
X-1297176Y472252D01*
X-1297378Y472421D01*
G01X-1295895Y469283D02*
X-1294714D01*
G01Y470157D02*
X-1295895D01*
G01X-1294714Y470229D02*
X-1295895D01*
G01X-1294517Y470598D02*
X-1293336D01*
G01X-1296683Y470866D02*
X-1295088D01*
G01X-1294714Y470913D02*
X-1295895D01*
G01Y470945D02*
X-1294714D01*
G01X-1295895Y470972D02*
X-1294714D01*
G01X-1295502Y471004D02*
X-1295108D01*
G01X-1295895Y471043D02*
X-1294714D01*
G01X-1295895Y471224D02*
X-1295108D01*
G01X-1295895Y471850D02*
X-1295108D01*
G01X-1294714Y471929D02*
X-1295895D01*
G01X-1297378Y471795D02*
X-1297183Y471631D01*
X-1296957Y471488D01*
X-1296710Y471374D01*
X-1296453Y471292D01*
X-1296178Y471241D01*
X-1295895Y471224D01*
G01X-1297378Y471795D02*
X-1297513Y471993D01*
X-1297613Y472161D01*
X-1297680Y472302D01*
X-1297718Y472418D01*
X-1297729Y472512D01*
X-1297715Y472587D01*
X-1297676Y472645D01*
X-1297609Y472686D01*
X-1297512Y472711D01*
X-1297378Y472720D01*
G01Y472421D02*
X-1297599Y472966D01*
X-1297712Y473381D01*
X-1297717Y473681D01*
X-1297605Y473850D01*
X-1297378Y473901D01*
G01X-1294517Y470911D02*
X-1294529Y470972D01*
X-1294562Y471030D01*
X-1294616Y471084D01*
X-1294691Y471132D01*
X-1294780Y471171D01*
X-1294881Y471200D01*
X-1294991Y471218D01*
X-1295108Y471224D01*
G01X-1295502Y471004D02*
X-1295544Y471324D01*
X-1295676Y471597D01*
X-1295895Y471797D01*
G01X-1297729Y473562D02*
Y472508D01*
G01X-1297628Y472720D02*
Y473901D01*
G01X-1297378Y472421D02*
Y471795D01*
G01Y472720D02*
Y473901D01*
G01X-1296945D02*
Y472720D01*
G01X-1296526D02*
Y473901D01*
G01X-1296486D02*
Y472720D01*
G01X-1296014Y473901D02*
Y472720D01*
G01X-1295502D02*
Y473901D01*
G01X-1295088Y470866D02*
Y470157D01*
G01X-1294714Y471797D02*
X-1294937Y471593D01*
X-1295068Y471318D01*
X-1295108Y471004D01*
G01X-1293336Y472129D02*
G03X-1295108Y473901I-1772J0D01*
G01X-1294517Y472129D02*
G03X-1295108Y472720I-591J0D01*
G01X-1182018Y487776D02*
X-1238156D01*
G01X-1234245Y488760D02*
X-1234954D01*
G01X-1233064Y489941D02*
X-1236135D01*
G01X-1096958Y490335D02*
X-1241686D01*
G01X-1182018Y491122D02*
X-1238156D01*
G01X-1096958Y492697D02*
X-1241686D01*
G01X-1182018Y494705D02*
X-1238156D01*
G01X-1182018Y495177D02*
X-1238156D01*
G01X-1228241Y497421D02*
X-1233872D01*
G01X-1235327D02*
X-1240959D01*
G01D02*
X-1240741Y497247D01*
X-1240539Y497019D01*
X-1240367Y496741D01*
X-1240234Y496420D01*
X-1240150Y496070D01*
X-1240121Y495706D01*
G01X-1233872Y497421D02*
X-1233654Y497247D01*
X-1233453Y497019D01*
X-1233280Y496741D01*
X-1233147Y496420D01*
X-1233064Y496070D01*
X-1233035Y495706D01*
G01X-1236135Y489941D02*
X-1234954Y488760D01*
G01X-1240121Y496278D02*
X-1240174Y496605D01*
X-1240331Y496919D01*
X-1240593Y497199D01*
X-1240959Y497421D01*
G01X-1233035Y496278D02*
X-1233087Y496605D01*
X-1233244Y496919D01*
X-1233507Y497199D01*
X-1233872Y497421D01*
G01X-1241686Y490335D02*
Y492697D01*
G01Y497601D02*
Y513681D01*
G01X-1240121Y496278D02*
Y490335D01*
G01X-1238156Y576489D02*
Y487776D01*
G01X-1236165Y496278D02*
Y490335D01*
G01X-1236135Y492697D02*
Y489941D01*
G01X-1233064D02*
Y492697D01*
G01X-1233035Y496278D02*
Y490335D01*
G01X-1236165Y495706D02*
X-1236136Y496070D01*
X-1236052Y496420D01*
X-1235920Y496741D01*
X-1235747Y497019D01*
X-1235545Y497247D01*
X-1235327Y497421D01*
G01X-1236165Y496278D02*
X-1236070Y496714D01*
X-1235789Y497114D01*
X-1235327Y497421D01*
G01X-1233064Y489941D02*
X-1234245Y488760D01*
G01X-1233872Y497421D02*
G03X-1235327I-727J-1385D01*
G01X-1240959D02*
G03X-1241686Y497601I-729J-1385D01*
G01X-1182018Y501221D02*
X-1238156D01*
G01X-1241686Y517618D02*
Y533760D01*
G01X-1233612Y501063D02*
G03I-709J0D01*
G01Y505394D02*
G03I-709J0D01*
G01X-1232631Y515650D02*
G03I-1969J0D01*
G01X-1241686Y513681D02*
G03Y517618I0J1968D01*
G01X-1233612Y510905D02*
G03I-709J0D01*
G01Y515236D02*
G03I-709J0D01*
G01Y519567D02*
G03I-709J0D01*
G01Y525079D02*
G03I-709J0D01*
G01X-1247706Y1098165D02*
Y563661D01*
G01Y1098165D02*
Y563661D01*
G01D02*
G03X-1243769I1968J0D01*
G01X-1247706D02*
G03X-1243769I1968J0D01*
G01X-1233612Y529409D02*
G03I-709J0D01*
G01X-1233222Y530827D02*
X-1235978D01*
G01X-1232237Y533350D02*
X-1236962D01*
G01X-1233852Y536507D02*
X-1235348D01*
G01X-1232828Y552187D02*
X-1229285D01*
G01X-1238733Y554232D02*
X-1237552D01*
G01X-1236135Y555236D02*
X-1238156D01*
G01X-1233064D02*
X-1186529D01*
G01X-1236135Y537871D02*
X-1235348Y536507D01*
G01X-1237552Y554232D02*
X-1236174Y551846D01*
G01X-1240111Y535335D02*
Y551846D01*
G01X-1236962Y555236D02*
Y531811D01*
G01X-1236174Y551846D02*
Y549148D01*
G01Y547489D02*
Y541825D01*
G01Y540166D02*
Y535335D01*
G01X-1236135Y537871D02*
Y540105D01*
G01Y541885D02*
Y547428D01*
G01Y549208D02*
Y555236D01*
G01X-1233064D02*
Y549208D01*
G01Y547428D02*
Y541885D01*
G01Y540105D02*
Y537871D01*
G01X-1233025Y535335D02*
Y540166D01*
G01Y541825D02*
Y547489D01*
G01Y549148D02*
Y551846D01*
G01X-1238733Y554232D02*
X-1240111Y551846D01*
G01X-1233025D02*
X-1231647Y554232D01*
G01X-1233064Y537871D02*
X-1233852Y536507D01*
G01X-1241686Y533760D02*
G03X-1240111Y535335I0J1575D01*
G01X-1236174D02*
G03X-1233025I1574J0D01*
G01X-1236962Y531811D02*
G03X-1235978Y530827I984J0D01*
G01X-1233222D02*
G03X-1232237Y531811I1J984D01*
G01X-1233612Y533740D02*
G03I-709J0D01*
G01X-1236135Y541885D02*
G03Y540105I1299J-890D01*
G01Y549208D02*
G03Y547428I1299J-890D01*
G01X-1233064D02*
G03Y549208I-1299J890D01*
G01Y540105D02*
G03Y541885I-1299J890D01*
G01X-1233612Y539252D02*
G03I-709J0D01*
G01Y543583D02*
G03I-709J0D01*
G01Y547913D02*
G03I-709J0D01*
G01Y557756D02*
G03I-709J0D01*
G01Y553425D02*
G03I-709J0D01*
G01X-1233248Y565440D02*
X-1233264Y565436D01*
X-1233280Y565434D01*
X-1233296Y565433D01*
G01X-1243769Y563661D02*
X-1091801D01*
G01X-1243769D02*
X-1091801D01*
G01X-1182018Y564055D02*
X-1238156D01*
G01X-1182018Y564842D02*
X-1238645D01*
G01X-1182346Y565433D02*
X-1238645D01*
G01X-1233611Y566417D02*
X-1236170D01*
G01X-1233709Y566654D02*
X-1236071D01*
G01X-1238645Y568055D02*
X-1236170D01*
G01X-1233611D02*
X-1229083D01*
G01X-1233709Y568228D02*
X-1236071D01*
G01X-1229083Y568252D02*
X-1233611D01*
G01X-1236170D02*
X-1238645D01*
G01X-1233709Y570591D02*
X-1236071D01*
G01X-1234004Y570748D02*
X-1235776D01*
G01X-1238156Y576489D02*
X-1238645D01*
G01X-1236536D02*
X-1233245D01*
G01X-1236532Y565440D02*
X-1236517Y565436D01*
X-1236501Y565434D01*
X-1236485Y565433D01*
G01X-1236681Y565518D02*
X-1236650Y565485D01*
X-1236613Y565461D01*
X-1236573Y565446D01*
X-1236532Y565440D01*
G01X-1236525Y564842D02*
X-1236532Y565440D01*
G01X-1236536Y576489D02*
X-1236532Y565440D01*
G01X-1238645Y603425D02*
Y564842D01*
G01X-1236681Y565518D02*
Y564842D01*
G01X-1236485Y576489D02*
Y565433D01*
G01X-1236170Y570354D02*
Y566417D01*
G01X-1236071Y570591D02*
Y566654D01*
G01X-1233709Y570591D02*
Y566654D01*
G01X-1233611Y570354D02*
Y566417D01*
G01X-1233296Y565433D02*
Y576489D01*
G01X-1233099Y565518D02*
Y564842D01*
G01X-1233245Y576489D02*
X-1233248Y565440D01*
G01X-1233249D02*
X-1233256Y564842D01*
G01X-1233099Y565518D02*
X-1233131Y565485D01*
X-1233168Y565461D01*
X-1233208Y565446D01*
X-1233249Y565440D01*
G01X-1235776Y570748D02*
G03X-1236170Y570354I0J-394D01*
G01X-1233611D02*
G03X-1234004Y570748I-394J0D01*
G01X-1233231Y595551D02*
X-1238645D01*
G01X-1233100Y602080D02*
X-1236316D01*
G01X-1233231Y602937D02*
X-1238645D01*
G01Y603110D02*
X-1226121D01*
G01X-1238645Y603425D02*
X-1182346D01*
G01X-1236316Y602080D02*
X-1237661Y603425D01*
G01X-1232711Y603218D02*
X-1232738Y603275D01*
X-1232776Y603326D01*
X-1232824Y603368D01*
X-1232879Y603399D01*
X-1232939Y603418D01*
X-1233002Y603425D01*
G01X-1232501Y603218D02*
X-1232528Y603275D01*
X-1232566Y603326D01*
X-1232613Y603368D01*
X-1232669Y603399D01*
X-1232729Y603418D01*
X-1232792Y603425D01*
G01X-1231873Y599831D02*
X-1233085Y603110D01*
G01X-1232711Y603218D02*
X-1231509Y599965D01*
G01X-1233231Y603425D02*
Y595551D01*
G01X-1233085Y603425D02*
Y603110D01*
G01X-1231755Y603425D02*
X-1233100Y602080D01*
G01X-1233085Y603110D02*
X-1232711Y603218D01*
G01X-1291013Y806968D02*
Y769567D01*
G01X-1281921Y817125D02*
X-1223504Y851719D01*
G01X-1257706Y1119094D02*
Y904646D01*
G01X-1297897Y976084D02*
Y984126D01*
G01X-1296667Y982366D02*
Y976084D01*
G01X-1293960D02*
Y982115D01*
G01X-1292730D02*
Y976084D01*
G01X-1290023D02*
Y982115D01*
G01X-1288793D02*
Y976084D01*
G01D02*
X-1290023D01*
G01X-1292730D02*
X-1293960D01*
G01X-1296667D02*
X-1297897D01*
G01X-1296667Y983372D02*
X-1296175Y983874D01*
G01Y982869D02*
X-1296667Y982366D01*
G01X-1292976Y983120D02*
X-1292238Y983874D01*
G01X-1291746Y983120D02*
X-1292238Y982869D01*
G01X-1296175Y983874D02*
X-1295437Y984126D01*
G01Y983120D02*
X-1296175Y982869D01*
G01X-1292238Y983874D02*
X-1291500Y984126D01*
G01X-1292238Y982869D02*
X-1292484Y982618D01*
G01D02*
X-1292730Y982115D01*
G01X-1296667Y984126D02*
Y983372D01*
G01X-1289285D02*
X-1288793Y982115D01*
G01X-1293960D02*
X-1294206Y982618D01*
G01X-1290023Y982115D02*
X-1290269Y982618D01*
G01X-1294206D02*
X-1294452Y982869D01*
G01X-1293714Y983874D02*
X-1292976Y983120D01*
G01X-1290269Y982618D02*
X-1290515Y982869D01*
G01X-1289777Y983874D02*
X-1289285Y983372D01*
G01X-1294452Y982869D02*
X-1294944Y983120D01*
G01X-1290515Y982869D02*
X-1291007Y983120D01*
G01X-1294452Y984126D02*
X-1293714Y983874D01*
G01X-1290515Y984126D02*
X-1289777Y983874D01*
G01X-1291007Y983120D02*
X-1291746D01*
G01X-1294944D02*
X-1295437D01*
G01X-1297897Y984126D02*
X-1296667D01*
G01X-1295437D02*
X-1294452D01*
G01X-1291500D02*
X-1290515D01*
G01X-1247706Y1098165D02*
G03X-1248122Y1099926I-3937J0D01*
G01X-1247706Y1098165D02*
G03X-1248122Y1099926I-3937J0D01*
G01X-1247706Y1102102D02*
Y1173504D01*
G01X-1266304Y1136288D02*
X-1248122Y1099926D01*
G01D02*
X-1266304Y1136288D01*
G01X-1291801Y1118779D02*
Y1173504D01*
G01X-1266304Y1136288D02*
G03X-1269825Y1138465I-3522J-1760D01*
G01X-1266304Y1136288D02*
G03X-1269825Y1138465I-3522J-1760D01*
G01X-1179116Y-837696D02*
X2479D01*
G01X-1214067Y497421D02*
X-1219699D01*
G01X-1221154D02*
X-1226786D01*
G01D02*
X-1226568Y497247D01*
X-1226366Y497019D01*
X-1226193Y496741D01*
X-1226061Y496420D01*
X-1225977Y496070D01*
X-1225948Y495706D01*
G01X-1219699Y497421D02*
X-1219481Y497247D01*
X-1219280Y497019D01*
X-1219107Y496741D01*
X-1218974Y496420D01*
X-1218891Y496070D01*
X-1218861Y495706D01*
G01X-1229078Y496278D02*
Y490335D01*
G01X-1225948Y496278D02*
X-1226001Y496605D01*
X-1226157Y496919D01*
X-1226420Y497199D01*
X-1226786Y497421D01*
G01X-1218861Y496278D02*
X-1218914Y496605D01*
X-1219071Y496919D01*
X-1219333Y497199D01*
X-1219699Y497421D01*
G01X-1225948Y496278D02*
Y490335D01*
G01X-1221991Y496278D02*
Y490335D01*
G01X-1218861Y496278D02*
Y490335D01*
G01X-1214905Y496278D02*
Y490335D01*
G01X-1229078Y495706D02*
X-1229049Y496070D01*
X-1228965Y496420D01*
X-1228833Y496741D01*
X-1228660Y497019D01*
X-1228459Y497247D01*
X-1228241Y497421D01*
G01X-1221991Y495706D02*
X-1221963Y496070D01*
X-1221879Y496420D01*
X-1221746Y496741D01*
X-1221574Y497019D01*
X-1221372Y497247D01*
X-1221154Y497421D01*
G01X-1214905Y495706D02*
X-1214876Y496070D01*
X-1214792Y496420D01*
X-1214660Y496741D01*
X-1214487Y497019D01*
X-1214285Y497247D01*
X-1214067Y497421D01*
G01X-1229078Y496278D02*
X-1228984Y496714D01*
X-1228702Y497114D01*
X-1228241Y497421D01*
G01X-1221991Y496278D02*
X-1221897Y496714D01*
X-1221616Y497114D01*
X-1221154Y497421D01*
G01X-1214905Y496278D02*
X-1214811Y496714D01*
X-1214529Y497114D01*
X-1214067Y497421D01*
G01X-1219699D02*
G03X-1221154I-727J-1385D01*
G01X-1226786D02*
G03X-1228241I-727J-1385D01*
G01X-1226525Y496339D02*
G03I-709J0D01*
G01Y500669D02*
G03I-709J0D01*
G01Y506181D02*
G03I-709J0D01*
G01X-1225544Y515650D02*
G03I-1969J0D01*
G01X-1218458D02*
G03I-1969J0D01*
G01X-1226525Y510512D02*
G03I-709J0D01*
G01Y514843D02*
G03I-709J0D01*
G01Y520354D02*
G03I-709J0D01*
G01Y524685D02*
G03I-709J0D01*
G01X-1219439Y501063D02*
G03I-708J0D01*
G01Y505394D02*
G03I-708J0D01*
G01X-1211371Y515650D02*
G03I-1969J0D01*
G01X-1219439Y510905D02*
G03I-708J0D01*
G01Y515236D02*
G03I-708J0D01*
G01Y519567D02*
G03I-708J0D01*
G01Y525079D02*
G03I-708J0D01*
G01X-1184639Y488760D02*
X-1185348D01*
G01X-1183458Y489941D02*
X-1186529D01*
G01X-1185721Y497421D02*
X-1191353D01*
G01X-1192807D02*
X-1198439D01*
G01X-1199894D02*
X-1205526D01*
G01X-1206981D02*
X-1212613D01*
G01X-1184266D02*
X-1178634D01*
G01X-1212613D02*
X-1212394Y497247D01*
X-1212193Y497019D01*
X-1212020Y496741D01*
X-1211887Y496420D01*
X-1211804Y496070D01*
X-1211775Y495706D01*
G01X-1205526Y497421D02*
X-1205308Y497247D01*
X-1205106Y497019D01*
X-1204933Y496741D01*
X-1204801Y496420D01*
X-1204717Y496070D01*
X-1204688Y495706D01*
G01X-1198439Y497421D02*
X-1198221Y497247D01*
X-1198020Y497019D01*
X-1197847Y496741D01*
X-1197714Y496420D01*
X-1197631Y496070D01*
X-1197602Y495706D01*
G01X-1191353Y497421D02*
X-1191135Y497247D01*
X-1190933Y497019D01*
X-1190760Y496741D01*
X-1190628Y496420D01*
X-1190544Y496070D01*
X-1190515Y495706D01*
G01X-1184266Y497421D02*
X-1184048Y497247D01*
X-1183846Y497019D01*
X-1183674Y496741D01*
X-1183541Y496420D01*
X-1183457Y496070D01*
X-1183428Y495706D01*
G01X-1186529Y489941D02*
X-1185348Y488760D01*
G01X-1211775Y496278D02*
X-1211828Y496605D01*
X-1211984Y496919D01*
X-1212247Y497199D01*
X-1212613Y497421D01*
G01X-1204688Y496278D02*
X-1204741Y496605D01*
X-1204898Y496919D01*
X-1205160Y497199D01*
X-1205526Y497421D01*
G01X-1197602Y496278D02*
X-1197654Y496605D01*
X-1197811Y496919D01*
X-1198074Y497199D01*
X-1198439Y497421D01*
G01X-1190515Y496278D02*
X-1190568Y496605D01*
X-1190724Y496919D01*
X-1190987Y497199D01*
X-1191353Y497421D01*
G01X-1211775Y496278D02*
Y490335D01*
G01X-1207818Y496278D02*
Y490335D01*
G01X-1204688Y496278D02*
Y490335D01*
G01X-1200731Y496278D02*
Y490335D01*
G01X-1197602Y496278D02*
Y490335D01*
G01X-1193645Y496278D02*
Y490335D01*
G01X-1190515Y496278D02*
Y490335D01*
G01X-1183428Y496278D02*
X-1183481Y496605D01*
X-1183638Y496919D01*
X-1183900Y497199D01*
X-1184266Y497421D01*
G01X-1186558Y496278D02*
Y490335D01*
G01X-1186529Y492697D02*
Y489941D01*
G01X-1207818Y495706D02*
X-1207789Y496070D01*
X-1207705Y496420D01*
X-1207573Y496741D01*
X-1207400Y497019D01*
X-1207199Y497247D01*
X-1206981Y497421D01*
G01X-1200731Y495706D02*
X-1200703Y496070D01*
X-1200619Y496420D01*
X-1200487Y496741D01*
X-1200314Y497019D01*
X-1200112Y497247D01*
X-1199894Y497421D01*
G01X-1193645Y495706D02*
X-1193616Y496070D01*
X-1193532Y496420D01*
X-1193400Y496741D01*
X-1193227Y497019D01*
X-1193026Y497247D01*
X-1192807Y497421D01*
G01X-1186558Y495706D02*
X-1186530Y496070D01*
X-1186446Y496420D01*
X-1186313Y496741D01*
X-1186141Y497019D01*
X-1185939Y497247D01*
X-1185721Y497421D01*
G01X-1207818Y496278D02*
X-1207724Y496714D01*
X-1207443Y497114D01*
X-1206981Y497421D01*
G01X-1200731Y496278D02*
X-1200637Y496714D01*
X-1200356Y497114D01*
X-1199894Y497421D01*
G01X-1193645Y496278D02*
X-1193551Y496714D01*
X-1193269Y497114D01*
X-1192807Y497421D01*
G01X-1186558Y496278D02*
X-1186464Y496714D01*
X-1186183Y497114D01*
X-1185721Y497421D01*
G01X-1183458Y489941D02*
X-1184639Y488760D01*
G01X-1212613Y497421D02*
G03X-1214067I-727J-1386D01*
G01X-1212352Y496339D02*
G03I-709J0D01*
G01X-1198439Y497421D02*
G03X-1199894I-728J-1385D01*
G01X-1205526D02*
G03X-1206981I-727J-1385D01*
G01X-1198179Y496339D02*
G03I-709J0D01*
G01X-1184266Y497421D02*
G03X-1185721I-727J-1385D01*
G01X-1191353D02*
G03X-1192807I-727J-1386D01*
G01X-1184005Y496339D02*
G03I-709J0D01*
G01X-1212352Y500669D02*
G03I-709J0D01*
G01Y506181D02*
G03I-709J0D01*
G01Y510512D02*
G03I-709J0D01*
G01Y514843D02*
G03I-709J0D01*
G01Y520354D02*
G03I-709J0D01*
G01X-1198179Y500669D02*
G03I-709J0D01*
G01X-1205265Y501063D02*
G03I-709J0D01*
G01Y505394D02*
G03I-709J0D01*
G01X-1198179Y506181D02*
G03I-709J0D01*
G01X-1204285Y515650D02*
G03I-1968J0D01*
G01X-1197198D02*
G03I-1969J0D01*
G01X-1205265Y510905D02*
G03I-709J0D01*
G01X-1198179Y510512D02*
G03I-709J0D01*
G01Y514843D02*
G03I-709J0D01*
G01X-1205265Y515236D02*
G03I-709J0D01*
G01Y519567D02*
G03I-709J0D01*
G01X-1198179Y520354D02*
G03I-709J0D01*
G01X-1212352Y524685D02*
G03I-709J0D01*
G01X-1205265Y525079D02*
G03I-709J0D01*
G01X-1198179Y524685D02*
G03I-709J0D01*
G01X-1184005Y500669D02*
G03I-709J0D01*
G01X-1191092Y501063D02*
G03I-709J0D01*
G01Y505394D02*
G03I-709J0D01*
G01X-1190111Y515650D02*
G03I-1969J0D01*
G01X-1183025D02*
G03I-1968J0D01*
G01X-1184005Y506181D02*
G03I-709J0D01*
G01X-1191092Y510905D02*
G03I-709J0D01*
G01X-1184005Y510512D02*
G03I-709J0D01*
G01Y514843D02*
G03I-709J0D01*
G01X-1191092Y515236D02*
G03I-709J0D01*
G01Y519567D02*
G03I-709J0D01*
G01X-1184005Y520354D02*
G03I-709J0D01*
G01X-1191092Y525079D02*
G03I-709J0D01*
G01X-1184005Y524685D02*
G03I-709J0D01*
G01X-1180836Y487776D02*
X-1154458D01*
G01X-1178261Y488760D02*
X-1177552D01*
G01X-1176371Y489941D02*
X-1179442D01*
G01X-1154458Y491122D02*
X-1180836D01*
G01X-1165298Y492769D02*
X-1169255D01*
G01X-1172385D02*
X-1176342D01*
G01X-1179472D02*
X-1180836D01*
G01X-1175009Y496240D02*
X-1159261D01*
G01X-1159485Y496464D02*
X-1174786D01*
G01X-1164461Y497421D02*
X-1170093D01*
G01X-1177180D02*
X-1171548D01*
G01X-1158501Y497448D02*
X-1175770D01*
G01X-1174786Y496464D02*
X-1175004Y496488D01*
X-1175211Y496561D01*
X-1175397Y496677D01*
X-1175555Y496834D01*
X-1175672Y497020D01*
X-1175744Y497227D01*
X-1175770Y497448D01*
G01X-1177180Y497421D02*
X-1176952Y497299D01*
X-1176750Y497144D01*
X-1176581Y496957D01*
X-1176452Y496742D01*
X-1176371Y496506D01*
G01X-1177180Y497421D02*
X-1176961Y497247D01*
X-1176760Y497019D01*
X-1176587Y496741D01*
X-1176454Y496420D01*
X-1176371Y496070D01*
X-1176342Y495706D01*
G01X-1170093Y497421D02*
X-1169875Y497247D01*
X-1169673Y497019D01*
X-1169500Y496741D01*
X-1169368Y496420D01*
X-1169284Y496070D01*
X-1169255Y495706D01*
G01X-1179442Y489941D02*
X-1178261Y488760D01*
G01X-1176342Y496278D02*
X-1176350Y496401D01*
X-1176371Y496523D01*
G01X-1175993Y497224D02*
X-1175918Y496848D01*
X-1175705Y496528D01*
X-1175386Y496315D01*
X-1175009Y496240D01*
G01X-1169255Y496278D02*
X-1169308Y496605D01*
X-1169465Y496919D01*
X-1169727Y497199D01*
X-1170093Y497421D01*
G01X-1183458Y492697D02*
Y489941D01*
G01X-1183428Y496278D02*
Y490335D01*
G01X-1182018Y576489D02*
Y487776D01*
G01X-1180836Y584331D02*
Y487776D01*
G01X-1179472Y490335D02*
Y496278D01*
G01X-1179442Y489941D02*
Y500571D01*
G01X-1176371D02*
Y489941D01*
G01X-1176342Y496278D02*
Y490335D01*
G01X-1175993Y503130D02*
Y497224D01*
G01X-1175770Y502906D02*
Y497448D01*
G01X-1174786Y496464D02*
Y503891D01*
G01X-1172385Y490335D02*
Y496278D01*
G01X-1169255D02*
Y490335D01*
G01X-1174049Y562596D02*
X-1175269Y492697D01*
G01X-1173065Y562596D02*
X-1174285Y492697D01*
G01X-1179472Y496278D02*
X-1179464Y496402D01*
X-1179442Y496523D01*
G01X-1179472Y495706D02*
X-1179443Y496070D01*
X-1179359Y496420D01*
X-1179227Y496741D01*
X-1179054Y497019D01*
X-1178852Y497247D01*
X-1178634Y497421D01*
G01X-1172385Y495706D02*
X-1172356Y496070D01*
X-1172272Y496420D01*
X-1172140Y496741D01*
X-1171967Y497019D01*
X-1171766Y497247D01*
X-1171548Y497421D01*
G01X-1172385Y496278D02*
X-1172291Y496714D01*
X-1172009Y497114D01*
X-1171548Y497421D01*
G01X-1179442Y496506D02*
X-1179360Y496745D01*
X-1179231Y496961D01*
X-1179061Y497146D01*
X-1178860Y497300D01*
X-1178634Y497421D01*
G01X-1175993Y497224D02*
X-1175770Y497448D01*
G01X-1174786Y496464D02*
X-1175009Y496240D01*
G01X-1176371Y489941D02*
X-1177552Y488760D01*
G01X-1170093Y497421D02*
G03X-1171548I-727J-1385D01*
G01X-1177180D02*
G03X-1178634I-727J-1386D01*
G01X-1175009Y504114D02*
X-1175386Y504039D01*
X-1175705Y503826D01*
X-1175918Y503507D01*
X-1175993Y503130D01*
G01X-1180836Y500571D02*
X-1179442D01*
G01X-1176371D02*
X-1158182D01*
G01X-1175770Y502906D02*
X-1158501D01*
G01X-1159485Y503891D02*
X-1174786D01*
G01X-1159261Y504114D02*
X-1175009D01*
G01X-1166853Y506722D02*
X-1167418D01*
X-1167700Y506724D01*
X-1167982Y506727D01*
G01X-1170635Y511059D02*
X-1163635Y512759D01*
G01X-1175009Y528130D02*
X-1175386Y528055D01*
X-1175705Y527842D01*
X-1175918Y527522D01*
X-1175993Y527146D01*
G01X-1172318Y511062D02*
X-1161953Y512757D01*
G01X-1174786Y527906D02*
X-1175004Y527882D01*
X-1175211Y527809D01*
X-1175397Y527693D01*
X-1175555Y527536D01*
X-1175672Y527350D01*
X-1175744Y527143D01*
X-1175770Y526922D01*
G01X-1172046Y512759D02*
X-1172318Y512757D01*
G01X-1167982Y517092D02*
X-1167418Y517096D01*
G01X-1167560Y509309D02*
X-1166710D01*
G01X-1169735Y511485D02*
X-1168885D01*
G01Y512335D02*
X-1169735D01*
G01X-1170635Y512759D02*
X-1172046D01*
G01X-1166710Y514509D02*
X-1167560D01*
G01X-1175009Y520256D02*
X-1159261D01*
G01X-1159485Y520479D02*
X-1174786D01*
G01X-1158501Y521464D02*
X-1175770D01*
G01Y526922D02*
X-1158501D01*
G01X-1167418Y517096D02*
X-1166853D01*
X-1166570Y517095D01*
X-1166288Y517092D01*
G01X-1172318Y511062D02*
X-1172046Y511060D01*
X-1170635Y511059D01*
G01X-1172318Y512757D02*
X-1161953Y511062D01*
G01X-1170635Y512759D02*
X-1163635Y511059D01*
G01X-1168955Y510089D02*
X-1170635Y511059D01*
G01X-1168045Y511000D02*
X-1168885Y511485D01*
G01X-1175770Y502906D02*
X-1175993Y503130D01*
G01X-1175009Y504114D02*
X-1174786Y503891D01*
G01X-1165315Y510089D02*
X-1168955Y513729D01*
G01X-1175770Y526922D02*
X-1175993Y527146D01*
G01X-1167985Y508409D02*
X-1168955Y510089D01*
G01X-1168045Y511000D02*
X-1167560Y510159D01*
G01X-1166285Y508409D02*
X-1167985Y515409D01*
G01X-1175993Y521240D02*
X-1175918Y520863D01*
X-1175705Y520544D01*
X-1175386Y520331D01*
X-1175009Y520256D01*
G01X-1166288Y506727D02*
X-1167982Y517092D01*
G01X-1175770Y521464D02*
X-1175745Y521246D01*
X-1175673Y521039D01*
X-1175557Y520852D01*
X-1175400Y520694D01*
X-1175214Y520578D01*
X-1175007Y520505D01*
X-1174786Y520479D01*
G01X-1172318Y511062D02*
X-1172322Y511627D01*
Y512192D01*
X-1172318Y512757D01*
G01X-1167985Y506998D02*
X-1167984Y506863D01*
X-1167982Y506727D01*
G01X-1175993Y527146D02*
Y521240D01*
G01X-1175770Y521464D02*
Y526922D01*
G01X-1174786Y520479D02*
Y527906D01*
G01X-1169735Y512335D02*
Y511485D01*
G01X-1167985Y508409D02*
Y506998D01*
G01X-1167560Y514509D02*
Y513659D01*
G01Y510159D02*
Y509309D01*
G01X-1167982Y517092D02*
X-1167984Y516956D01*
X-1167985Y516820D01*
Y515409D01*
G01X-1175770Y502906D02*
X-1175745Y503124D01*
X-1175673Y503331D01*
X-1175557Y503518D01*
X-1175400Y503676D01*
X-1175214Y503792D01*
X-1175007Y503865D01*
X-1174786Y503891D01*
G01X-1167982Y506727D02*
X-1166288Y517092D01*
G01X-1167985Y508409D02*
X-1166285Y515409D01*
G01X-1168955Y513729D02*
X-1167985Y515409D01*
G01X-1168045Y512819D02*
X-1167560Y513659D01*
G01X-1175993Y521240D02*
X-1175770Y521464D01*
G01X-1174786Y520479D02*
X-1175009Y520256D01*
G01X-1168955Y510089D02*
X-1165315Y513729D01*
G01X-1170635Y512759D02*
X-1168955Y513729D01*
G01X-1168045Y512819D02*
X-1168885Y512335D01*
G01X-1175938Y515650D02*
G03I-1969J0D01*
G01X-1168852D02*
G03I-1968J0D01*
G01X-1158785Y511909D02*
G03I-8350J0D01*
G01X-1162115D02*
G03I-5020J0D01*
G01X-1167985Y516684D02*
G03X-1171910Y512759I850J-4775D01*
G01Y511059D02*
G03X-1167985Y507135I4775J851D01*
G01X-1162706Y511909D02*
G03I-4429J0D01*
G01X-1162835D02*
G03I-4300J0D01*
G01X-1163444D02*
G03I-3691J0D01*
G01X-1226525Y529016D02*
G03I-709J0D01*
G01X-1219439Y529409D02*
G03I-708J0D01*
G01X-1225741Y552187D02*
X-1222198D01*
G01X-1218655D02*
X-1215111D01*
G01X-1216293Y554232D02*
X-1217474D01*
G01X-1223379D02*
X-1224560D01*
G01X-1230466D02*
X-1231647D01*
G01X-1230466D02*
X-1229088Y551846D01*
G01X-1223379Y554232D02*
X-1222001Y551846D01*
G01X-1216293Y554232D02*
X-1214915Y551846D01*
G01X-1232237Y555236D02*
Y531811D01*
G01X-1229088Y551846D02*
Y535335D01*
G01X-1225938D02*
Y551846D01*
G01X-1222001D02*
Y535335D01*
G01X-1218852D02*
Y551846D01*
G01X-1214915D02*
Y535335D01*
G01X-1225938Y551846D02*
X-1224560Y554232D01*
G01X-1218852Y551846D02*
X-1217474Y554232D01*
G01X-1229088Y535335D02*
G03X-1225938I1575J0D01*
G01X-1222001D02*
G03X-1218852I1575J0D01*
G01X-1226525Y534528D02*
G03I-709J0D01*
G01Y538858D02*
G03I-709J0D01*
G01Y543189D02*
G03I-709J0D01*
G01X-1214915Y535335D02*
G03X-1211765I1575J0D01*
G01X-1219439Y533740D02*
G03I-708J0D01*
G01Y539252D02*
G03I-708J0D01*
G01Y543583D02*
G03I-708J0D01*
G01Y547913D02*
G03I-708J0D01*
G01X-1226525Y548701D02*
G03I-709J0D01*
G01X-1219439Y553425D02*
G03I-708J0D01*
G01Y557756D02*
G03I-708J0D01*
G01X-1226209Y575308D02*
X-1226133Y575325D01*
X-1226069Y575367D01*
X-1226027Y575431D01*
X-1226012Y575505D01*
G01X-1227197Y575903D02*
X-1227117Y575916D01*
X-1227041Y575940D01*
X-1226971Y575974D01*
X-1226910Y576017D01*
X-1226861Y576068D01*
X-1226828Y576123D01*
X-1226809Y576181D01*
G01X-1227378Y576932D02*
X-1227372Y576933D01*
X-1227363D01*
X-1227355Y576935D01*
X-1227347D01*
X-1227339Y576937D01*
X-1227330Y576938D01*
G01X-1226012Y564921D02*
X-1229595D01*
G01X-1215422D02*
X-1211839D01*
G01X-1212351Y566417D02*
X-1214910D01*
G01X-1219437D02*
X-1221996D01*
G01X-1226524D02*
X-1229083D01*
G01X-1221996Y568055D02*
X-1226524D01*
G01X-1219437D02*
X-1214910D01*
G01Y568252D02*
X-1219437D01*
G01X-1221996D02*
X-1226524D01*
G01X-1214910Y570354D02*
X-1216190D01*
G01X-1229083D02*
X-1230363D01*
G01X-1231012Y570379D02*
X-1229083D01*
G01X-1216839D02*
X-1214910D01*
G01X-1212744Y570748D02*
X-1214516D01*
G01X-1214910D02*
X-1216190D01*
G01X-1219831D02*
X-1221603D01*
G01X-1226394D02*
X-1226524D01*
G01X-1229083D02*
X-1230363D01*
G01X-1226918D02*
X-1228689D01*
G01X-1231012Y570761D02*
X-1229083D01*
G01X-1216839D02*
X-1214910D01*
G01X-1230320Y570945D02*
X-1229083D01*
G01X-1216147D02*
X-1214910D01*
G01Y571142D02*
X-1217601D01*
G01X-1231774D02*
X-1229083D01*
G01X-1230245Y571679D02*
X-1229083D01*
G01X-1216072D02*
X-1214910D01*
G01X-1230633Y571876D02*
X-1229083D01*
G01X-1216460D02*
X-1214910D01*
G01X-1212036Y575308D02*
X-1215225D01*
G01X-1226209D02*
X-1229398D01*
G01X-1231774Y575624D02*
X-1226394D01*
G01X-1217601D02*
X-1212221D01*
G01X-1211839Y575728D02*
X-1215422D01*
G01X-1226012D02*
X-1229595D01*
G01X-1230971Y575903D02*
X-1227197D01*
G01X-1216798D02*
X-1213024D01*
G01X-1217216Y575926D02*
X-1217604D01*
G01X-1231389D02*
X-1231777D01*
G01X-1226779D02*
X-1226391D01*
G01X-1218926Y576489D02*
X-1222508D01*
G01X-1213205Y576932D02*
X-1216617D01*
G01X-1227378D02*
X-1230790D01*
G01X-1231177Y577210D02*
X-1226991D01*
G01X-1217004D02*
X-1212818D01*
G01X-1223487Y565433D02*
X-1223533Y565438D01*
X-1223578Y565455D01*
X-1223618Y565483D01*
X-1223652Y565521D01*
X-1223680Y565566D01*
G01X-1229398Y575308D02*
X-1229444Y575314D01*
X-1229490Y575331D01*
X-1229531Y575360D01*
X-1229564Y575399D01*
X-1229587Y575448D01*
X-1229595Y575505D01*
G01X-1215225Y575308D02*
X-1215271Y575314D01*
X-1215317Y575331D01*
X-1215357Y575360D01*
X-1215391Y575399D01*
X-1215413Y575448D01*
X-1215422Y575505D01*
G01X-1216798Y575903D02*
X-1216878Y575916D01*
X-1216954Y575940D01*
X-1217024Y575974D01*
X-1217085Y576017D01*
X-1217133Y576068D01*
X-1217167Y576123D01*
X-1217185Y576181D01*
G01X-1230837Y576938D02*
X-1230831Y576937D01*
X-1230815Y576935D01*
X-1230806Y576934D01*
X-1230790Y576932D01*
G01X-1216664Y576938D02*
X-1216650Y576936D01*
X-1216641Y576935D01*
X-1216617Y576932D01*
G01X-1230363Y570354D02*
X-1230670Y570415D01*
X-1230934Y570590D01*
X-1231105Y570849D01*
X-1231163Y571142D01*
G01X-1216190Y570354D02*
X-1216497Y570415D01*
X-1216761Y570590D01*
X-1216932Y570849D01*
X-1216990Y571142D01*
G01X-1230363Y570748D02*
X-1230572Y570802D01*
X-1230722Y570949D01*
X-1230775Y571142D01*
G01X-1216190Y570748D02*
X-1216399Y570802D01*
X-1216549Y570949D01*
X-1216602Y571142D01*
G01X-1227330Y576938D02*
X-1227247Y576960D01*
X-1227170Y576993D01*
X-1227103Y577037D01*
X-1227049Y577090D01*
X-1227011Y577149D01*
X-1226991Y577210D01*
G01X-1230708Y571142D02*
X-1230688Y571102D01*
X-1230654Y571063D01*
X-1230605Y571028D01*
X-1230545Y570998D01*
X-1230476Y570973D01*
X-1230400Y570955D01*
X-1230320Y570945D01*
G01X-1230633Y571876D02*
X-1230613Y571836D01*
X-1230579Y571798D01*
X-1230530Y571763D01*
X-1230470Y571732D01*
X-1230401Y571707D01*
X-1230325Y571690D01*
X-1230245Y571679D01*
G01X-1216535Y571142D02*
X-1216515Y571102D01*
X-1216480Y571063D01*
X-1216432Y571028D01*
X-1216372Y570998D01*
X-1216302Y570973D01*
X-1216227Y570955D01*
X-1216147Y570945D01*
G01X-1216460Y571876D02*
X-1216440Y571836D01*
X-1216405Y571798D01*
X-1216357Y571763D01*
X-1216297Y571732D01*
X-1216228Y571707D01*
X-1216152Y571690D01*
X-1216072Y571679D01*
G01X-1231177Y577210D02*
X-1231157Y577149D01*
X-1231120Y577091D01*
X-1231067Y577039D01*
X-1231000Y576994D01*
X-1230922Y576960D01*
X-1230837Y576938D01*
G01X-1231359Y576181D02*
X-1231341Y576124D01*
X-1231307Y576069D01*
X-1231259Y576018D01*
X-1231199Y575975D01*
X-1231128Y575940D01*
X-1231052Y575916D01*
X-1230971Y575903D01*
G01X-1227197D02*
X-1227175Y575820D01*
X-1227161Y575725D01*
X-1227156Y575624D01*
G01X-1231777Y575926D02*
X-1231775Y575822D01*
Y575722D01*
X-1231774Y575624D01*
G01X-1226776Y575724D02*
X-1226777Y575826D01*
X-1226779Y575926D01*
G01X-1231777Y599292D02*
Y575926D01*
G01X-1231774Y575624D02*
Y571142D01*
G01X-1231389Y599292D02*
Y575926D01*
G01X-1231177Y577210D02*
Y599292D01*
G01X-1231163Y571142D02*
Y601023D01*
G01X-1231012Y570379D02*
Y575624D01*
G01X-1230790Y576932D02*
Y599292D01*
G01X-1230775Y571142D02*
Y601023D01*
G01X-1230633D02*
Y571876D01*
G01X-1230363Y570748D02*
Y570354D01*
G01X-1230320Y570945D02*
Y570748D01*
G01X-1230245Y571679D02*
Y601023D01*
G01X-1229595Y575728D02*
Y564842D01*
G01X-1229398Y575308D02*
Y565433D01*
G01X-1229083Y571876D02*
Y566417D01*
G01X-1217004Y577210D02*
X-1216984Y577149D01*
X-1216947Y577091D01*
X-1216893Y577039D01*
X-1216827Y576994D01*
X-1216748Y576960D01*
X-1216664Y576938D01*
G01X-1229595Y565630D02*
X-1229580Y565556D01*
X-1229537Y565491D01*
X-1229473Y565449D01*
X-1229398Y565433D01*
G01X-1222508Y565630D02*
X-1222493Y565556D01*
X-1222451Y565491D01*
X-1222387Y565449D01*
X-1222311Y565433D01*
G01X-1215422Y565630D02*
X-1215407Y565556D01*
X-1215364Y565491D01*
X-1215300Y565449D01*
X-1215225Y565433D01*
G01X-1227197Y575903D02*
X-1227378Y576932D01*
G01X-1226991Y577210D02*
X-1226809Y576181D01*
G01D02*
X-1226797Y576104D01*
X-1226787Y576018D01*
X-1226779Y575926D01*
G01X-1230708Y571142D02*
X-1230698Y571055D01*
X-1230670Y570972D01*
X-1230624Y570897D01*
X-1230562Y570834D01*
X-1230489Y570787D01*
X-1230407Y570758D01*
X-1230320Y570748D01*
G01X-1216535Y571142D02*
X-1216525Y571055D01*
X-1216496Y570972D01*
X-1216451Y570897D01*
X-1216389Y570834D01*
X-1216316Y570787D01*
X-1216234Y570758D01*
X-1216147Y570748D01*
G01X-1217604Y575926D02*
X-1217602Y575822D01*
Y575722D01*
X-1217601Y575624D01*
G01X-1227883Y570748D02*
Y601023D01*
G01X-1227496D02*
Y570748D01*
G01X-1227378Y576932D02*
Y599292D01*
G01X-1227354Y601023D02*
Y570748D01*
G01X-1227156D02*
Y575624D01*
G01X-1226991Y577210D02*
Y599292D01*
G01X-1226966Y601023D02*
Y570748D01*
G01X-1226779Y575926D02*
Y599292D01*
G01X-1226776Y575724D02*
X-1226775Y570721D01*
G01X-1226524Y570354D02*
Y566417D01*
G01X-1226394Y570748D02*
Y575624D01*
G01X-1226391Y575926D02*
Y599292D01*
G01X-1226209Y565433D02*
Y575308D01*
G01X-1226012Y564842D02*
Y575728D01*
G01X-1223684Y565566D02*
Y564842D01*
G01X-1223674Y600472D02*
Y565566D01*
G01X-1223487Y565433D02*
Y600472D01*
G01X-1222508Y576489D02*
Y564842D01*
G01X-1222311Y576489D02*
Y565433D01*
G01X-1221996Y570354D02*
Y566417D01*
G01X-1219747Y600472D02*
Y576489D01*
G01X-1219437Y570354D02*
Y566417D01*
G01X-1219122Y576489D02*
Y565433D01*
G01X-1218937Y576489D02*
X-1218936Y565566D01*
G01X-1218926Y564842D02*
Y576489D01*
G01X-1217604Y599292D02*
Y575926D01*
G01X-1217601Y575624D02*
Y571142D01*
G01X-1217216Y599292D02*
Y575926D01*
G01X-1217004Y577210D02*
Y599292D01*
G01X-1216990Y571142D02*
Y601023D01*
G01X-1216839Y570379D02*
Y575624D01*
G01X-1216617Y576932D02*
Y599292D01*
G01X-1216602Y571142D02*
Y601023D01*
G01X-1216460D02*
Y571876D01*
G01X-1216190Y570748D02*
Y570354D01*
G01X-1216147Y570945D02*
Y570748D01*
G01X-1216072Y571679D02*
Y601023D01*
G01X-1215422Y575728D02*
Y564842D01*
G01X-1215225Y575308D02*
Y565433D01*
G01X-1214910Y571876D02*
Y566417D01*
G01X-1226518Y570329D02*
Y570748D01*
G01X-1226394Y575624D02*
X-1226392Y575926D01*
G01X-1231389D02*
X-1231391Y575829D01*
X-1231393Y575728D01*
Y571142D01*
G01X-1217216Y575926D02*
X-1217218Y575829D01*
X-1217219Y575728D01*
X-1217220Y571142D01*
G01X-1231012Y575624D02*
X-1231007Y575725D01*
X-1230993Y575820D01*
X-1230971Y575903D01*
G01X-1216839Y575624D02*
X-1216834Y575725D01*
X-1216820Y575820D01*
X-1216798Y575903D01*
G01X-1231389Y575926D02*
X-1231381Y576018D01*
X-1231371Y576104D01*
X-1231359Y576181D01*
G01X-1230633Y571876D02*
X-1230708Y571142D01*
G01X-1230320Y570945D02*
X-1230245Y571679D01*
G01X-1216460Y571876D02*
X-1216535Y571142D01*
G01X-1216147Y570945D02*
X-1216072Y571679D01*
G01X-1217185Y576181D02*
X-1217198Y576104D01*
X-1217207Y576018D01*
X-1217216Y575926D01*
G01X-1231359Y576181D02*
X-1231177Y577210D01*
G01X-1230790Y576932D02*
X-1230971Y575903D01*
G01X-1226012Y565630D02*
X-1226027Y565556D01*
X-1226070Y565491D01*
X-1226134Y565449D01*
X-1226209Y565433D01*
G01X-1217185Y576181D02*
X-1217004Y577210D01*
G01X-1216617Y576932D02*
X-1216798Y575903D01*
G01X-1218926Y565630D02*
X-1218940Y565556D01*
X-1218983Y565491D01*
X-1219047Y565449D01*
X-1219122Y565433D01*
G01X-1218931Y565566D02*
X-1218974Y565500D01*
X-1219038Y565451D01*
X-1219122Y565433D01*
G01X-1231774Y571142D02*
G03X-1231012Y570379I762J-1D01*
G01X-1226524Y570354D02*
G03X-1226918Y570748I-394J0D01*
G01X-1228689D02*
G03X-1229083Y570354I0J-394D01*
G01X-1221603Y570748D02*
G03X-1221996Y570354I0J-393D01*
G01X-1231393Y571142D02*
G03X-1231012Y570761I381J0D01*
G01X-1217601Y571142D02*
G03X-1216839Y570379I762J-1D01*
G01X-1214516Y570748D02*
G03X-1214910Y570354I0J-394D01*
G01X-1219437D02*
G03X-1219831Y570748I-394J0D01*
G01X-1217220Y571142D02*
G03X-1216839Y570761I381J0D01*
G01X-1212352Y529016D02*
G03I-709J0D01*
G01X-1205265Y529409D02*
G03I-709J0D01*
G01X-1198179Y529016D02*
G03I-709J0D01*
G01X-1191092Y529409D02*
G03I-709J0D01*
G01X-1184005Y529016D02*
G03I-709J0D01*
G01X-1183615Y530827D02*
X-1186371D01*
G01X-1182631Y533350D02*
X-1187355D01*
G01X-1184245Y536928D02*
X-1185741D01*
G01X-1211568Y552187D02*
X-1208025D01*
G01X-1204481D02*
X-1200938D01*
G01X-1187946Y554232D02*
X-1189127D01*
G01X-1195033D02*
X-1196214D01*
G01X-1209206D02*
X-1210387D01*
G01X-1203300D02*
X-1202119D01*
G01X-1209206D02*
X-1207828Y551846D01*
G01X-1202119Y554232D02*
X-1200741Y551846D01*
G01X-1186529Y538292D02*
X-1185741Y536928D01*
G01X-1195033Y554232D02*
X-1193655Y551846D01*
G01X-1187946Y554232D02*
X-1186568Y551846D01*
G01X-1211765Y535335D02*
Y551846D01*
G01X-1207828D02*
Y535335D01*
G01X-1204678D02*
Y551846D01*
G01X-1200741D02*
Y535335D01*
G01X-1197592D02*
Y551846D01*
G01X-1193655D02*
Y535335D01*
G01X-1190505D02*
Y551846D01*
G01X-1187355Y555236D02*
Y531811D01*
G01X-1186568Y551846D02*
Y549568D01*
G01Y547909D02*
Y542246D01*
G01Y540587D02*
Y535335D01*
G01X-1186529Y555236D02*
Y549629D01*
G01Y547849D02*
Y542306D01*
G01Y540526D02*
Y538292D01*
G01X-1211765Y551846D02*
X-1210387Y554232D01*
G01X-1204678Y551846D02*
X-1203300Y554232D01*
G01X-1197592Y551846D02*
X-1196214Y554232D01*
G01X-1190505Y551846D02*
X-1189127Y554232D01*
G01X-1183458Y538292D02*
X-1184245Y536928D01*
G01X-1212352Y534528D02*
G03I-709J0D01*
G01Y538858D02*
G03I-709J0D01*
G01Y543189D02*
G03I-709J0D01*
G01X-1207828Y535335D02*
G03X-1204678I1575J0D01*
G01X-1200741D02*
G03X-1197592I1574J0D01*
G01X-1198179Y534528D02*
G03I-709J0D01*
G01X-1205265Y533740D02*
G03I-709J0D01*
G01Y539252D02*
G03I-709J0D01*
G01X-1198179Y538858D02*
G03I-709J0D01*
G01X-1205265Y543583D02*
G03I-709J0D01*
G01X-1198179Y543189D02*
G03I-709J0D01*
G01X-1205265Y547913D02*
G03I-709J0D01*
G01X-1212352Y548701D02*
G03I-709J0D01*
G01X-1198179D02*
G03I-709J0D01*
G01X-1205265Y553425D02*
G03I-709J0D01*
G01Y557756D02*
G03I-709J0D01*
G01X-1193655Y535335D02*
G03X-1190505I1575J0D01*
G01X-1186568D02*
G03X-1183418I1575J0D01*
G01X-1187355Y531811D02*
G03X-1186371Y530827I984J0D01*
G01X-1184005Y534528D02*
G03I-709J0D01*
G01X-1191092Y533740D02*
G03I-709J0D01*
G01Y539252D02*
G03I-709J0D01*
G01X-1184005Y538858D02*
G03I-709J0D01*
G01X-1191092Y543583D02*
G03I-709J0D01*
G01Y547913D02*
G03I-709J0D01*
G01Y553425D02*
G03I-709J0D01*
G01X-1186529Y542306D02*
G03Y540526I1299J-890D01*
G01X-1184005Y543189D02*
G03I-709J0D01*
G01X-1186529Y549629D02*
G03Y547849I1299J-890D01*
G01X-1184005Y548701D02*
G03I-709J0D01*
G01X-1191092Y557756D02*
G03I-709J0D01*
G01X-1184811Y576938D02*
X-1184728Y576960D01*
X-1184650Y576993D01*
X-1184583Y577037D01*
X-1184530Y577090D01*
X-1184491Y577149D01*
X-1184471Y577210D01*
G01X-1198984Y576938D02*
X-1198901Y576960D01*
X-1198824Y576993D01*
X-1198756Y577037D01*
X-1198703Y577090D01*
X-1198664Y577149D01*
X-1198644Y577210D01*
G01X-1213157Y576938D02*
X-1213074Y576960D01*
X-1212997Y576993D01*
X-1212930Y577037D01*
X-1212876Y577090D01*
X-1212837Y577149D01*
X-1212818Y577210D01*
G01X-1197863Y575308D02*
X-1197786Y575325D01*
X-1197723Y575367D01*
X-1197680Y575431D01*
X-1197666Y575505D01*
G01X-1212036Y575308D02*
X-1211959Y575325D01*
X-1211896Y575367D01*
X-1211854Y575431D01*
X-1211839Y575505D01*
G01X-1184677Y575903D02*
X-1184597Y575916D01*
X-1184521Y575940D01*
X-1184451Y575974D01*
X-1184391Y576017D01*
X-1184342Y576068D01*
X-1184308Y576123D01*
X-1184290Y576181D01*
G01X-1184859Y576932D02*
X-1184852Y576933D01*
X-1184844D01*
X-1184835Y576935D01*
X-1184828D01*
X-1184819Y576937D01*
X-1184811Y576938D01*
G01X-1199032Y576932D02*
X-1199025Y576933D01*
X-1199017D01*
X-1199009Y576935D01*
X-1199001D01*
X-1198993Y576937D01*
X-1198984Y576938D01*
G01X-1213205Y576932D02*
X-1213198Y576933D01*
X-1213190D01*
X-1213182Y576935D01*
X-1213174D01*
X-1213166Y576937D01*
X-1213157Y576938D01*
G01X-1197666Y564921D02*
X-1201248D01*
G01X-1187075D02*
X-1183493D01*
G01X-1184004Y566417D02*
X-1186563D01*
G01X-1191091D02*
X-1193650D01*
G01X-1198178D02*
X-1200737D01*
G01X-1205264D02*
X-1207823D01*
G01X-1184103Y566654D02*
X-1186465D01*
G01X-1212351Y568055D02*
X-1207823D01*
G01X-1205264D02*
X-1200737D01*
G01X-1198178D02*
X-1193650D01*
G01X-1191091D02*
X-1186563D01*
G01X-1184103Y568228D02*
X-1186465D01*
G01X-1186563Y568252D02*
X-1191091D01*
G01X-1193650D02*
X-1198178D01*
G01X-1200737D02*
X-1205264D01*
G01X-1207823D02*
X-1212351D01*
G01X-1186465Y569733D02*
X-1184103D01*
G01X-1186563Y570354D02*
X-1187844D01*
G01X-1200737D02*
X-1202017D01*
G01X-1202665Y570379D02*
X-1200737D01*
G01X-1188492D02*
X-1186563D01*
G01X-1184103Y570591D02*
X-1186465D01*
G01X-1186563Y570748D02*
X-1187844D01*
G01X-1191485D02*
X-1193256D01*
G01X-1198047D02*
X-1198178D01*
G01X-1198571D02*
X-1200343D01*
G01X-1200737D02*
X-1202017D01*
G01X-1205658D02*
X-1207430D01*
G01X-1212220D02*
X-1212351D01*
G01X-1186170D02*
X-1184398D01*
G01X-1202665Y570761D02*
X-1200737D01*
G01X-1188492D02*
X-1186563D01*
G01X-1201974Y570945D02*
X-1200737D01*
G01X-1187800D02*
X-1186563D01*
G01Y571142D02*
X-1189254D01*
G01X-1200737D02*
X-1203428D01*
G01X-1201899Y571679D02*
X-1200737D01*
G01X-1187726D02*
X-1186563D01*
G01X-1202287Y571876D02*
X-1200737D01*
G01X-1188113D02*
X-1186563D01*
G01X-1186930Y574646D02*
X-1183639D01*
G01X-1187075Y575059D02*
X-1183493D01*
G01X-1183689Y575308D02*
X-1186878D01*
G01X-1197863D02*
X-1201052D01*
G01X-1203428Y575624D02*
X-1198048D01*
G01X-1189254D02*
X-1183874D01*
G01X-1183493Y575728D02*
X-1187075D01*
G01X-1197666D02*
X-1201248D01*
G01X-1202625Y575903D02*
X-1198850D01*
G01X-1188452D02*
X-1184677D01*
G01X-1183872Y575926D02*
X-1184259D01*
G01X-1188869D02*
X-1189257D01*
G01X-1203043D02*
X-1203430D01*
G01X-1212606D02*
X-1212218D01*
G01X-1198433D02*
X-1198045D01*
G01X-1190579Y576489D02*
X-1194162D01*
G01X-1204752D02*
X-1208335D01*
G01X-1184859Y576932D02*
X-1188270D01*
G01X-1199032D02*
X-1202443D01*
G01X-1202831Y577210D02*
X-1198644D01*
G01X-1188657D02*
X-1184471D01*
G01X-1209314Y565433D02*
X-1209359Y565438D01*
X-1209404Y565455D01*
X-1209445Y565483D01*
X-1209478Y565521D01*
X-1209506Y565566D01*
G01X-1195141Y565433D02*
X-1195186Y565438D01*
X-1195231Y565455D01*
X-1195272Y565483D01*
X-1195305Y565521D01*
X-1195333Y565566D01*
G01X-1201052Y575308D02*
X-1201098Y575314D01*
X-1201144Y575331D01*
X-1201184Y575360D01*
X-1201217Y575399D01*
X-1201240Y575448D01*
X-1201248Y575505D01*
G01X-1186878Y575308D02*
X-1186925Y575314D01*
X-1186970Y575331D01*
X-1187011Y575360D01*
X-1187044Y575399D01*
X-1187067Y575448D01*
X-1187075Y575505D01*
G01X-1202625Y575903D02*
X-1202705Y575916D01*
X-1202781Y575940D01*
X-1202851Y575974D01*
X-1202911Y576017D01*
X-1202960Y576068D01*
X-1202994Y576123D01*
X-1203012Y576181D01*
G01X-1188452Y575903D02*
X-1188531Y575916D01*
X-1188608Y575940D01*
X-1188678Y575974D01*
X-1188738Y576017D01*
X-1188787Y576068D01*
X-1188821Y576123D01*
X-1188839Y576181D01*
G01X-1202491Y576938D02*
X-1202484Y576937D01*
X-1202452Y576933D01*
X-1202443Y576932D01*
G01X-1188318Y576938D02*
X-1188311Y576937D01*
X-1188287Y576934D01*
X-1188278Y576933D01*
X-1188270Y576932D01*
G01X-1202017Y570354D02*
X-1202324Y570415D01*
X-1202587Y570590D01*
X-1202759Y570849D01*
X-1202817Y571142D01*
G01X-1187844Y570354D02*
X-1188151Y570415D01*
X-1188414Y570590D01*
X-1188586Y570849D01*
X-1188643Y571142D01*
G01X-1202017Y570748D02*
X-1202226Y570802D01*
X-1202376Y570949D01*
X-1202429Y571142D01*
G01X-1187844Y570748D02*
X-1188052Y570802D01*
X-1188202Y570949D01*
X-1188255Y571142D01*
G01X-1186926Y565440D02*
X-1186910Y565436D01*
X-1186894Y565434D01*
X-1186878Y565433D01*
G01X-1187075Y565518D02*
X-1187044Y565485D01*
X-1187007Y565461D01*
X-1186967Y565446D01*
X-1186926Y565440D01*
G01X-1202361Y571142D02*
X-1202342Y571102D01*
X-1202307Y571063D01*
X-1202259Y571028D01*
X-1202198Y570998D01*
X-1202129Y570973D01*
X-1202054Y570955D01*
X-1201974Y570945D01*
G01X-1202287Y571876D02*
X-1202267Y571836D01*
X-1202232Y571798D01*
X-1202184Y571763D01*
X-1202124Y571732D01*
X-1202054Y571707D01*
X-1201979Y571690D01*
X-1201899Y571679D01*
G01X-1188188Y571142D02*
X-1188168Y571102D01*
X-1188134Y571063D01*
X-1188085Y571028D01*
X-1188025Y570998D01*
X-1187956Y570973D01*
X-1187880Y570955D01*
X-1187800Y570945D01*
G01X-1188113Y571876D02*
X-1188094Y571836D01*
X-1188059Y571798D01*
X-1188011Y571763D01*
X-1187950Y571732D01*
X-1187881Y571707D01*
X-1187805Y571690D01*
X-1187726Y571679D01*
G01X-1202831Y577210D02*
X-1202811Y577149D01*
X-1202774Y577091D01*
X-1202720Y577039D01*
X-1202654Y576994D01*
X-1202575Y576960D01*
X-1202491Y576938D01*
G01X-1188657Y577210D02*
X-1188638Y577149D01*
X-1188600Y577091D01*
X-1188547Y577039D01*
X-1188480Y576994D01*
X-1188402Y576960D01*
X-1188318Y576938D01*
G01X-1213024Y575903D02*
X-1213002Y575820D01*
X-1212988Y575725D01*
X-1212983Y575624D01*
G01X-1198850Y575903D02*
X-1198828Y575820D01*
X-1198815Y575725D01*
X-1198810Y575624D01*
G01X-1208335Y565630D02*
X-1208320Y565556D01*
X-1208278Y565491D01*
X-1208213Y565449D01*
X-1208138Y565433D01*
G01X-1201248Y565630D02*
X-1201233Y565556D01*
X-1201191Y565491D01*
X-1201127Y565449D01*
X-1201052Y565433D01*
G01X-1194162Y565630D02*
X-1194147Y565556D01*
X-1194104Y565491D01*
X-1194040Y565449D01*
X-1193965Y565433D01*
G01X-1213024Y575903D02*
X-1213205Y576932D01*
G01X-1212818Y577210D02*
X-1212636Y576181D01*
G01X-1212606Y575926D02*
X-1212614Y576018D01*
X-1212624Y576104D01*
X-1212636Y576181D01*
G01X-1198433Y575926D02*
X-1198441Y576018D01*
X-1198451Y576104D01*
X-1198463Y576181D01*
G01X-1184259Y575926D02*
X-1184268Y576018D01*
X-1184278Y576104D01*
X-1184290Y576181D01*
G01X-1184637Y575624D02*
X-1184641Y575725D01*
X-1184655Y575820D01*
X-1184677Y575903D01*
G01X-1186918Y564842D02*
X-1186926Y565439D01*
G01X-1212602Y575724D02*
X-1212604Y575826D01*
X-1212606Y575926D01*
G01X-1203430D02*
X-1203429Y575822D01*
Y575722D01*
X-1203428Y575624D01*
G01X-1198429Y575724D02*
X-1198430Y575826D01*
X-1198433Y575926D01*
G01X-1189257D02*
X-1189255Y575822D01*
Y575722D01*
X-1189254Y575624D01*
G01X-1213710Y570748D02*
Y601023D01*
G01X-1213322D02*
Y570748D01*
G01X-1213205Y576932D02*
Y599292D01*
G01X-1213180Y601023D02*
Y570748D01*
G01X-1212983D02*
Y575624D01*
G01X-1212818Y599292D02*
Y577210D01*
G01X-1212793Y601023D02*
Y570748D01*
G01X-1212606Y575926D02*
Y599292D01*
G01X-1212602Y575724D02*
Y570721D01*
G01X-1212351Y570354D02*
Y566417D01*
G01X-1212221Y570748D02*
Y575624D01*
G01X-1212218Y575926D02*
Y599292D01*
G01X-1212036Y565433D02*
Y575308D01*
G01X-1211839Y564842D02*
Y575728D01*
G01X-1209511Y565566D02*
Y564842D01*
G01X-1209501Y600472D02*
Y565566D01*
G01X-1209314Y565433D02*
Y600472D01*
G01X-1208335Y576489D02*
Y564842D01*
G01X-1208138Y576489D02*
Y565433D01*
G01X-1207823Y570354D02*
Y566417D01*
G01X-1205574Y600472D02*
Y576489D01*
G01X-1205264Y570354D02*
Y566417D01*
G01X-1204949Y576489D02*
Y565433D01*
G01X-1204764Y576489D02*
X-1204763Y565566D01*
G01X-1204752Y564842D02*
Y576489D01*
G01X-1203430Y599292D02*
Y575926D01*
G01X-1203428Y575624D02*
Y571142D01*
G01X-1203043Y599292D02*
Y575926D01*
G01X-1202831Y577210D02*
Y599292D01*
G01X-1202817Y571142D02*
Y601023D01*
G01X-1202665Y570379D02*
Y575624D01*
G01X-1202443Y576932D02*
Y599292D01*
G01X-1202429Y571142D02*
Y601023D01*
G01X-1202287D02*
Y571876D01*
G01X-1202017Y570748D02*
Y570354D01*
G01X-1201974Y570945D02*
Y570748D01*
G01X-1201899Y571679D02*
Y601023D01*
G01X-1201248Y575728D02*
Y564842D01*
G01X-1201052Y575308D02*
Y565433D01*
G01X-1200737Y571876D02*
Y566417D01*
G01X-1199537Y570748D02*
Y601023D01*
G01X-1199149D02*
Y570748D01*
G01X-1199032Y576932D02*
Y599292D01*
G01X-1199007Y601023D02*
Y570748D01*
G01X-1198810D02*
Y575624D01*
G01X-1198644Y599292D02*
Y577210D01*
G01X-1198619Y601023D02*
Y570748D01*
G01X-1198433Y575926D02*
Y599292D01*
G01X-1198429Y575724D02*
Y570721D01*
G01X-1198178Y570354D02*
Y566417D01*
G01X-1198048Y570748D02*
Y575624D01*
G01X-1198045Y575926D02*
Y599292D01*
G01X-1197863Y565433D02*
Y575308D01*
G01X-1197666Y564842D02*
Y575728D01*
G01X-1195338Y565566D02*
Y564842D01*
G01X-1195328Y600472D02*
Y565566D01*
G01X-1195141Y565433D02*
Y600472D01*
G01X-1194162Y576489D02*
Y564842D01*
G01X-1193965Y576489D02*
Y565433D01*
G01X-1193650Y570354D02*
Y566417D01*
G01X-1191401Y600472D02*
Y576489D01*
G01X-1191091Y570354D02*
Y566417D01*
G01X-1190776Y576489D02*
Y565433D01*
G01X-1190591Y576489D02*
X-1190589Y565566D01*
G01X-1190579Y564842D02*
Y576489D01*
G01X-1189257Y599292D02*
Y575926D01*
G01X-1189254Y575624D02*
Y571142D01*
G01X-1188869Y599292D02*
Y575926D01*
G01X-1188657Y577210D02*
Y599292D01*
G01X-1188643Y571142D02*
Y601023D01*
G01X-1188492Y570379D02*
Y575624D01*
G01X-1188270Y576932D02*
Y599292D01*
G01X-1188255Y571142D02*
Y601023D01*
G01X-1188113D02*
Y571876D01*
G01X-1212345Y570329D02*
X-1212344Y570748D01*
G01X-1198172Y570329D02*
X-1198171Y570748D01*
G01X-1212220Y575624D02*
X-1212218Y575926D01*
G01X-1198047Y575624D02*
X-1198045Y575926D01*
G01X-1203043D02*
X-1203045Y575829D01*
X-1203046Y575728D01*
Y571142D01*
G01X-1202665Y575624D02*
X-1202661Y575725D01*
X-1202647Y575820D01*
X-1202625Y575903D01*
G01X-1198850D02*
X-1199032Y576932D01*
G01X-1198644Y577210D02*
X-1198463Y576181D01*
G01X-1184677Y575903D02*
X-1184859Y576932D01*
G01X-1184471Y577210D02*
X-1184290Y576181D01*
G01X-1187075Y574836D02*
X-1187067Y574779D01*
X-1187045Y574731D01*
X-1187013Y574692D01*
X-1186974Y574663D01*
X-1186930Y574646D01*
G01X-1202361Y571142D02*
X-1202352Y571055D01*
X-1202323Y570972D01*
X-1202278Y570897D01*
X-1202216Y570834D01*
X-1202143Y570787D01*
X-1202061Y570758D01*
X-1201974Y570748D01*
G01X-1188188Y571142D02*
X-1188179Y571055D01*
X-1188150Y570972D01*
X-1188104Y570897D01*
X-1188043Y570834D01*
X-1187969Y570787D01*
X-1187888Y570758D01*
X-1187800Y570748D01*
G01X-1184256Y575724D02*
X-1184257Y575826D01*
X-1184259Y575926D01*
G01X-1186930Y574646D02*
X-1186926Y565439D01*
G01X-1187844Y570748D02*
Y570354D01*
G01X-1187800Y570945D02*
Y570748D01*
G01X-1187726Y571679D02*
Y601023D01*
G01X-1187075Y575728D02*
Y574836D01*
G01Y565518D02*
Y564842D01*
G01X-1186878Y575308D02*
Y565433D01*
G01X-1186563Y571876D02*
Y566417D01*
G01X-1186465Y570591D02*
Y566654D01*
G01X-1185364Y570748D02*
Y601023D01*
G01X-1184976D02*
Y570748D01*
G01X-1184859Y576932D02*
Y599292D01*
G01X-1184834Y601023D02*
Y570748D01*
G01X-1184637D02*
Y575624D01*
G01X-1184471Y599292D02*
Y577210D01*
G01X-1184446Y601023D02*
Y570748D01*
G01X-1184259Y599292D02*
Y575926D01*
G01X-1184255Y570721D02*
X-1184256Y575724D01*
G01X-1188869Y575926D02*
X-1188872Y575829D01*
X-1188873Y575728D01*
Y571142D01*
G01X-1188492Y575624D02*
X-1188487Y575725D01*
X-1188474Y575820D01*
X-1188452Y575903D01*
G01X-1202287Y571876D02*
X-1202361Y571142D01*
G01X-1201974Y570945D02*
X-1201899Y571679D01*
G01X-1188113Y571876D02*
X-1188188Y571142D01*
G01X-1187800Y570945D02*
X-1187726Y571679D01*
G01X-1203012Y576181D02*
X-1203024Y576104D01*
X-1203034Y576018D01*
X-1203043Y575926D01*
G01X-1188839Y576181D02*
X-1188851Y576104D01*
X-1188861Y576018D01*
X-1188869Y575926D01*
G01X-1203012Y576181D02*
X-1202831Y577210D01*
G01X-1202443Y576932D02*
X-1202625Y575903D01*
G01X-1188839Y576181D02*
X-1188657Y577210D01*
G01X-1188270Y576932D02*
X-1188452Y575903D01*
G01X-1211839Y565630D02*
X-1211854Y565556D01*
X-1211896Y565491D01*
X-1211961Y565449D01*
X-1212036Y565433D01*
G01X-1204752Y565630D02*
X-1204767Y565556D01*
X-1204810Y565491D01*
X-1204874Y565449D01*
X-1204949Y565433D01*
G01X-1197666Y565630D02*
X-1197680Y565556D01*
X-1197723Y565491D01*
X-1197787Y565449D01*
X-1197863Y565433D01*
G01X-1190579Y565630D02*
X-1190594Y565556D01*
X-1190637Y565491D01*
X-1190701Y565449D01*
X-1190776Y565433D01*
G01X-1212636Y576181D02*
X-1212654Y576124D01*
X-1212688Y576069D01*
X-1212735Y576018D01*
X-1212796Y575975D01*
X-1212867Y575940D01*
X-1212943Y575916D01*
X-1213024Y575903D01*
G01X-1198463Y576181D02*
X-1198481Y576124D01*
X-1198515Y576069D01*
X-1198562Y576018D01*
X-1198622Y575975D01*
X-1198693Y575940D01*
X-1198770Y575916D01*
X-1198850Y575903D01*
G01X-1204757Y565566D02*
X-1204801Y565500D01*
X-1204865Y565451D01*
X-1204949Y565433D01*
G01X-1190584Y565566D02*
X-1190628Y565500D01*
X-1190691Y565451D01*
X-1190776Y565433D01*
G01X-1212351Y570354D02*
G03X-1212744Y570748I-394J0D01*
G01X-1203428Y571142D02*
G03X-1202665Y570379I763J0D01*
G01X-1198178Y570354D02*
G03X-1198571Y570748I-394J0D01*
G01X-1200343D02*
G03X-1200737Y570354I0J-394D01*
G01X-1205264D02*
G03X-1205658Y570748I-394J0D01*
G01X-1207430D02*
G03X-1207823Y570354I1J-394D01*
G01X-1203046Y571142D02*
G03X-1202665Y570761I381J0D01*
G01X-1189254Y571142D02*
G03X-1188492Y570379I762J-1D01*
G01X-1184004Y570354D02*
G03X-1184398Y570748I-394J0D01*
G01X-1186170D02*
G03X-1186563Y570354I1J-394D01*
G01X-1191091D02*
G03X-1191485Y570748I-394J0D01*
G01X-1193256D02*
G03X-1193650Y570354I0J-394D01*
G01X-1188873Y571142D02*
G03X-1188492Y570761I381J0D01*
G01X-1174786Y527906D02*
X-1159485D01*
G01X-1159261Y528130D02*
X-1175009D01*
G01D02*
X-1174786Y527906D01*
G01X-1155442Y530965D02*
X-1179852D01*
G01Y531358D02*
X-1155442D01*
G01X-1180836Y531949D02*
X-1180442D01*
G01X-1180836Y533488D02*
X-1154458D01*
G01X-1170072Y536949D02*
X-1171568D01*
G01X-1177060D02*
X-1178753D01*
G01X-1172970Y539429D02*
X-1168710D01*
G01X-1166686Y554232D02*
X-1167867D01*
G01X-1173773D02*
X-1174954D01*
G01X-1182041D02*
X-1180859D01*
G01X-1182018Y555236D02*
X-1183458D01*
G01X-1165269Y555413D02*
X-1169285D01*
G01X-1172355D02*
X-1176273D01*
G01X-1179541D02*
X-1180836D01*
G01X-1178753Y536949D02*
X-1179541Y537404D01*
G01X-1171568Y536949D02*
X-1172355Y537404D01*
G01X-1167135Y533594D02*
X-1172970Y539429D01*
G01X-1172135D02*
X-1167135Y534429D01*
G01X-1168710Y539429D02*
X-1167135Y537854D01*
G01X-1165560Y539429D02*
X-1167135Y541004D01*
G01Y544429D02*
X-1162135Y539429D01*
G01X-1167135Y545264D02*
X-1161300Y539429D01*
G01X-1180859Y554232D02*
X-1179541Y551948D01*
G01X-1173773Y554232D02*
X-1172395Y551846D01*
G01X-1183458Y555236D02*
Y549629D01*
G01Y547849D02*
Y542306D01*
G01Y540526D02*
Y538292D01*
G01X-1183418Y535335D02*
Y540587D01*
G01Y542246D02*
Y547909D01*
G01Y549568D02*
Y551846D01*
G01X-1182631Y555236D02*
Y531811D01*
G01X-1180442Y531949D02*
Y584331D01*
G01X-1179852Y531358D02*
Y530965D01*
G01X-1179541Y555413D02*
Y537404D01*
G01X-1179481Y537369D02*
Y535335D01*
G01X-1176332D02*
Y537369D01*
G01X-1176273Y537404D02*
Y555413D01*
G01X-1172395Y551846D02*
Y535335D01*
G01X-1172355Y555413D02*
Y537404D01*
G01X-1169285D02*
Y555413D01*
G01X-1169245Y535335D02*
Y551846D01*
G01X-1183418D02*
X-1182029Y554252D01*
G01X-1176273Y551948D02*
X-1174954Y554232D01*
G01X-1169245Y551846D02*
X-1167867Y554232D01*
G01X-1172970Y539429D02*
X-1167135Y545264D01*
G01Y544429D02*
X-1172135Y539429D01*
G01X-1167135Y541004D02*
X-1168710Y539429D01*
G01X-1167135Y537854D02*
X-1165560Y539429D01*
G01X-1162135D02*
X-1167135Y534429D01*
G01X-1161300Y539429D02*
X-1167135Y533594D01*
G01X-1176273Y537404D02*
X-1177060Y536949D01*
G01X-1169285Y537404D02*
X-1170072Y536949D01*
G01X-1179481Y535335D02*
G03X-1176332I1574J0D01*
G01X-1172395D02*
G03X-1169245I1575J0D01*
G01X-1183615Y530827D02*
G03X-1182631Y531811I0J984D01*
G01X-1180836Y531949D02*
G03X-1179852Y530965I984J0D01*
G01X-1180442Y531949D02*
G03X-1179852Y531358I591J0D01*
G01X-1159261Y539429D02*
G03I-7874J0D01*
G01X-1162391D02*
G03I-4744J0D01*
G01X-1183458Y540526D02*
G03Y542306I-1299J890D01*
G01Y547849D02*
G03Y549629I-1299J890D01*
G01X-1183643Y565439D02*
X-1183658Y565436D01*
X-1183674Y565434D01*
X-1183689Y565433D01*
G01X-1175521Y581083D02*
X-1175898Y581008D01*
X-1176217Y580794D01*
X-1176430Y580475D01*
X-1176505Y580098D01*
G01X-1173065Y563563D02*
X-1173437Y563490D01*
X-1173755Y563281D01*
X-1173969Y562967D01*
X-1174049Y562596D01*
G01X-1180049Y585118D02*
X-1180339Y585063D01*
X-1180562Y584928D01*
X-1180717Y584747D01*
X-1180807Y584543D01*
X-1180836Y584331D01*
G01X-1178314Y585165D02*
X-1178614Y585118D01*
G01X-1174049Y562596D02*
X-1174024Y562599D01*
G01X-1167395Y573258D02*
X-1167299Y573271D01*
X-1167197Y573314D01*
X-1167097Y573385D01*
X-1167000Y573483D01*
X-1166905Y573604D01*
X-1166815Y573746D01*
X-1166726Y573910D01*
X-1166639Y574094D01*
G01X-1174024Y562599D02*
X-1173952Y562602D01*
X-1173836Y562603D01*
G01X-1177024Y586080D02*
X-1176646Y586085D01*
G01X-1177343Y586079D02*
X-1177021Y586080D01*
G01X-1161118Y559331D02*
X-1173672D01*
G01X-1161725Y562596D02*
X-1173065D01*
G01X-1173836Y562603D02*
X-1173679D01*
X-1173493Y562602D01*
G01X-1161725Y563563D02*
X-1173065D01*
G01X-1180836Y563760D02*
X-1154458D01*
G01Y564547D02*
X-1180836D01*
G01X-1172080Y567402D02*
X-1162710D01*
G01X-1184004Y568055D02*
X-1182346D01*
G01X-1184004Y568252D02*
X-1182346D01*
G01X-1175521Y569272D02*
X-1159773D01*
G01X-1159928Y569427D02*
X-1175366D01*
G01X-1158944Y570411D02*
X-1176350D01*
G01X-1183874Y570748D02*
X-1184004D01*
G01X-1168151Y574094D02*
X-1171254D01*
G01X-1172324D02*
X-1173609D01*
G01X-1182018Y576489D02*
X-1182346D01*
G01X-1176350Y579944D02*
X-1158944D01*
G01X-1159928Y580928D02*
X-1175366D01*
G01X-1159773Y581083D02*
X-1175521D01*
G01X-1180836Y584331D02*
X-1154458D01*
G01X-1155245Y585118D02*
X-1180048D01*
G01X-1158018Y586085D02*
X-1176646D01*
G01X-1177341Y586079D02*
X-1177555Y586080D01*
X-1177630Y586085D01*
G01X-1173493Y562602D02*
X-1173065Y562596D01*
G01X-1175366Y569427D02*
X-1175584Y569451D01*
X-1175791Y569523D01*
X-1175978Y569640D01*
X-1176135Y569797D01*
X-1176252Y569983D01*
X-1176325Y570190D01*
X-1176350Y570411D01*
G01X-1167491Y573271D02*
X-1167593Y573314D01*
G01X-1176350Y579944D02*
X-1176505Y580098D01*
G01X-1175521Y581083D02*
X-1175366Y580928D01*
G01X-1172070Y573601D02*
X-1171988Y573480D01*
X-1171906Y573383D01*
X-1171826Y573311D01*
X-1171748Y573270D01*
X-1171675Y573258D01*
X-1171608Y573274D01*
X-1171544Y573318D01*
X-1171484Y573391D01*
X-1171429Y573488D01*
X-1171378Y573607D01*
G01X-1167885Y573604D02*
X-1167976Y573746D01*
X-1168064Y573910D01*
G01X-1172070Y573601D02*
X-1172156Y573749D01*
G01X-1172154Y573744D02*
X-1172239Y573911D01*
G01X-1168151Y574094D02*
X-1168064Y573910D01*
X-1167976Y573746D01*
X-1167885Y573604D01*
X-1167791Y573483D01*
X-1167693Y573385D01*
X-1167593Y573314D01*
X-1167491Y573271D01*
X-1167395Y573258D01*
G01X-1172324Y574094D02*
X-1172238Y573908D01*
G01X-1172080Y567402D02*
X-1173458Y573259D01*
G01X-1176505Y570256D02*
X-1176430Y569879D01*
X-1176217Y569560D01*
X-1175898Y569346D01*
X-1175521Y569272D01*
G01X-1173469Y573319D02*
X-1173609Y574094D01*
G01X-1173458Y573258D02*
X-1173480Y573382D01*
G01X-1184103Y570591D02*
Y566654D01*
G01X-1184004Y570354D02*
Y566417D01*
G01X-1183874Y570748D02*
Y575624D01*
G01X-1183872Y575926D02*
Y599292D01*
G01X-1183689Y565433D02*
Y575308D01*
G01X-1183493Y575728D02*
Y574836D01*
G01Y565518D02*
Y564842D01*
G01X-1182346D02*
Y603425D01*
G01X-1180048Y564547D02*
Y585118D01*
G01X-1176646Y586085D02*
Y585118D01*
G01X-1176505Y580098D02*
Y570256D01*
G01X-1176350Y579944D02*
Y570411D01*
G01X-1175366Y569427D02*
Y580928D01*
G01X-1173672Y605591D02*
Y559331D01*
G01X-1173667Y605591D02*
Y559331D01*
G01X-1173636D02*
Y605591D01*
G01X-1173609D02*
Y574094D01*
G01X-1173458Y559331D02*
Y573259D01*
G01X-1173065Y563563D02*
Y562596D01*
G01X-1172570Y605591D02*
Y559331D01*
G01X-1172387Y605591D02*
Y559331D01*
G01X-1172336Y563563D02*
Y597559D01*
G01X-1172324Y605591D02*
Y574094D01*
G01X-1171254Y605984D02*
Y574094D01*
G01X-1171230Y605591D02*
Y559331D01*
G01X-1171089Y605591D02*
Y559331D01*
G01X-1168442D02*
Y605591D01*
G01X-1168213D02*
Y559331D01*
G01X-1168151Y605591D02*
Y574094D01*
G01X-1183639Y574646D02*
X-1183643Y565439D01*
G01X-1183999Y570329D02*
X-1183998Y570748D01*
G01X-1183874Y575624D02*
X-1183872Y575926D01*
G01X-1183643Y565439D02*
X-1183650Y564842D01*
G01X-1177300Y605017D02*
X-1177630Y586085D01*
G01X-1176316Y605017D02*
X-1176646Y586085D01*
G01X-1176350Y579944D02*
X-1176326Y580162D01*
X-1176254Y580369D01*
X-1176137Y580555D01*
X-1175980Y580713D01*
X-1175794Y580829D01*
X-1175587Y580902D01*
X-1175366Y580928D01*
G01X-1177630Y586085D02*
X-1177683Y585785D01*
X-1177824Y585515D01*
X-1178042Y585302D01*
X-1178314Y585165D01*
G01X-1183493Y575505D02*
X-1183508Y575431D01*
X-1183550Y575366D01*
X-1183615Y575324D01*
X-1183689Y575308D01*
G01X-1171254Y574094D02*
X-1171292Y573908D01*
G01Y573911D02*
X-1171334Y573744D01*
G01X-1171333Y573749D02*
X-1171381Y573601D01*
X-1171433Y573480D01*
X-1171489Y573383D01*
X-1171552Y573311D01*
X-1171619Y573270D01*
X-1171689Y573258D01*
X-1171761Y573274D01*
X-1171835Y573318D01*
X-1171914Y573391D01*
X-1171994Y573488D01*
X-1172074Y573607D01*
G01X-1183493Y565518D02*
X-1183524Y565485D01*
X-1183561Y565461D01*
X-1183602Y565446D01*
X-1183643Y565439D01*
G01X-1176505Y570256D02*
X-1176350Y570411D01*
G01X-1175366Y569427D02*
X-1175521Y569272D01*
G01X-1167097Y573385D02*
X-1167197Y573314D01*
G01X-1180048Y585118D02*
X-1180206Y585051D01*
X-1180332Y584869D01*
X-1180414Y584615D01*
X-1180442Y584331D01*
G01X-1183639Y574646D02*
X-1183594Y574663D01*
X-1183555Y574692D01*
X-1183523Y574731D01*
X-1183501Y574779D01*
X-1183493Y574836D01*
G01X-1173065Y563563D02*
G03X-1174049Y562596I0J-984D01*
G01X-1178614Y585118D02*
G03X-1177630Y586085I0J984D01*
G01X-1180048Y585118D02*
G03X-1180836Y584331I-1J-787D01*
G01X-1225744Y603199D02*
X-1225667Y603218D01*
G01X-1226121Y603110D02*
X-1225744Y603199D01*
G01X-1225166Y603425D02*
X-1225228Y603419D01*
X-1225288Y603400D01*
X-1225343Y603369D01*
X-1225391Y603327D01*
X-1225430Y603276D01*
X-1225457Y603218D01*
G01X-1226736Y603425D02*
X-1226798Y603419D01*
X-1226858Y603400D01*
X-1226913Y603369D01*
X-1226961Y603327D01*
X-1227000Y603276D01*
X-1227027Y603218D01*
G01X-1216072Y601063D02*
X-1216460Y601056D01*
G01X-1230246Y601063D02*
X-1230633Y601056D01*
G01X-1219058Y595551D02*
X-1223586D01*
G01X-1223946D02*
X-1226308D01*
G01X-1231777Y599292D02*
X-1230790D01*
G01X-1227378D02*
X-1226391D01*
G01X-1217604D02*
X-1216617D01*
G01X-1226659Y599965D02*
X-1226869D01*
G01X-1217125D02*
X-1217335D01*
G01X-1231298D02*
X-1231509D01*
G01X-1219747Y600472D02*
X-1223673D01*
G01X-1231163Y601023D02*
X-1230245D01*
G01X-1227883D02*
X-1226966D01*
G01X-1216990D02*
X-1216072D01*
G01X-1216562Y601696D02*
X-1216722D01*
G01X-1230735D02*
X-1230895D01*
G01X-1227394D02*
X-1227233D01*
G01X-1211841Y602080D02*
X-1216657D01*
G01X-1218927D02*
X-1222143D01*
G01X-1226014D02*
X-1230830D01*
G01X-1219058Y602937D02*
X-1223586D01*
G01X-1223946D02*
X-1226308D01*
G01X-1211948Y603110D02*
X-1225083D01*
G01X-1218328Y603218D02*
X-1218537D01*
G01X-1225457D02*
X-1225667D01*
G01X-1232501D02*
X-1232711D01*
G01X-1227027D02*
X-1226671D01*
G01X-1217284D02*
X-1216928D01*
G01X-1231457D02*
X-1231101D01*
G01X-1227883Y601063D02*
X-1227495Y601056D01*
G01X-1227533Y601677D02*
X-1227472Y601676D01*
X-1227424Y601682D01*
X-1227394Y601696D01*
G01X-1232501Y603218D02*
X-1232424Y603199D01*
X-1232047Y603110D01*
G01X-1218328Y603218D02*
X-1218251Y603199D01*
X-1217874Y603110D01*
G01X-1226671Y603218D02*
X-1226308Y603113D01*
G01X-1225457Y603218D02*
X-1225083Y603110D01*
G01X-1226869Y599965D02*
X-1227234Y600100D01*
G01X-1226659Y599965D02*
X-1226295Y599831D01*
G01X-1227233Y601696D02*
X-1226869Y601561D01*
G01X-1230735Y601696D02*
X-1230704Y601682D01*
X-1230656Y601676D01*
X-1230595Y601677D01*
G01X-1216562Y601696D02*
X-1216531Y601682D01*
X-1216483Y601676D01*
X-1216422Y601677D01*
G01X-1227490Y603425D02*
X-1227395Y603332D01*
X-1227387Y603063D01*
X-1227468Y602637D01*
X-1227631Y602080D01*
G01X-1229229D02*
X-1230574Y603425D01*
G01X-1222143Y602080D02*
X-1223487Y603425D01*
G01X-1215056Y602080D02*
X-1216401Y603425D01*
G01X-1227027Y603218D02*
X-1227116Y603324D01*
X-1227263Y603394D01*
X-1227490Y603425D01*
G01X-1230683Y601812D02*
X-1230460Y601470D01*
X-1230343Y601266D01*
X-1230246Y601063D01*
G01X-1216510Y601812D02*
X-1216287Y601470D01*
X-1216170Y601266D01*
X-1216072Y601063D01*
G01X-1230830Y602080D02*
X-1230762Y601946D01*
X-1230683Y601812D01*
G01X-1216657Y602080D02*
X-1216589Y601946D01*
X-1216510Y601812D01*
G01X-1231457Y603218D02*
X-1231485Y603275D01*
X-1231523Y603326D01*
X-1231571Y603368D01*
X-1231626Y603399D01*
X-1231685Y603418D01*
X-1231749Y603425D01*
G01X-1231101Y603218D02*
X-1231129Y603275D01*
X-1231167Y603326D01*
X-1231215Y603368D01*
X-1231270Y603399D01*
X-1231330Y603418D01*
X-1231393Y603425D01*
G01X-1218537Y603218D02*
X-1218565Y603275D01*
X-1218603Y603326D01*
X-1218650Y603368D01*
X-1218706Y603399D01*
X-1218766Y603418D01*
X-1218829Y603425D01*
G01X-1218328Y603218D02*
X-1218355Y603275D01*
X-1218393Y603326D01*
X-1218440Y603368D01*
X-1218496Y603399D01*
X-1218555Y603418D01*
X-1218619Y603425D01*
G01X-1217284Y603218D02*
X-1217311Y603275D01*
X-1217350Y603326D01*
X-1217398Y603368D01*
X-1217453Y603399D01*
X-1217512Y603418D01*
X-1217576Y603425D01*
G01X-1216928Y603218D02*
X-1216955Y603275D01*
X-1216993Y603326D01*
X-1217042Y603368D01*
X-1217096Y603399D01*
X-1217156Y603418D01*
X-1217220Y603425D01*
G01X-1231298Y599965D02*
X-1232501Y603218D01*
G01X-1232047Y603110D02*
X-1230934Y600100D01*
G01X-1231832Y603110D02*
X-1231259Y601561D01*
G01X-1230895Y601696D02*
X-1231457Y603218D01*
G01X-1230498Y602080D02*
X-1230662Y602642D01*
X-1230742Y603068D01*
X-1230733Y603334D01*
X-1230639Y603425D01*
G01X-1231177Y599292D02*
X-1231191Y599520D01*
X-1231231Y599746D01*
X-1231298Y599965D01*
G01X-1230790Y599292D02*
X-1230806Y599566D01*
X-1230854Y599837D01*
X-1230934Y600100D01*
G01X-1231389Y599292D02*
X-1231402Y599521D01*
X-1231443Y599746D01*
X-1231509Y599965D01*
G01X-1230775Y601023D02*
X-1230789Y601251D01*
X-1230829Y601477D01*
X-1230895Y601696D01*
G01X-1230246Y601063D02*
X-1230245Y601023D01*
G01X-1230633Y601056D02*
Y601023D01*
G01X-1232047Y603110D02*
Y603425D01*
G01X-1231832Y603110D02*
Y603425D01*
G01X-1217700Y599831D02*
X-1218912Y603110D01*
G01X-1218537Y603218D02*
X-1217335Y599965D01*
G01X-1217125D02*
X-1218328Y603218D01*
G01X-1217874Y603110D02*
X-1216761Y600100D01*
G01X-1217659Y603110D02*
X-1217086Y601561D01*
G01X-1216722Y601696D02*
X-1217284Y603218D01*
G01X-1216324Y602080D02*
X-1216489Y602642D01*
X-1216568Y603068D01*
X-1216559Y603334D01*
X-1216466Y603425D01*
G01X-1230735Y601696D02*
X-1230681Y601485D01*
X-1230647Y601270D01*
X-1230633Y601056D01*
G01X-1216562Y601696D02*
X-1216507Y601485D01*
X-1216474Y601270D01*
X-1216460Y601056D01*
G01X-1231101Y603218D02*
X-1231033Y602797D01*
X-1230917Y602315D01*
X-1230735Y601696D01*
G01X-1216928Y603218D02*
X-1216859Y602797D01*
X-1216744Y602315D01*
X-1216562Y601696D01*
G01X-1217004Y599292D02*
X-1217018Y599520D01*
X-1217058Y599746D01*
X-1217125Y599965D01*
G01X-1216617Y599292D02*
X-1216633Y599566D01*
X-1216681Y599837D01*
X-1216761Y600100D01*
G01X-1217216Y599292D02*
X-1217229Y599521D01*
X-1217269Y599746D01*
X-1217335Y599965D01*
G01X-1216602Y601023D02*
X-1216615Y601251D01*
X-1216655Y601477D01*
X-1216722Y601696D01*
G01X-1216072Y601063D02*
Y601023D01*
G01X-1216460Y601056D02*
Y601023D01*
G01X-1226308Y603425D02*
Y595551D01*
G01X-1226121Y603110D02*
Y603425D01*
G01X-1225083Y603110D02*
Y603425D01*
G01X-1223946D02*
Y595551D01*
G01X-1223586D02*
Y603425D01*
G01X-1219058D02*
Y595551D01*
G01X-1218912Y603425D02*
Y603110D01*
G01X-1217874D02*
Y603425D01*
G01X-1217659D02*
Y603110D01*
G01X-1227883Y601023D02*
Y601063D01*
G01X-1227495Y601056D02*
X-1227496Y601023D01*
G01X-1226779Y599292D02*
X-1226766Y599520D01*
X-1226726Y599746D01*
X-1226659Y599965D01*
G01X-1227495Y601056D02*
X-1227482Y601270D01*
X-1227448Y601485D01*
X-1227394Y601696D01*
G01X-1227027Y603218D02*
X-1227097Y602794D01*
X-1227213Y602311D01*
X-1227394Y601696D01*
G01X-1227233D02*
X-1227300Y601477D01*
X-1227340Y601251D01*
X-1227354Y601023D01*
G01X-1227234Y600100D02*
X-1227314Y599837D01*
X-1227362Y599566D01*
X-1227378Y599292D01*
G01X-1226869Y599965D02*
X-1226937Y599746D01*
X-1226977Y599520D01*
X-1226991Y599292D01*
G01X-1226671Y603218D02*
X-1227233Y601696D01*
G01X-1226869Y601561D02*
X-1226308Y603079D01*
G01X-1227234Y600100D02*
X-1226121Y603110D01*
G01X-1225667Y603218D02*
X-1226869Y599965D01*
G01X-1226659D02*
X-1225457Y603218D01*
G01X-1225083Y603110D02*
X-1226295Y599831D01*
G01X-1226671Y603218D02*
X-1226644Y603275D01*
X-1226606Y603326D01*
X-1226559Y603368D01*
X-1226503Y603399D01*
X-1226443Y603418D01*
X-1226380Y603425D01*
G01X-1225667Y603218D02*
X-1225640Y603275D01*
X-1225602Y603326D01*
X-1225555Y603368D01*
X-1225499Y603399D01*
X-1225439Y603418D01*
X-1225376Y603425D01*
G01X-1227883Y601063D02*
X-1227786Y601266D01*
X-1227668Y601470D01*
G01D02*
X-1227445Y601812D01*
X-1227367Y601946D01*
X-1227298Y602080D01*
G01X-1231101Y603218D02*
X-1231020Y603318D01*
X-1230862Y603395D01*
X-1230639Y603425D01*
G01X-1216928Y603218D02*
X-1216847Y603318D01*
X-1216689Y603395D01*
X-1216466Y603425D01*
G01X-1224668D02*
X-1226014Y602080D01*
G01X-1217582Y603425D02*
X-1218927Y602080D01*
G01X-1230895Y601696D02*
X-1231259Y601561D01*
G01X-1231509Y599965D02*
X-1231873Y599831D01*
G01X-1230934Y600100D02*
X-1231298Y599965D01*
G01X-1216722Y601696D02*
X-1217086Y601561D01*
G01X-1231457Y603218D02*
X-1231832Y603110D01*
G01X-1217335Y599965D02*
X-1217700Y599831D01*
G01X-1216761Y600100D02*
X-1217125Y599965D01*
G01X-1218912Y603110D02*
X-1218537Y603218D01*
G01X-1217284D02*
X-1217659Y603110D01*
G01X-1226295Y599831D02*
G03X-1226392Y599292I1457J-540D01*
G01X-1231163Y601023D02*
G03X-1231259Y601561I-1554J0D01*
G01X-1231776Y599292D02*
G03X-1231873Y599831I-1554J-1D01*
G01X-1226869Y601561D02*
G03X-1226966Y601023I1456J-540D01*
G01X-1216990D02*
G03X-1217086Y601561I-1554J0D01*
G01X-1217603Y599292D02*
G03X-1217700Y599831I-1553J-1D01*
G01X-1197398Y603199D02*
X-1197321Y603218D01*
G01X-1211571Y603199D02*
X-1211494Y603218D01*
G01X-1197775Y603110D02*
X-1197398Y603199D01*
G01X-1211948Y603110D02*
X-1211571Y603199D01*
G01X-1184216Y603425D02*
X-1184279Y603419D01*
X-1184339Y603400D01*
X-1184393Y603369D01*
X-1184442Y603327D01*
X-1184480Y603276D01*
X-1184507Y603218D01*
G01X-1196819Y603425D02*
X-1196882Y603419D01*
X-1196942Y603400D01*
X-1196996Y603369D01*
X-1197045Y603327D01*
X-1197083Y603276D01*
X-1197111Y603218D01*
G01X-1198389Y603425D02*
X-1198452Y603419D01*
X-1198512Y603400D01*
X-1198567Y603369D01*
X-1198615Y603327D01*
X-1198653Y603276D01*
X-1198681Y603218D01*
G01X-1210993Y603425D02*
X-1211055Y603419D01*
X-1211115Y603400D01*
X-1211170Y603369D01*
X-1211218Y603327D01*
X-1211256Y603276D01*
X-1211284Y603218D01*
G01X-1212563Y603425D02*
X-1212625Y603419D01*
X-1212685Y603400D01*
X-1212740Y603369D01*
X-1212788Y603327D01*
X-1212826Y603276D01*
X-1212854Y603218D01*
G01X-1187726Y601063D02*
X-1188114Y601056D01*
G01X-1201899Y601063D02*
X-1202287Y601056D01*
G01X-1195600Y595551D02*
X-1197962D01*
G01X-1190712D02*
X-1195239D01*
G01X-1204885D02*
X-1209413D01*
G01X-1209773D02*
X-1212135D01*
G01X-1183872Y599292D02*
X-1184859D01*
G01X-1213205D02*
X-1212218D01*
G01X-1203430D02*
X-1202443D01*
G01X-1199032D02*
X-1198045D01*
G01X-1189257D02*
X-1188270D01*
G01X-1188779Y599965D02*
X-1188989D01*
G01X-1212486D02*
X-1212696D01*
G01X-1184140D02*
X-1184350D01*
G01X-1198313D02*
X-1198523D01*
G01X-1202952D02*
X-1203162D01*
G01X-1191401Y600472D02*
X-1195327D01*
G01X-1205574D02*
X-1209500D01*
G01X-1213710Y601023D02*
X-1212793D01*
G01X-1202817D02*
X-1201899D01*
G01X-1199537D02*
X-1198619D01*
G01X-1188643D02*
X-1187726D01*
G01X-1185364D02*
X-1184446D01*
G01X-1188215Y601696D02*
X-1188376D01*
G01X-1202389D02*
X-1202549D01*
G01X-1213220D02*
X-1213060D01*
G01X-1199047D02*
X-1198887D01*
G01X-1184874D02*
X-1184714D01*
G01X-1184085Y602080D02*
X-1188311D01*
G01X-1190581D02*
X-1193796D01*
G01X-1197667D02*
X-1202484D01*
G01X-1204754D02*
X-1207969D01*
G01X-1195600Y602937D02*
X-1197962D01*
G01X-1190712D02*
X-1195239D01*
G01X-1204885D02*
X-1209413D01*
G01X-1209773D02*
X-1212135D01*
G01X-1183602Y603110D02*
X-1196737D01*
G01X-1197775D02*
X-1210910D01*
G01X-1189981Y603218D02*
X-1190191D01*
G01X-1197111D02*
X-1197321D01*
G01X-1204154D02*
X-1204364D01*
G01X-1211284D02*
X-1211494D01*
G01X-1212854D02*
X-1212498D01*
G01X-1203111D02*
X-1202755D01*
G01X-1198681D02*
X-1198325D01*
G01X-1188938D02*
X-1188581D01*
G01X-1184507D02*
X-1184152D01*
G01X-1213710Y601063D02*
X-1213322Y601056D01*
G01X-1199537Y601063D02*
X-1199149Y601056D01*
G01X-1185363Y601063D02*
X-1184976Y601056D01*
G01X-1213360Y601677D02*
X-1213299Y601676D01*
X-1213251Y601682D01*
X-1213220Y601696D01*
G01X-1199187Y601677D02*
X-1199126Y601676D01*
X-1199078Y601682D01*
X-1199047Y601696D01*
G01X-1185014Y601677D02*
X-1184952Y601676D01*
X-1184905Y601682D01*
X-1184874Y601696D01*
G01X-1204154Y603218D02*
X-1204078Y603199D01*
X-1203700Y603110D01*
G01X-1189981Y603218D02*
X-1189904Y603199D01*
X-1189527Y603110D01*
G01X-1212498Y603218D02*
X-1212135Y603113D01*
G01X-1211284Y603218D02*
X-1210910Y603110D01*
G01X-1198325Y603218D02*
X-1197962Y603113D01*
G01X-1197111Y603218D02*
X-1196737Y603110D01*
G01X-1212696Y599965D02*
X-1213061Y600100D01*
G01X-1212122Y599831D02*
X-1212486Y599965D01*
G01X-1213060Y601696D02*
X-1212696Y601561D01*
G01X-1198523Y599965D02*
X-1198887Y600100D01*
G01X-1197948Y599831D02*
X-1198313Y599965D01*
G01X-1198887Y601696D02*
X-1198523Y601561D01*
G01X-1184350Y599965D02*
X-1184714Y600100D01*
G01Y601696D02*
X-1184350Y601561D01*
G01X-1202389Y601696D02*
X-1202358Y601682D01*
X-1202310Y601676D01*
X-1202249Y601677D01*
G01X-1188215Y601696D02*
X-1188185Y601682D01*
X-1188137Y601676D01*
X-1188076Y601677D01*
G01X-1213317Y603425D02*
X-1213222Y603332D01*
X-1213214Y603063D01*
X-1213294Y602637D01*
X-1213458Y602080D01*
G01X-1199143Y603425D02*
X-1199049Y603332D01*
X-1199041Y603063D01*
X-1199121Y602637D01*
X-1199285Y602080D01*
G01X-1184970Y603425D02*
X-1184876Y603332D01*
X-1184868Y603063D01*
X-1184948Y602637D01*
X-1185111Y602080D01*
G01X-1207969D02*
X-1209314Y603425D01*
G01X-1200883Y602080D02*
X-1202228Y603425D01*
G01X-1195141D02*
X-1193796Y602080D01*
G01X-1188054Y603425D02*
X-1186709Y602080D01*
G01X-1212854Y603218D02*
X-1212943Y603324D01*
X-1213090Y603394D01*
X-1213317Y603425D01*
G01X-1198681Y603218D02*
X-1198770Y603324D01*
X-1198917Y603394D01*
X-1199143Y603425D01*
G01X-1184507Y603218D02*
X-1184596Y603324D01*
X-1184743Y603394D01*
X-1184970Y603425D01*
G01X-1202337Y601812D02*
X-1202114Y601470D01*
X-1201996Y601266D01*
X-1201899Y601063D01*
G01X-1188164Y601812D02*
X-1187941Y601470D01*
X-1187823Y601266D01*
X-1187726Y601063D01*
G01X-1202484Y602080D02*
X-1202416Y601946D01*
X-1202337Y601812D01*
G01X-1188311Y602080D02*
X-1188243Y601946D01*
X-1188164Y601812D01*
G01X-1204364Y603218D02*
X-1204392Y603275D01*
X-1204430Y603326D01*
X-1204477Y603368D01*
X-1204533Y603399D01*
X-1204593Y603418D01*
X-1204656Y603425D01*
G01X-1204154Y603218D02*
X-1204181Y603275D01*
X-1204220Y603326D01*
X-1204267Y603368D01*
X-1204322Y603399D01*
X-1204382Y603418D01*
X-1204446Y603425D01*
G01X-1203111Y603218D02*
X-1203138Y603275D01*
X-1203176Y603326D01*
X-1203225Y603368D01*
X-1203280Y603399D01*
X-1203339Y603418D01*
X-1203402Y603425D01*
G01X-1202755Y603218D02*
X-1202782Y603275D01*
X-1202820Y603326D01*
X-1202868Y603368D01*
X-1202923Y603399D01*
X-1202983Y603418D01*
X-1203046Y603425D01*
G01X-1190191Y603218D02*
X-1190218Y603275D01*
X-1190256Y603326D01*
X-1190304Y603368D01*
X-1190359Y603399D01*
X-1190419Y603418D01*
X-1190483Y603425D01*
G01X-1189981Y603218D02*
X-1190008Y603275D01*
X-1190046Y603326D01*
X-1190094Y603368D01*
X-1190149Y603399D01*
X-1190209Y603418D01*
X-1190272Y603425D01*
G01X-1188938Y603218D02*
X-1188965Y603275D01*
X-1189003Y603326D01*
X-1189052Y603368D01*
X-1189106Y603399D01*
X-1189166Y603418D01*
X-1189229Y603425D01*
G01X-1188581Y603218D02*
X-1188609Y603275D01*
X-1188647Y603326D01*
X-1188695Y603368D01*
X-1188750Y603399D01*
X-1188810Y603418D01*
X-1188873Y603425D01*
G01X-1203527Y599831D02*
X-1204739Y603110D01*
G01X-1204364Y603218D02*
X-1203162Y599965D01*
G01X-1202952D02*
X-1204154Y603218D01*
G01X-1203700Y603110D02*
X-1202588Y600100D01*
G01X-1203485Y603110D02*
X-1202913Y601561D01*
G01X-1202549Y601696D02*
X-1203111Y603218D01*
G01X-1189354Y599831D02*
X-1190565Y603110D01*
G01X-1190191Y603218D02*
X-1188989Y599965D01*
G01X-1188779D02*
X-1189981Y603218D01*
G01X-1189527Y603110D02*
X-1188415Y600100D01*
G01X-1189312Y603110D02*
X-1188740Y601561D01*
G01X-1188376Y601696D02*
X-1188938Y603218D01*
G01X-1202151Y602080D02*
X-1202316Y602642D01*
X-1202395Y603068D01*
X-1202386Y603334D01*
X-1202293Y603425D01*
G01X-1187978Y602080D02*
X-1188143Y602642D01*
X-1188222Y603068D01*
X-1188213Y603334D01*
X-1188119Y603425D01*
G01X-1202389Y601696D02*
X-1202334Y601485D01*
X-1202300Y601270D01*
X-1202287Y601056D01*
G01X-1202831Y599292D02*
X-1202844Y599520D01*
X-1202885Y599746D01*
X-1202952Y599965D01*
G01X-1188657Y599292D02*
X-1188671Y599520D01*
X-1188712Y599746D01*
X-1188779Y599965D01*
G01X-1202443Y599292D02*
X-1202459Y599566D01*
X-1202508Y599837D01*
X-1202588Y600100D01*
G01X-1188270Y599292D02*
X-1188286Y599566D01*
X-1188335Y599837D01*
X-1188415Y600100D01*
G01X-1203043Y599292D02*
X-1203056Y599521D01*
X-1203096Y599746D01*
X-1203162Y599965D01*
G01X-1188869Y599292D02*
X-1188883Y599521D01*
X-1188923Y599746D01*
X-1188989Y599965D01*
G01X-1202429Y601023D02*
X-1202442Y601251D01*
X-1202482Y601477D01*
X-1202549Y601696D01*
G01X-1188255Y601023D02*
X-1188269Y601251D01*
X-1188309Y601477D01*
X-1188376Y601696D01*
G01X-1201899Y601063D02*
Y601023D01*
G01X-1187726Y601063D02*
Y601023D01*
G01X-1202287Y601056D02*
Y601023D01*
G01X-1188114Y601056D02*
X-1188113Y601023D01*
G01X-1212135Y603425D02*
Y595551D01*
G01X-1211948Y603110D02*
Y603425D01*
G01X-1210910Y603110D02*
Y603425D01*
G01X-1209773D02*
Y595551D01*
G01X-1209413D02*
Y603425D01*
G01X-1204885D02*
Y595551D01*
G01X-1204739Y603425D02*
Y603110D01*
G01X-1203700D02*
Y603425D01*
G01X-1203485D02*
Y603110D01*
G01X-1197962Y603425D02*
Y595551D01*
G01X-1197775Y603110D02*
Y603425D01*
G01X-1196737Y603110D02*
Y603425D01*
G01X-1195600D02*
Y595551D01*
G01X-1195239D02*
Y603425D01*
G01X-1190712D02*
Y595551D01*
G01X-1190565Y603425D02*
Y603110D01*
G01X-1189527D02*
Y603425D01*
G01X-1189312D02*
Y603110D01*
G01X-1213710Y601023D02*
Y601063D01*
G01X-1213322Y601056D02*
Y601023D01*
G01X-1199537D02*
Y601063D01*
G01X-1199149Y601056D02*
Y601023D01*
G01X-1212606Y599292D02*
X-1212593Y599520D01*
X-1212552Y599746D01*
X-1212486Y599965D01*
G01X-1198433Y599292D02*
X-1198419Y599520D01*
X-1198379Y599746D01*
X-1198313Y599965D01*
G01X-1213322Y601056D02*
X-1213309Y601270D01*
X-1213275Y601485D01*
X-1213220Y601696D01*
G01X-1199149Y601056D02*
X-1199135Y601270D01*
X-1199102Y601485D01*
X-1199047Y601696D01*
G01X-1212854Y603218D02*
X-1212924Y602794D01*
X-1213039Y602311D01*
X-1213220Y601696D01*
G01X-1188215D02*
X-1188161Y601485D01*
X-1188127Y601270D01*
X-1188114Y601056D01*
G01X-1202755Y603218D02*
X-1202686Y602797D01*
X-1202571Y602315D01*
X-1202389Y601696D01*
G01X-1188581Y603218D02*
X-1188513Y602797D01*
X-1188398Y602315D01*
X-1188215Y601696D01*
G01X-1185364Y601023D02*
X-1185363Y601063D01*
G01X-1184976Y601056D02*
Y601023D01*
G01X-1184259Y599292D02*
X-1184246Y599520D01*
X-1184206Y599746D01*
X-1184140Y599965D01*
G01X-1184976Y601056D02*
X-1184962Y601270D01*
X-1184928Y601485D01*
X-1184874Y601696D01*
G01X-1198681Y603218D02*
X-1198750Y602794D01*
X-1198866Y602311D01*
X-1199047Y601696D01*
G01X-1184507Y603218D02*
X-1184577Y602794D01*
X-1184693Y602311D01*
X-1184874Y601696D01*
G01X-1213060D02*
X-1213127Y601477D01*
X-1213167Y601251D01*
X-1213180Y601023D01*
G01X-1198887Y601696D02*
X-1198954Y601477D01*
X-1198994Y601251D01*
X-1199007Y601023D01*
G01X-1213061Y600100D02*
X-1213141Y599837D01*
X-1213189Y599566D01*
X-1213205Y599292D01*
G01X-1198887Y600100D02*
X-1198967Y599837D01*
X-1199016Y599566D01*
X-1199032Y599292D01*
G01X-1212696Y599965D02*
X-1212763Y599746D01*
X-1212804Y599520D01*
X-1212818Y599292D01*
G01X-1198523Y599965D02*
X-1198590Y599746D01*
X-1198631Y599520D01*
X-1198644Y599292D01*
G01X-1212498Y603218D02*
X-1213060Y601696D01*
G01X-1212696Y601561D02*
X-1212135Y603079D01*
G01X-1213061Y600100D02*
X-1211948Y603110D01*
G01X-1211494Y603218D02*
X-1212696Y599965D01*
G01X-1212486D02*
X-1211284Y603218D01*
G01X-1210910Y603110D02*
X-1212122Y599831D01*
G01X-1198325Y603218D02*
X-1198887Y601696D01*
G01X-1198523Y601561D02*
X-1197962Y603079D01*
G01X-1198887Y600100D02*
X-1197775Y603110D01*
G01X-1197321Y603218D02*
X-1198523Y599965D01*
G01X-1198313D02*
X-1197111Y603218D01*
G01X-1212498D02*
X-1212471Y603275D01*
X-1212433Y603326D01*
X-1212385Y603368D01*
X-1212330Y603399D01*
X-1212270Y603418D01*
X-1212207Y603425D01*
G01X-1211494Y603218D02*
X-1211467Y603275D01*
X-1211429Y603326D01*
X-1211381Y603368D01*
X-1211326Y603399D01*
X-1211266Y603418D01*
X-1211203Y603425D01*
G01X-1213710Y601063D02*
X-1213613Y601266D01*
X-1213495Y601470D01*
G01X-1184714Y601696D02*
X-1184780Y601477D01*
X-1184820Y601251D01*
X-1184834Y601023D01*
G01X-1184714Y600100D02*
X-1184794Y599837D01*
X-1184843Y599566D01*
X-1184859Y599292D01*
G01X-1184350Y599965D02*
X-1184417Y599746D01*
X-1184457Y599520D01*
X-1184471Y599292D01*
G01X-1196737Y603110D02*
X-1197948Y599831D01*
G01X-1184152Y603218D02*
X-1184714Y601696D01*
G01X-1184350Y601561D02*
X-1183789Y603079D01*
G01X-1184714Y600100D02*
X-1183602Y603110D01*
G01X-1183148Y603218D02*
X-1184350Y599965D01*
G01X-1198325Y603218D02*
X-1198298Y603275D01*
X-1198259Y603326D01*
X-1198212Y603368D01*
X-1198156Y603399D01*
X-1198097Y603418D01*
X-1198033Y603425D01*
G01X-1197321Y603218D02*
X-1197294Y603275D01*
X-1197255Y603326D01*
X-1197208Y603368D01*
X-1197153Y603399D01*
X-1197093Y603418D01*
X-1197030Y603425D01*
G01X-1199537Y601063D02*
X-1199439Y601266D01*
X-1199322Y601470D01*
G01X-1185363Y601063D02*
X-1185266Y601266D01*
X-1185149Y601470D01*
G01X-1213495D02*
X-1213272Y601812D01*
X-1213193Y601946D01*
X-1213125Y602080D01*
G01X-1199322Y601470D02*
X-1199099Y601812D01*
X-1199020Y601946D01*
X-1198952Y602080D01*
G01X-1185149Y601470D02*
X-1184926Y601812D01*
X-1184847Y601946D01*
X-1184779Y602080D01*
G01X-1202755Y603218D02*
X-1202674Y603318D01*
X-1202515Y603395D01*
X-1202293Y603425D01*
G01X-1188581Y603218D02*
X-1188500Y603318D01*
X-1188342Y603395D01*
X-1188119Y603425D01*
G01X-1210495D02*
X-1211841Y602080D01*
G01X-1203409Y603425D02*
X-1204754Y602080D01*
G01X-1196322Y603425D02*
X-1197667Y602080D01*
G01X-1189235Y603425D02*
X-1190581Y602080D01*
G01X-1202549Y601696D02*
X-1202913Y601561D01*
G01X-1203162Y599965D02*
X-1203527Y599831D01*
G01X-1202588Y600100D02*
X-1202952Y599965D01*
G01X-1188376Y601696D02*
X-1188740Y601561D01*
G01X-1188989Y599965D02*
X-1189354Y599831D01*
G01X-1188415Y600100D02*
X-1188779Y599965D01*
G01X-1204739Y603110D02*
X-1204364Y603218D01*
G01X-1203111D02*
X-1203485Y603110D01*
G01X-1190565D02*
X-1190191Y603218D01*
G01X-1188938D02*
X-1189312Y603110D01*
G01X-1197949Y599831D02*
G03X-1198045Y599292I1458J-538D01*
G01X-1212122Y599831D02*
G03X-1212218Y599292I1458J-538D01*
G01X-1202817Y601023D02*
G03X-1202913Y601561I-1553J0D01*
G01X-1203430Y599292D02*
G03X-1203526Y599831I-1554J1D01*
G01X-1212696Y601561D02*
G03X-1212793Y601023I1456J-540D01*
G01X-1198523Y601561D02*
G03X-1198619Y601023I1457J-538D01*
G01X-1188643D02*
G03X-1188740Y601561I-1554J-2D01*
G01X-1189257Y599292D02*
G03X-1189353Y599831I-1554J1D01*
G01X-1184350Y601561D02*
G03X-1184446Y601023I1457J-538D01*
G01X-1167892Y605700D02*
X-1167639Y605766D01*
G01X-1183224Y603199D02*
X-1183148Y603218D01*
G01X-1183602Y603110D02*
X-1183224Y603199D01*
G01X-1171821Y605787D02*
X-1172072Y605740D01*
X-1172324Y605591D01*
G01X-1176316Y605984D02*
X-1176617Y605937D01*
X-1176889Y605800D01*
X-1177106Y605587D01*
X-1177247Y605317D01*
X-1177300Y605017D01*
G01D02*
X-1177275Y605020D01*
X-1177203Y605023D01*
X-1177087Y605024D01*
X-1176929D01*
X-1176744Y605023D01*
G01X-1182646Y603425D02*
X-1182709Y603419D01*
X-1182768Y603400D01*
X-1182823Y603369D01*
X-1182872Y603327D01*
X-1182910Y603276D01*
X-1182938Y603218D01*
G01X-1167395Y605787D02*
X-1167643Y605765D01*
G01X-1182346Y595551D02*
X-1183789D01*
G01X-1162454Y597559D02*
X-1172336D01*
G01X-1177416Y598346D02*
X-1157248D01*
G01X-1182346Y602937D02*
X-1183789D01*
G01X-1182346Y603110D02*
X-1182563D01*
G01X-1182938Y603218D02*
X-1183148D01*
G01X-1158348Y605017D02*
X-1176316D01*
G01X-1166676Y605591D02*
X-1171254D01*
G01X-1172324D02*
X-1174615D01*
G01X-1158348Y605984D02*
X-1176316D01*
G01X-1176744Y605023D02*
X-1176316Y605017D01*
G01X-1167395Y605787D02*
X-1167149Y605766D01*
G01X-1171821Y605787D02*
X-1171555Y605740D01*
G01X-1184152Y603218D02*
X-1183789Y603113D01*
G01X-1182563Y603110D02*
X-1182938Y603218D01*
G01X-1183775Y599831D02*
X-1184140Y599965D01*
G01X-1171254Y605591D02*
X-1171555Y605740D01*
G01X-1172336Y597559D02*
X-1173123Y598346D01*
G01X-1173672Y605591D02*
X-1174066Y605984D01*
G01X-1173852D02*
X-1173655Y605787D01*
G01X-1174055Y605984D02*
X-1173667Y605591D01*
G01X-1171230D02*
X-1171598Y605984D01*
G01X-1173636Y605591D02*
X-1173994Y605984D01*
G01X-1172570Y605591D02*
X-1172891Y605984D01*
G01X-1171089Y605591D02*
X-1171317Y605984D01*
G01X-1172387Y605591D02*
X-1172524Y605984D01*
G01X-1173655Y605787D02*
X-1173650Y605765D01*
X-1173635Y605700D01*
X-1173609Y605591D01*
G01X-1173650Y605766D02*
X-1173655Y605787D01*
G01X-1168508Y605984D02*
X-1168485Y605853D01*
X-1168442Y605591D01*
G01X-1168485Y605853D02*
X-1168508Y605984D01*
G01X-1183789Y603425D02*
Y595551D01*
G01X-1183602Y603110D02*
Y603425D01*
G01X-1182563Y603110D02*
Y603425D01*
G01X-1176745Y605885D02*
Y598346D01*
G01X-1176316Y605017D02*
Y605984D01*
G01X-1174645D02*
Y682009D01*
G01X-1174615Y605591D02*
Y605984D01*
G01X-1174369D02*
Y605591D01*
G01X-1173655Y605787D02*
Y605984D01*
G01X-1173303D02*
Y605591D01*
G01X-1173221Y605984D02*
Y605591D01*
G01X-1173139D02*
Y605984D01*
G01X-1172975Y605591D02*
Y605984D01*
G01X-1168316D02*
Y605591D01*
G01X-1168070Y605984D02*
Y605591D01*
G01X-1167906D02*
Y605984D01*
G01X-1167865D02*
Y605591D01*
G01X-1167660Y605984D02*
Y605591D01*
G01X-1167496D02*
Y605984D01*
G01X-1167332Y605591D02*
Y605984D01*
G01X-1177300Y605017D02*
X-1177220Y605389D01*
X-1177005Y605702D01*
X-1176688Y605911D01*
X-1176316Y605984D01*
G01X-1184140Y599965D02*
X-1182938Y603218D01*
G01X-1182563Y603110D02*
X-1183775Y599831D01*
G01X-1168213Y605591D02*
X-1168050Y605984D01*
G01X-1184152Y603218D02*
X-1184124Y603275D01*
X-1184086Y603326D01*
X-1184039Y603368D01*
X-1183983Y603399D01*
X-1183924Y603418D01*
X-1183860Y603425D01*
G01X-1183148Y603218D02*
X-1183120Y603275D01*
X-1183082Y603326D01*
X-1183035Y603368D01*
X-1182980Y603399D01*
X-1182920Y603418D01*
X-1182856Y603425D01*
G01X-1182739D02*
X-1184085Y602080D01*
G01X-1168151Y605591D02*
X-1167888Y605702D01*
G01X-1183776Y599831D02*
G03X-1183872Y599292I1458J-538D01*
G01X-1176316Y605984D02*
G03X-1177300Y605017I0J-984D01*
G01X-1174645Y682009D02*
X-1160145D01*
G01X-1169100Y691614D02*
X-1165690D01*
G01X-1169100D02*
X-1174645Y682009D01*
G01X-1165690Y691614D02*
G03X-1169100I-1705J-984D01*
G01X-1223504Y851719D02*
X-1211693D01*
G01X-1159699Y-837696D02*
Y-856633D01*
G01X-1085621Y-597187D02*
G03I-9842J0D01*
G01X-1157274Y68419D02*
Y-466085D01*
G01X-1161211D02*
G03X-1157274I1969J0D01*
G01X-1094479Y-221990D02*
G03I-18701J0D01*
G01X-1106290D02*
G03I-6890J0D01*
G01X-1094479Y85096D02*
G03I-18701J0D01*
G01X-1156859Y70180D02*
G03X-1157274Y68419I3522J-1759D01*
G01X-1138678Y106542D02*
X-1156859Y70180D01*
G01X-822306Y108719D02*
X-1135156D01*
G01D02*
G03X-1138678Y106542I0J-3937D01*
G01X-1106290Y85096D02*
G03I-6890J0D01*
G01X-1159261Y496240D02*
X-1158884Y496315D01*
X-1158565Y496528D01*
X-1158352Y496848D01*
X-1158277Y497224D01*
G01X-1159485Y496464D02*
X-1159267Y496488D01*
X-1159059Y496561D01*
X-1158874Y496677D01*
X-1158716Y496834D01*
X-1158599Y497020D01*
X-1158526Y497227D01*
X-1158501Y497448D01*
G01X-1156293Y488760D02*
X-1157001D01*
G01X-1155111Y489941D02*
X-1158182D01*
G01X-1154458Y492769D02*
X-1155082D01*
G01X-1158212D02*
X-1162168D01*
G01X-1163006Y497421D02*
X-1157374D01*
G01X-1155920D02*
X-1150288D01*
G01X-1155920D02*
X-1155692Y497299D01*
X-1155490Y497144D01*
X-1155321Y496957D01*
X-1155193Y496742D01*
X-1155111Y496506D01*
G01X-1163006Y497421D02*
X-1162788Y497247D01*
X-1162587Y497019D01*
X-1162414Y496741D01*
X-1162281Y496420D01*
X-1162198Y496070D01*
X-1162168Y495706D01*
G01X-1155920Y497421D02*
X-1155702Y497247D01*
X-1155500Y497019D01*
X-1155327Y496741D01*
X-1155194Y496420D01*
X-1155111Y496070D01*
X-1155082Y495706D01*
G01X-1158182Y489941D02*
X-1157001Y488760D01*
G01X-1159261Y496240D02*
X-1159485Y496464D01*
G01X-1158501Y497448D02*
X-1158277Y497224D01*
G01X-1162168Y496278D02*
X-1162221Y496605D01*
X-1162378Y496919D01*
X-1162641Y497199D01*
X-1163006Y497421D01*
G01X-1155082Y496278D02*
X-1155090Y496401D01*
X-1155111Y496523D01*
G01X-1160505Y492697D02*
X-1161725Y562596D01*
G01X-1160741D02*
X-1159521Y492697D01*
G01X-1165298Y490335D02*
Y496278D01*
G01X-1162168D02*
Y490335D01*
G01X-1159485Y496464D02*
Y503891D01*
G01X-1158501Y497448D02*
Y502906D01*
G01X-1158277Y497224D02*
Y503130D01*
G01X-1158212Y490335D02*
Y496278D01*
G01X-1158182Y489941D02*
Y500571D01*
G01X-1155111D02*
Y489941D01*
G01X-1155082Y496278D02*
Y490335D01*
G01X-1154458Y487776D02*
Y584331D01*
G01X-1158212Y496278D02*
X-1158204Y496402D01*
X-1158182Y496523D01*
G01X-1165298Y495706D02*
X-1165270Y496070D01*
X-1165186Y496420D01*
X-1165054Y496741D01*
X-1164881Y497019D01*
X-1164679Y497247D01*
X-1164461Y497421D01*
G01X-1158212Y495706D02*
X-1158183Y496070D01*
X-1158099Y496420D01*
X-1157967Y496741D01*
X-1157794Y497019D01*
X-1157593Y497247D01*
X-1157374Y497421D01*
G01X-1165298Y496278D02*
X-1165204Y496714D01*
X-1164923Y497114D01*
X-1164461Y497421D01*
G01X-1158182Y496506D02*
X-1158100Y496745D01*
X-1157971Y496961D01*
X-1157801Y497146D01*
X-1157600Y497300D01*
X-1157374Y497421D01*
G01X-1155111Y489941D02*
X-1156293Y488760D01*
G01X-1155920Y497421D02*
G03X-1157374I-727J-1386D01*
G01X-1163006D02*
G03X-1164461I-727J-1385D01*
G01X-1166288Y506727D02*
X-1166853Y506722D01*
G01X-1155111Y500571D02*
X-1154458D01*
G01X-1159261Y520256D02*
X-1158884Y520331D01*
X-1158565Y520544D01*
X-1158352Y520863D01*
X-1158277Y521240D01*
G01X-1159485Y520479D02*
X-1159267Y520504D01*
X-1159059Y520576D01*
X-1158874Y520692D01*
X-1158716Y520850D01*
X-1158599Y521035D01*
X-1158526Y521242D01*
X-1158501Y521464D01*
G01X-1161953Y511062D02*
X-1162088Y511061D01*
X-1162224Y511060D01*
G01X-1163635Y511059D02*
X-1162224Y511060D01*
G01X-1165385Y511485D02*
X-1164535D01*
G01Y512335D02*
X-1165385D01*
G01X-1161953Y512757D02*
X-1162088Y512758D01*
X-1162224Y512759D01*
X-1163635D01*
G01X-1159485Y503891D02*
X-1159267Y503866D01*
X-1159059Y503794D01*
X-1158874Y503678D01*
X-1158716Y503520D01*
X-1158599Y503335D01*
X-1158526Y503128D01*
X-1158501Y502906D01*
G01X-1159485Y527906D02*
X-1159267Y527882D01*
X-1159059Y527809D01*
X-1158874Y527693D01*
X-1158716Y527536D01*
X-1158599Y527350D01*
X-1158526Y527143D01*
X-1158501Y526922D01*
G01X-1165385Y512335D02*
X-1166225Y512819D01*
G01X-1165315Y513729D02*
X-1163635Y512759D01*
G01X-1159261Y520256D02*
X-1159485Y520479D01*
G01X-1158501Y521464D02*
X-1158277Y521240D01*
G01X-1166225Y512819D02*
X-1166710Y513659D01*
G01X-1166285Y515409D02*
X-1165315Y513729D01*
G01X-1158277Y503130D02*
X-1158352Y503507D01*
X-1158565Y503826D01*
X-1158884Y504039D01*
X-1159261Y504114D01*
G01X-1158277Y527146D02*
X-1158352Y527522D01*
X-1158565Y527842D01*
X-1158884Y528055D01*
X-1159261Y528130D01*
G01X-1161953Y512757D02*
X-1161948Y512192D01*
Y511627D01*
X-1161953Y511062D01*
G01X-1166285Y516820D02*
X-1166287Y516956D01*
X-1166288Y517092D01*
G01X-1166710Y509309D02*
Y510159D01*
G01Y513659D02*
Y514509D01*
G01X-1166285Y515409D02*
Y516820D01*
G01X-1164535Y512335D02*
Y511485D01*
G01X-1159485Y520479D02*
Y527906D01*
G01X-1158501Y521464D02*
Y526922D01*
G01X-1158277Y521240D02*
Y527146D01*
G01X-1166285Y508409D02*
Y506998D01*
X-1166287Y506863D01*
X-1166288Y506727D01*
G01X-1166225Y511000D02*
X-1166710Y510159D01*
G01X-1165315Y510089D02*
X-1166285Y508409D01*
G01X-1158277Y527146D02*
X-1158501Y526922D01*
G01X-1159485Y503891D02*
X-1159261Y504114D01*
G01X-1158277Y503130D02*
X-1158501Y502906D01*
G01X-1166225Y511000D02*
X-1165385Y511485D01*
G01X-1163635Y511059D02*
X-1165315Y510089D01*
G01X-1166285Y507135D02*
G03X-1162360Y511059I-850J4775D01*
G01Y512759D02*
G03X-1166285Y516684I-4775J-850D01*
G01X-1161765Y515650D02*
G03I-1969J0D01*
G01X-1154678D02*
G03I-1969J0D01*
G01X-1096979Y487776D02*
X-1153117D01*
G01X-1149206Y488760D02*
X-1149915D01*
G01X-1148025Y489941D02*
X-1151096D01*
G01X-1096979Y491122D02*
X-1153117D01*
G01X-1096979Y494705D02*
X-1153117D01*
G01X-1096979Y495177D02*
X-1153117D01*
G01X-1121941Y497421D02*
X-1127573D01*
G01X-1129028D02*
X-1134660D01*
G01X-1136115D02*
X-1141746D01*
G01X-1143201D02*
X-1148833D01*
G01D02*
X-1148615Y497247D01*
X-1148413Y497019D01*
X-1148241Y496741D01*
X-1148108Y496420D01*
X-1148024Y496070D01*
X-1147995Y495706D01*
G01X-1141746Y497421D02*
X-1141528Y497247D01*
X-1141327Y497019D01*
X-1141154Y496741D01*
X-1141021Y496420D01*
X-1140938Y496070D01*
X-1140909Y495706D01*
G01X-1134660Y497421D02*
X-1134442Y497247D01*
X-1134240Y497019D01*
X-1134067Y496741D01*
X-1133935Y496420D01*
X-1133851Y496070D01*
X-1133822Y495706D01*
G01X-1127573Y497421D02*
X-1127355Y497247D01*
X-1127154Y497019D01*
X-1126981Y496741D01*
X-1126848Y496420D01*
X-1126765Y496070D01*
X-1126735Y495706D01*
G01X-1151096Y489941D02*
X-1149915Y488760D01*
G01X-1147995Y496278D02*
X-1148048Y496605D01*
X-1148205Y496919D01*
X-1148467Y497199D01*
X-1148833Y497421D01*
G01X-1153117Y576489D02*
Y487776D01*
G01X-1151125Y496278D02*
Y490335D01*
G01X-1151096Y492697D02*
Y489941D01*
G01X-1148025D02*
Y492697D01*
G01X-1147995Y496278D02*
Y490335D01*
G01X-1140909Y496278D02*
X-1140961Y496605D01*
X-1141118Y496919D01*
X-1141381Y497199D01*
X-1141746Y497421D01*
G01X-1133822Y496278D02*
X-1133875Y496605D01*
X-1134031Y496919D01*
X-1134294Y497199D01*
X-1134660Y497421D01*
G01X-1126735Y496278D02*
X-1126788Y496605D01*
X-1126945Y496919D01*
X-1127207Y497199D01*
X-1127573Y497421D01*
G01X-1144039Y496278D02*
Y490335D01*
G01X-1140909Y496278D02*
Y490335D01*
G01X-1136952Y496278D02*
Y490335D01*
G01X-1133822Y496278D02*
Y490335D01*
G01X-1129865Y496278D02*
Y490335D01*
G01X-1126735Y496278D02*
Y490335D01*
G01X-1151125Y495706D02*
X-1151096Y496070D01*
X-1151013Y496420D01*
X-1150880Y496741D01*
X-1150707Y497019D01*
X-1150506Y497247D01*
X-1150288Y497421D01*
G01X-1144039Y495706D02*
X-1144010Y496070D01*
X-1143926Y496420D01*
X-1143794Y496741D01*
X-1143621Y497019D01*
X-1143419Y497247D01*
X-1143201Y497421D01*
G01X-1136952Y495706D02*
X-1136923Y496070D01*
X-1136839Y496420D01*
X-1136707Y496741D01*
X-1136534Y497019D01*
X-1136333Y497247D01*
X-1136115Y497421D01*
G01X-1129865Y495706D02*
X-1129837Y496070D01*
X-1129753Y496420D01*
X-1129620Y496741D01*
X-1129448Y497019D01*
X-1129246Y497247D01*
X-1129028Y497421D01*
G01X-1151125Y496278D02*
X-1151031Y496714D01*
X-1150750Y497114D01*
X-1150288Y497421D01*
G01X-1144039Y496278D02*
X-1143944Y496714D01*
X-1143663Y497114D01*
X-1143201Y497421D01*
G01X-1136952Y496278D02*
X-1136858Y496714D01*
X-1136576Y497114D01*
X-1136115Y497421D01*
G01X-1129865Y496278D02*
X-1129771Y496714D01*
X-1129490Y497114D01*
X-1129028Y497421D01*
G01X-1148025Y489941D02*
X-1149206Y488760D01*
G01X-1148833Y497421D02*
G03X-1150288I-727J-1385D01*
G01X-1127573D02*
G03X-1129028I-727J-1385D01*
G01X-1134660D02*
G03X-1136115I-727J-1385D01*
G01X-1141746D02*
G03X-1143201I-727J-1385D01*
G01X-1127313Y496339D02*
G03I-708J0D01*
G01X-1141486D02*
G03I-709J0D01*
G01X-1096979Y501221D02*
X-1153117D01*
G01X-1148572Y501063D02*
G03I-709J0D01*
G01Y505394D02*
G03I-709J0D01*
G01Y510905D02*
G03I-709J0D01*
G01X-1147592Y515650D02*
G03I-1968J0D01*
G01X-1148572Y515236D02*
G03I-709J0D01*
G01Y519567D02*
G03I-709J0D01*
G01Y525079D02*
G03I-709J0D01*
G01X-1127313Y500669D02*
G03I-708J0D01*
G01X-1134399Y501063D02*
G03I-709J0D01*
G01Y505394D02*
G03I-709J0D01*
G01X-1141486Y500669D02*
G03I-709J0D01*
G01X-1134399Y510905D02*
G03I-709J0D01*
G01X-1141486Y506181D02*
G03I-709J0D01*
G01Y510512D02*
G03I-709J0D01*
G01X-1140505Y515650D02*
G03I-1969J0D01*
G01X-1133418D02*
G03I-1969J0D01*
G01X-1134399Y515236D02*
G03I-709J0D01*
G01X-1141486Y514843D02*
G03I-709J0D01*
G01X-1127313Y506181D02*
G03I-708J0D01*
G01Y510512D02*
G03I-708J0D01*
G01X-1126332Y515650D02*
G03I-1969J0D01*
G01X-1127313Y514843D02*
G03I-708J0D01*
G01X-1134399Y519567D02*
G03I-709J0D01*
G01X-1141486Y520354D02*
G03I-709J0D01*
G01X-1134399Y525079D02*
G03I-709J0D01*
G01X-1141486Y524685D02*
G03I-709J0D01*
G01X-1127313Y520354D02*
G03I-708J0D01*
G01Y524685D02*
G03I-708J0D01*
G01X-1100681Y497421D02*
X-1106313D01*
G01X-1107768D02*
X-1113400D01*
G01X-1114855D02*
X-1120487D01*
G01D02*
X-1120268Y497247D01*
X-1120067Y497019D01*
X-1119894Y496741D01*
X-1119761Y496420D01*
X-1119678Y496070D01*
X-1119649Y495706D01*
G01X-1113400Y497421D02*
X-1113182Y497247D01*
X-1112980Y497019D01*
X-1112807Y496741D01*
X-1112675Y496420D01*
X-1112591Y496070D01*
X-1112562Y495706D01*
G01X-1106313Y497421D02*
X-1106095Y497247D01*
X-1105894Y497019D01*
X-1105721Y496741D01*
X-1105588Y496420D01*
X-1105505Y496070D01*
X-1105476Y495706D01*
G01X-1119649Y496278D02*
X-1119702Y496605D01*
X-1119858Y496919D01*
X-1120121Y497199D01*
X-1120487Y497421D01*
G01X-1112562Y496278D02*
X-1112615Y496605D01*
X-1112772Y496919D01*
X-1113034Y497199D01*
X-1113400Y497421D01*
G01X-1122779Y496278D02*
Y490335D01*
G01X-1119649Y496278D02*
Y490335D01*
G01X-1115692Y496278D02*
Y490335D01*
G01X-1112562Y496278D02*
Y490335D01*
G01X-1108605Y496278D02*
Y490335D01*
G01X-1105476Y496278D02*
X-1105528Y496605D01*
X-1105685Y496919D01*
X-1105948Y497199D01*
X-1106313Y497421D01*
G01X-1105476Y496278D02*
Y490335D01*
G01X-1122779Y495706D02*
X-1122750Y496070D01*
X-1122666Y496420D01*
X-1122534Y496741D01*
X-1122361Y497019D01*
X-1122159Y497247D01*
X-1121941Y497421D01*
G01X-1115692Y495706D02*
X-1115663Y496070D01*
X-1115580Y496420D01*
X-1115447Y496741D01*
X-1115274Y497019D01*
X-1115073Y497247D01*
X-1114855Y497421D01*
G01X-1108605Y495706D02*
X-1108577Y496070D01*
X-1108493Y496420D01*
X-1108361Y496741D01*
X-1108188Y497019D01*
X-1107986Y497247D01*
X-1107768Y497421D01*
G01X-1122779Y496278D02*
X-1122685Y496714D01*
X-1122403Y497114D01*
X-1121941Y497421D01*
G01X-1115692Y496278D02*
X-1115598Y496714D01*
X-1115317Y497114D01*
X-1114855Y497421D01*
G01X-1108605Y496278D02*
X-1108511Y496714D01*
X-1108230Y497114D01*
X-1107768Y497421D01*
G01X-1120487D02*
G03X-1121941I-727J-1386D01*
G01X-1106313D02*
G03X-1107768I-728J-1385D01*
G01X-1113400D02*
G03X-1114855I-727J-1385D01*
G01X-1113139Y496339D02*
G03I-709J0D01*
G01X-1119245Y515650D02*
G03I-1969J0D01*
G01X-1106053Y501063D02*
G03I-709J0D01*
G01Y505394D02*
G03I-709J0D01*
G01X-1113139Y500669D02*
G03I-709J0D01*
G01X-1120226Y501063D02*
G03I-709J0D01*
G01Y505394D02*
G03I-709J0D01*
G01X-1113139Y506181D02*
G03I-709J0D01*
G01X-1120226Y510905D02*
G03I-709J0D01*
G01X-1113139Y510512D02*
G03I-709J0D01*
G01X-1112159Y515650D02*
G03I-1968J0D01*
G01X-1113139Y514843D02*
G03I-709J0D01*
G01X-1120226Y515236D02*
G03I-709J0D01*
G01X-1106053Y510905D02*
G03I-709J0D01*
G01X-1105072Y515650D02*
G03I-1969J0D01*
G01X-1097985D02*
G03I-1969J0D01*
G01X-1106053Y515236D02*
G03I-709J0D01*
G01X-1120226Y519567D02*
G03I-709J0D01*
G01Y525079D02*
G03I-709J0D01*
G01X-1106053Y519567D02*
G03I-709J0D01*
G01Y525079D02*
G03I-709J0D01*
G01X-1113139Y520354D02*
G03I-709J0D01*
G01Y524685D02*
G03I-709J0D01*
G01X-1159485Y527906D02*
X-1159261Y528130D01*
G01X-1154852Y531949D02*
X-1154458D01*
G01X-1155800Y536949D02*
X-1157493D01*
G01X-1162985D02*
X-1164481D01*
G01X-1165560Y539429D02*
X-1161300D01*
G01X-1159600Y554232D02*
X-1160781D01*
G01X-1154458Y555413D02*
X-1155013D01*
G01X-1158281D02*
X-1162198D01*
G01X-1164481Y536949D02*
X-1165269Y537404D01*
G01X-1157493Y536949D02*
X-1158281Y537404D01*
G01X-1166686Y554232D02*
X-1165308Y551846D01*
G01X-1159600Y554232D02*
X-1158281Y551948D01*
G01X-1167135Y537854D02*
Y533594D01*
G01Y541004D02*
Y545264D01*
G01X-1165308Y551846D02*
Y535335D01*
G01X-1165269Y555413D02*
Y537404D01*
G01X-1162198Y555413D02*
Y537404D01*
G01X-1162159Y535335D02*
Y551846D01*
G01X-1158281Y555413D02*
Y537404D01*
G01X-1158222Y537369D02*
Y535335D01*
G01X-1155442Y531358D02*
Y530965D01*
G01X-1155072Y535335D02*
Y537369D01*
G01X-1155013Y537404D02*
Y555413D01*
G01X-1154852Y584331D02*
Y531949D01*
G01X-1162159Y551846D02*
X-1160781Y554232D01*
G01X-1155013Y551948D02*
X-1153694Y554232D01*
G01X-1162198Y537404D02*
X-1162985Y536949D01*
G01X-1155013Y537404D02*
X-1155800Y536949D01*
G01X-1165308Y535335D02*
G03X-1162159I1575J0D01*
G01X-1158222D02*
G03X-1155072I1575J0D01*
G01X-1155442Y530965D02*
G03X-1154458Y531949I0J984D01*
G01X-1155442Y531358D02*
G03X-1154852Y531949I-1J591D01*
G01X-1159773Y569272D02*
X-1159396Y569346D01*
X-1159077Y569560D01*
X-1158864Y569879D01*
X-1158789Y570256D01*
G01X-1159928Y569427D02*
X-1159710Y569451D01*
X-1159503Y569523D01*
X-1159317Y569640D01*
X-1159159Y569797D01*
X-1159042Y569983D01*
X-1158969Y570190D01*
X-1158944Y570411D01*
G01X-1157034Y586085D02*
X-1157108Y586080D01*
G01X-1161297Y562602D02*
X-1161725Y562596D01*
G01X-1157324Y586079D02*
X-1157109Y586080D01*
G01X-1161111Y562603D02*
X-1161300Y562602D01*
G01X-1161181Y574094D02*
X-1162467D01*
G01X-1163536D02*
X-1166639D01*
G01X-1160954Y562603D02*
X-1161114D01*
G01X-1157643Y586080D02*
X-1157321Y586079D01*
G01X-1160956Y562603D02*
X-1160839Y562602D01*
X-1160767Y562599D01*
X-1160741Y562596D01*
G01X-1157641Y586080D02*
X-1158018Y586085D01*
G01X-1159928Y580928D02*
X-1159710Y580903D01*
X-1159503Y580831D01*
X-1159317Y580715D01*
X-1159159Y580557D01*
X-1159042Y580372D01*
X-1158969Y580165D01*
X-1158944Y579944D01*
G01X-1161725Y563563D02*
X-1161424Y563516D01*
X-1161152Y563379D01*
X-1160935Y563166D01*
X-1160794Y562896D01*
X-1160741Y562596D01*
G01X-1156050Y585118D02*
X-1156350Y585165D01*
X-1156622Y585302D01*
X-1156840Y585515D01*
X-1156981Y585785D01*
X-1157034Y586085D01*
G01X-1159773Y569272D02*
X-1159928Y569427D01*
G01X-1158944Y570411D02*
X-1158789Y570256D01*
G01X-1163498Y573908D02*
X-1163456Y573744D01*
G01X-1163536Y574094D02*
X-1163498Y573908D01*
X-1163456Y573744D01*
X-1163409Y573600D01*
X-1163357Y573479D01*
X-1163300Y573382D01*
X-1163237Y573311D01*
X-1163170Y573270D01*
X-1163100Y573258D01*
X-1163029Y573275D01*
X-1162954Y573319D01*
X-1162876Y573391D01*
X-1162796Y573488D01*
X-1162715Y573608D01*
X-1162634Y573749D01*
X-1162551Y573911D01*
X-1162467Y574094D01*
G01X-1158789Y580098D02*
X-1158864Y580475D01*
X-1159077Y580794D01*
X-1159396Y581008D01*
X-1159773Y581083D01*
G01X-1154852Y584331D02*
X-1154880Y584614D01*
X-1154961Y584867D01*
X-1155087Y585050D01*
X-1155245Y585118D01*
G01X-1158348Y605017D02*
X-1158018Y586085D01*
G01X-1157365Y605017D02*
X-1157034Y586085D01*
G01X-1166639Y574094D02*
Y605591D01*
G01X-1166577D02*
Y559331D01*
G01X-1166348Y605591D02*
Y559331D01*
G01X-1163701Y605591D02*
Y559331D01*
G01X-1163561Y605591D02*
Y559331D01*
G01X-1163536Y605984D02*
Y574094D01*
G01X-1162467D02*
Y605591D01*
G01X-1162454Y563563D02*
Y597559D01*
G01X-1162403Y605591D02*
Y559331D01*
G01X-1162220Y605591D02*
Y559331D01*
G01X-1161725Y563563D02*
Y562596D01*
G01X-1161332Y559331D02*
Y573259D01*
G01X-1161181Y605591D02*
Y574094D01*
G01X-1161154Y605591D02*
Y559331D01*
G01X-1161124Y605591D02*
Y559331D01*
G01X-1161118Y605591D02*
Y559331D01*
G01X-1159928Y569427D02*
Y580928D01*
G01X-1158944Y570411D02*
Y579944D01*
G01X-1158789Y570256D02*
Y580098D01*
G01X-1158018Y586085D02*
Y585118D01*
G01X-1155245Y564547D02*
Y585118D01*
G01X-1154458Y584331D02*
X-1154488Y584546D01*
X-1154579Y584750D01*
X-1154734Y584929D01*
X-1154956Y585063D01*
X-1155245Y585118D01*
G01X-1161332Y573258D02*
X-1161215Y573911D01*
G01X-1161181Y574094D02*
X-1161215Y573908D01*
G01X-1162710Y567402D02*
X-1161332Y573259D01*
G01X-1162716Y573607D02*
X-1162634Y573749D01*
X-1162551Y573911D01*
G01X-1159928Y580928D02*
X-1159773Y581083D01*
G01X-1158789Y580098D02*
X-1158944Y579944D01*
G01X-1160741Y562596D02*
G03X-1161725Y563563I-984J-17D01*
G01X-1157034Y586085D02*
G03X-1156050Y585118I984J17D01*
G01X-1154458Y584331D02*
G03X-1155245Y585118I-787J0D01*
G01X-1148572Y529409D02*
G03I-709J0D01*
G01X-1141486Y529016D02*
G03I-709J0D01*
G01X-1127313D02*
G03I-708J0D01*
G01X-1134399Y529409D02*
G03I-709J0D01*
G01X-1148182Y530827D02*
X-1150938D01*
G01X-1147198Y533350D02*
X-1151922D01*
G01X-1148812Y536507D02*
X-1150308D01*
G01X-1124167Y554232D02*
X-1125348D01*
G01X-1131253D02*
X-1132434D01*
G01X-1138340D02*
X-1139521D01*
G01X-1145426D02*
X-1146607D01*
G01X-1153694D02*
X-1152513D01*
G01X-1151096Y555236D02*
X-1153117D01*
G01X-1148025D02*
X-1101489D01*
G01X-1151096Y537871D02*
X-1150308Y536507D01*
G01X-1152513Y554232D02*
X-1151135Y551846D01*
G01X-1145426Y554232D02*
X-1144048Y551846D01*
G01X-1138340Y554232D02*
X-1136962Y551846D01*
G01X-1131253Y554232D02*
X-1129875Y551846D01*
G01X-1151922Y555236D02*
Y531811D01*
G01X-1151135Y551846D02*
Y549148D01*
G01Y547489D02*
Y541825D01*
G01Y540166D02*
Y535335D01*
G01X-1151096Y537871D02*
Y540105D01*
G01Y541885D02*
Y547428D01*
G01Y549208D02*
Y555236D01*
G01X-1148025D02*
Y549208D01*
G01Y547428D02*
Y541885D01*
G01Y540105D02*
Y537871D01*
G01X-1147985Y535335D02*
Y540166D01*
G01Y541825D02*
Y547489D01*
G01Y549148D02*
Y551846D01*
G01X-1147198Y555236D02*
Y531811D01*
G01X-1144048Y551846D02*
Y535335D01*
G01X-1140899D02*
Y551846D01*
G01X-1136962D02*
Y535335D01*
G01X-1133812D02*
Y551846D01*
G01X-1129875D02*
Y535335D01*
G01X-1126726D02*
Y551846D01*
G01X-1147985D02*
X-1146607Y554232D01*
G01X-1140899Y551846D02*
X-1139521Y554232D01*
G01X-1148025Y537871D02*
X-1148812Y536507D01*
G01X-1133812Y551846D02*
X-1132434Y554232D01*
G01X-1126726Y551846D02*
X-1125348Y554232D01*
G01X-1151135Y535335D02*
G03X-1147985I1575J0D01*
G01X-1151922Y531811D02*
G03X-1150938Y530827I984J0D01*
G01X-1148182D02*
G03X-1147198Y531811I0J984D01*
G01X-1148572Y533740D02*
G03I-709J0D01*
G01Y539252D02*
G03I-709J0D01*
G01X-1134399Y533740D02*
G03I-709J0D01*
G01X-1144048Y535335D02*
G03X-1140899I1574J0D01*
G01X-1136962D02*
G03X-1133812I1575J0D01*
G01X-1134399Y539252D02*
G03I-709J0D01*
G01X-1141486Y534528D02*
G03I-709J0D01*
G01Y538858D02*
G03I-709J0D01*
G01X-1129875Y535335D02*
G03X-1126726I1575J0D01*
G01X-1127313Y534528D02*
G03I-708J0D01*
G01Y538858D02*
G03I-708J0D01*
G01X-1151096Y541885D02*
G03Y540105I1299J-890D01*
G01Y549208D02*
G03Y547428I1299J-890D01*
G01X-1148025D02*
G03Y549208I-1299J890D01*
G01Y540105D02*
G03Y541885I-1299J890D01*
G01X-1148572Y543583D02*
G03I-709J0D01*
G01Y547913D02*
G03I-709J0D01*
G01Y553425D02*
G03I-709J0D01*
G01Y557756D02*
G03I-709J0D01*
G01X-1134399Y543583D02*
G03I-709J0D01*
G01X-1127313Y543189D02*
G03I-708J0D01*
G01Y548701D02*
G03I-708J0D01*
G01X-1134399Y547913D02*
G03I-709J0D01*
G01Y553425D02*
G03I-709J0D01*
G01X-1141486Y543189D02*
G03I-709J0D01*
G01Y548701D02*
G03I-709J0D01*
G01X-1134399Y557756D02*
G03I-709J0D01*
G01X-1128118Y576938D02*
X-1128035Y576960D01*
X-1127957Y576993D01*
X-1127890Y577037D01*
X-1127837Y577090D01*
X-1127798Y577149D01*
X-1127778Y577210D01*
G01X-1142291Y576938D02*
X-1142208Y576960D01*
X-1142131Y576993D01*
X-1142063Y577037D01*
X-1142010Y577090D01*
X-1141971Y577149D01*
X-1141952Y577210D01*
G01X-1148209Y565440D02*
X-1148225Y565436D01*
X-1148241Y565434D01*
X-1148256Y565433D01*
G01X-1126996Y575308D02*
X-1126920Y575325D01*
X-1126857Y575367D01*
X-1126814Y575431D01*
X-1126800Y575505D01*
G01X-1141170Y575308D02*
X-1141093Y575325D01*
X-1141030Y575367D01*
X-1140987Y575431D01*
X-1140973Y575505D01*
G01X-1142157Y575903D02*
X-1142078Y575916D01*
X-1142001Y575940D01*
X-1141931Y575974D01*
X-1141871Y576017D01*
X-1141822Y576068D01*
X-1141788Y576123D01*
X-1141770Y576181D01*
G01X-1128166Y576932D02*
X-1128159Y576933D01*
X-1128151D01*
X-1128143Y576935D01*
X-1128135D01*
X-1128126Y576937D01*
X-1128118Y576938D01*
G01X-1142339Y576932D02*
X-1142332Y576933D01*
X-1142324D01*
X-1142316Y576935D01*
X-1142308D01*
X-1142300Y576937D01*
X-1142291Y576938D01*
G01X-1096979Y564055D02*
X-1153117D01*
G01X-1096979Y564842D02*
X-1153605D01*
G01X-1140973Y564921D02*
X-1144555D01*
G01X-1130382D02*
X-1126800D01*
G01X-1097306Y565433D02*
X-1153605D01*
G01X-1127311Y566417D02*
X-1129870D01*
G01X-1134398D02*
X-1136957D01*
G01X-1141485D02*
X-1144044D01*
G01X-1148571D02*
X-1151130D01*
G01X-1148670Y566654D02*
X-1151032D01*
G01X-1136957Y568055D02*
X-1141485D01*
G01X-1153605D02*
X-1151130D01*
G01X-1148571D02*
X-1144044D01*
G01X-1134398D02*
X-1129870D01*
G01X-1127311D02*
X-1122784D01*
G01X-1148670Y568228D02*
X-1151032D01*
G01X-1122784Y568252D02*
X-1127311D01*
G01X-1129870D02*
X-1134398D01*
G01X-1136957D02*
X-1141485D01*
G01X-1144044D02*
X-1148571D01*
G01X-1151130D02*
X-1153605D01*
G01X-1129870Y570354D02*
X-1131151D01*
G01X-1144044D02*
X-1145324D01*
G01X-1145972Y570379D02*
X-1144044D01*
G01X-1131799D02*
X-1129870D01*
G01X-1148670Y570591D02*
X-1151032D01*
G01X-1127181Y570748D02*
X-1127311D01*
G01X-1129870D02*
X-1131151D01*
G01X-1127705D02*
X-1129477D01*
G01X-1134792D02*
X-1136563D01*
G01X-1141354D02*
X-1141485D01*
G01X-1141878D02*
X-1143650D01*
G01X-1144044D02*
X-1145324D01*
G01X-1148965D02*
X-1150737D01*
G01X-1145972Y570761D02*
X-1144044D01*
G01X-1131799D02*
X-1129870D01*
G01X-1145281Y570945D02*
X-1144044D01*
G01X-1131107D02*
X-1129870D01*
G01Y571142D02*
X-1132561D01*
G01X-1146735D02*
X-1144044D01*
G01X-1145206Y571679D02*
X-1144044D01*
G01X-1131033D02*
X-1129870D01*
G01X-1145594Y571876D02*
X-1144044D01*
G01X-1131420D02*
X-1129870D01*
G01X-1126996Y575308D02*
X-1130185D01*
G01X-1141170D02*
X-1144359D01*
G01X-1146735Y575624D02*
X-1141355D01*
G01X-1132561D02*
X-1127181D01*
G01X-1126800Y575728D02*
X-1130382D01*
G01X-1140973D02*
X-1144555D01*
G01X-1145932Y575903D02*
X-1142157D01*
G01X-1131759D02*
X-1127984D01*
G01X-1132176Y575926D02*
X-1132564D01*
G01X-1146350D02*
X-1146737D01*
G01X-1141740D02*
X-1141352D01*
G01X-1127567D02*
X-1127179D01*
G01X-1133886Y576489D02*
X-1137469D01*
G01X-1153117D02*
X-1153605D01*
G01X-1151496D02*
X-1148205D01*
G01X-1128166Y576932D02*
X-1131577D01*
G01X-1142339D02*
X-1145750D01*
G01X-1146138Y577210D02*
X-1141952D01*
G01X-1131965D02*
X-1127778D01*
G01X-1138448Y565433D02*
X-1138493Y565438D01*
X-1138538Y565455D01*
X-1138579Y565483D01*
X-1138612Y565521D01*
X-1138640Y565566D01*
G01X-1124275Y565433D02*
X-1124320Y565438D01*
X-1124365Y565455D01*
X-1124405Y565483D01*
X-1124439Y565521D01*
X-1124467Y565566D01*
G01X-1144359Y575308D02*
X-1144405Y575314D01*
X-1144451Y575331D01*
X-1144491Y575360D01*
X-1144524Y575399D01*
X-1144547Y575448D01*
X-1144555Y575505D01*
G01X-1130185Y575308D02*
X-1130232Y575314D01*
X-1130278Y575331D01*
X-1130318Y575360D01*
X-1130351Y575399D01*
X-1130374Y575448D01*
X-1130382Y575505D01*
G01X-1131759Y575903D02*
X-1131839Y575916D01*
X-1131915Y575940D01*
X-1131985Y575974D01*
X-1132045Y576017D01*
X-1132094Y576068D01*
X-1132128Y576123D01*
X-1132146Y576181D01*
G01X-1145798Y576938D02*
X-1145791Y576937D01*
X-1145759Y576933D01*
X-1145750Y576932D01*
G01X-1145324Y570354D02*
X-1145631Y570415D01*
X-1145894Y570590D01*
X-1146066Y570849D01*
X-1146124Y571142D01*
G01X-1131151Y570354D02*
X-1131458Y570415D01*
X-1131721Y570590D01*
X-1131893Y570849D01*
X-1131950Y571142D01*
G01X-1145324Y570748D02*
X-1145533Y570802D01*
X-1145683Y570949D01*
X-1145736Y571142D01*
G01X-1151493Y565440D02*
X-1151477Y565436D01*
X-1151461Y565434D01*
X-1151445Y565433D01*
G01X-1131625Y576938D02*
X-1131618Y576937D01*
X-1131594Y576934D01*
X-1131585Y576933D01*
X-1131577Y576932D01*
G01X-1131151Y570748D02*
X-1131359Y570802D01*
X-1131509Y570949D01*
X-1131563Y571142D01*
G01X-1151642Y565518D02*
X-1151611Y565485D01*
X-1151574Y565461D01*
X-1151533Y565446D01*
X-1151493Y565440D01*
G01X-1145668Y571142D02*
X-1145649Y571102D01*
X-1145614Y571063D01*
X-1145566Y571028D01*
X-1145505Y570998D01*
X-1145436Y570973D01*
X-1145361Y570955D01*
X-1145281Y570945D01*
G01X-1145594Y571876D02*
X-1145574Y571836D01*
X-1145539Y571798D01*
X-1145491Y571763D01*
X-1145431Y571732D01*
X-1145361Y571707D01*
X-1145286Y571690D01*
X-1145206Y571679D01*
G01X-1131495Y571142D02*
X-1131476Y571102D01*
X-1131441Y571063D01*
X-1131393Y571028D01*
X-1131332Y570998D01*
X-1131263Y570973D01*
X-1131187Y570955D01*
X-1131107Y570945D01*
G01X-1131420Y571876D02*
X-1131401Y571836D01*
X-1131366Y571798D01*
X-1131318Y571763D01*
X-1131257Y571732D01*
X-1131188Y571707D01*
X-1131113Y571690D01*
X-1131033Y571679D01*
G01X-1146138Y577210D02*
X-1146118Y577149D01*
X-1146081Y577091D01*
X-1146027Y577039D01*
X-1145961Y576994D01*
X-1145882Y576960D01*
X-1145798Y576938D01*
G01X-1146319Y576181D02*
X-1146302Y576124D01*
X-1146268Y576069D01*
X-1146220Y576018D01*
X-1146160Y575975D01*
X-1146089Y575940D01*
X-1146013Y575916D01*
X-1145932Y575903D01*
G01X-1151485Y564842D02*
X-1151493Y565440D01*
G01X-1146737Y575926D02*
X-1146736Y575822D01*
Y575722D01*
X-1146735Y575624D01*
G01X-1151496Y576489D02*
X-1151493Y565440D01*
G01X-1153605Y603425D02*
Y564842D01*
G01X-1151642Y565518D02*
Y564842D01*
G01X-1151445Y576489D02*
Y565433D01*
G01X-1151130Y570354D02*
Y566417D01*
G01X-1151032Y570591D02*
Y566654D01*
G01X-1148670Y570591D02*
Y566654D01*
G01X-1148571Y570354D02*
Y566417D01*
G01X-1148256Y565433D02*
Y576489D01*
G01X-1148059Y565518D02*
Y564842D01*
G01X-1148205Y576489D02*
X-1148209Y565440D01*
G01X-1131965Y577210D02*
X-1131945Y577149D01*
X-1131907Y577091D01*
X-1131854Y577039D01*
X-1131787Y576994D01*
X-1131709Y576960D01*
X-1131625Y576938D01*
G01X-1142157Y575903D02*
X-1142135Y575820D01*
X-1142122Y575725D01*
X-1142117Y575624D01*
G01X-1127984Y575903D02*
X-1127962Y575820D01*
X-1127948Y575725D01*
X-1127944Y575624D01*
G01X-1144555Y565630D02*
X-1144541Y565556D01*
X-1144498Y565491D01*
X-1144434Y565449D01*
X-1144359Y565433D01*
G01X-1137469Y565630D02*
X-1137454Y565556D01*
X-1137411Y565491D01*
X-1137347Y565449D01*
X-1137272Y565433D01*
G01X-1130382Y565630D02*
X-1130367Y565556D01*
X-1130325Y565491D01*
X-1130261Y565449D01*
X-1130185Y565433D01*
G01X-1142157Y575903D02*
X-1142339Y576932D01*
G01X-1141952Y577210D02*
X-1141770Y576181D01*
G01X-1127984Y575903D02*
X-1128166Y576932D01*
G01X-1127778Y577210D02*
X-1127597Y576181D01*
G01X-1141770D02*
X-1141758Y576104D01*
X-1141748Y576018D01*
X-1141740Y575926D01*
G01X-1145668Y571142D02*
X-1145659Y571055D01*
X-1145630Y570972D01*
X-1145585Y570897D01*
X-1145523Y570834D01*
X-1145450Y570787D01*
X-1145368Y570758D01*
X-1145281Y570748D01*
G01X-1131495Y571142D02*
X-1131486Y571055D01*
X-1131457Y570972D01*
X-1131411Y570897D01*
X-1131350Y570834D01*
X-1131276Y570787D01*
X-1131195Y570758D01*
X-1131107Y570748D01*
G01X-1127567Y575926D02*
X-1127575Y576018D01*
X-1127585Y576104D01*
X-1127597Y576181D01*
G01X-1141736Y575724D02*
X-1141737Y575826D01*
X-1141740Y575926D01*
G01X-1132564D02*
X-1132563Y575822D01*
Y575722D01*
X-1132561Y575624D01*
G01X-1127563Y575724D02*
X-1127564Y575826D01*
X-1127567Y575926D01*
G01X-1146737Y599292D02*
Y575926D01*
G01X-1146735Y575624D02*
Y571142D01*
G01X-1146350Y599292D02*
Y575926D01*
G01X-1146138Y577210D02*
Y599292D01*
G01X-1146124Y571142D02*
Y601023D01*
G01X-1145972Y570379D02*
Y575624D01*
G01X-1145750Y576932D02*
Y599292D01*
G01X-1145736Y571142D02*
Y601023D01*
G01X-1145594D02*
Y571876D01*
G01X-1145324Y570748D02*
Y570354D01*
G01X-1145281Y570945D02*
Y570748D01*
G01X-1145206Y571679D02*
Y601023D01*
G01X-1144555Y575728D02*
Y564842D01*
G01X-1144359Y575308D02*
Y565433D01*
G01X-1144044Y571876D02*
Y566417D01*
G01X-1142844Y570748D02*
Y601023D01*
G01X-1142456D02*
Y570748D01*
G01X-1142339Y576932D02*
Y599292D01*
G01X-1142314Y601023D02*
Y570748D01*
G01X-1142117D02*
Y575624D01*
G01X-1141952Y577210D02*
Y599292D01*
G01X-1141926Y601023D02*
Y570748D01*
G01X-1141740Y575926D02*
Y599292D01*
G01X-1141736Y575724D02*
Y570721D01*
G01X-1141485Y570354D02*
Y566417D01*
G01X-1141355Y570748D02*
Y575624D01*
G01X-1141352Y575926D02*
Y599292D01*
G01X-1141170Y565433D02*
Y575308D01*
G01X-1140973Y564842D02*
Y575728D01*
G01X-1138645Y565566D02*
Y564842D01*
G01X-1138635Y600472D02*
Y565566D01*
G01X-1138448Y565433D02*
Y600472D01*
G01X-1137469Y576489D02*
Y564842D01*
G01X-1137272Y576489D02*
Y565433D01*
G01X-1136957Y570354D02*
Y566417D01*
G01X-1134708Y600472D02*
Y576489D01*
G01X-1134398Y570354D02*
Y566417D01*
G01X-1134083Y576489D02*
Y565433D01*
G01X-1133898Y576489D02*
X-1133896Y565566D01*
G01X-1133886Y564842D02*
Y576489D01*
G01X-1132564Y599292D02*
Y575926D01*
G01X-1132561Y575624D02*
Y571142D01*
G01X-1132176Y599292D02*
Y575926D01*
G01X-1131965Y577210D02*
Y599292D01*
G01X-1131950Y571142D02*
Y601023D01*
G01X-1131799Y570379D02*
Y575624D01*
G01X-1131577Y576932D02*
Y599292D01*
G01X-1131563Y571142D02*
Y601023D01*
G01X-1131420D02*
Y571876D01*
G01X-1131151Y570748D02*
Y570354D01*
G01X-1131107Y570945D02*
Y570748D01*
G01X-1131033Y571679D02*
Y601023D01*
G01X-1130382Y575728D02*
Y564842D01*
G01X-1130185Y575308D02*
Y565433D01*
G01X-1129870Y571876D02*
Y566417D01*
G01X-1128671Y570748D02*
Y601023D01*
G01X-1128283D02*
Y570748D01*
G01X-1128166Y576932D02*
Y599292D01*
G01X-1128141Y601023D02*
Y570748D01*
G01X-1127944D02*
Y575624D01*
G01X-1127778Y599292D02*
Y577210D01*
G01X-1127753Y601023D02*
Y570748D01*
G01X-1127567Y575926D02*
Y599292D01*
G01X-1127563Y575724D02*
Y570721D01*
G01X-1127311Y570354D02*
Y566417D01*
G01X-1127181Y570748D02*
Y575624D01*
G01X-1127179Y575926D02*
Y599292D01*
G01X-1126996Y565433D02*
Y575308D01*
G01X-1126800Y564842D02*
Y575728D01*
G01X-1124472Y565566D02*
Y564842D01*
G01X-1124461Y600472D02*
Y565566D01*
G01X-1124275Y565433D02*
Y600472D01*
G01X-1141479Y570329D02*
X-1141478Y570748D01*
G01X-1127306Y570329D02*
X-1127305Y570748D01*
G01X-1141354Y575624D02*
X-1141352Y575926D01*
G01X-1127181Y575624D02*
X-1127179Y575926D01*
G01X-1148209Y565440D02*
X-1148217Y564842D01*
G01X-1146350Y575926D02*
X-1146352Y575829D01*
X-1146353Y575728D01*
X-1146354Y571142D01*
G01X-1132176Y575926D02*
X-1132179Y575829D01*
X-1132180Y575728D01*
Y571142D01*
G01X-1145972Y575624D02*
X-1145968Y575725D01*
X-1145954Y575820D01*
X-1145932Y575903D01*
G01X-1131799Y575624D02*
X-1131794Y575725D01*
X-1131781Y575820D01*
X-1131759Y575903D01*
G01X-1146350Y575926D02*
X-1146341Y576018D01*
X-1146331Y576104D01*
X-1146319Y576181D01*
G01X-1145594Y571876D02*
X-1145668Y571142D01*
G01X-1145281Y570945D02*
X-1145206Y571679D01*
G01X-1131420Y571876D02*
X-1131495Y571142D01*
G01X-1131107Y570945D02*
X-1131033Y571679D01*
G01X-1146319Y576181D02*
X-1146138Y577210D01*
G01X-1145750Y576932D02*
X-1145932Y575903D01*
G01X-1140973Y565630D02*
X-1140987Y565556D01*
X-1141030Y565491D01*
X-1141094Y565449D01*
X-1141170Y565433D01*
G01X-1132146Y576181D02*
X-1132158Y576104D01*
X-1132168Y576018D01*
X-1132176Y575926D01*
G01X-1132146Y576181D02*
X-1131965Y577210D01*
G01X-1131577Y576932D02*
X-1131759Y575903D01*
G01X-1133886Y565630D02*
X-1133901Y565556D01*
X-1133944Y565491D01*
X-1134008Y565449D01*
X-1134083Y565433D01*
G01X-1126800Y565630D02*
X-1126814Y565556D01*
X-1126857Y565491D01*
X-1126921Y565449D01*
X-1126996Y565433D01*
G01X-1127597Y576181D02*
X-1127615Y576124D01*
X-1127648Y576069D01*
X-1127696Y576018D01*
X-1127756Y575975D01*
X-1127827Y575940D01*
X-1127904Y575916D01*
X-1127984Y575903D01*
G01X-1133891Y565566D02*
X-1133935Y565500D01*
X-1133998Y565451D01*
X-1134083Y565433D01*
G01X-1148059Y565518D02*
X-1148091Y565485D01*
X-1148128Y565461D01*
X-1148168Y565446D01*
X-1148209Y565440D01*
G01X-1150737Y570748D02*
G03X-1151130Y570354I1J-394D01*
G01X-1148571D02*
G03X-1148965Y570748I-394J0D01*
G01X-1132561Y571142D02*
G03X-1131799Y570379I762J-1D01*
G01X-1146735Y571142D02*
G03X-1145972Y570379I763J0D01*
G01X-1127311Y570354D02*
G03X-1127705Y570748I-394J0D01*
G01X-1129477D02*
G03X-1129870Y570354I0J-393D01*
G01X-1141485D02*
G03X-1141878Y570748I-394J0D01*
G01X-1143650D02*
G03X-1144044Y570354I0J-394D01*
G01X-1134398D02*
G03X-1134792Y570748I-394J0D01*
G01X-1136563D02*
G03X-1136957Y570354I0J-394D01*
G01X-1132180Y571142D02*
G03X-1131799Y570761I381J0D01*
G01X-1146354Y571142D02*
G03X-1145972Y570761I381J0D01*
G01X-1120226Y529409D02*
G03I-709J0D01*
G01X-1113139Y529016D02*
G03I-709J0D01*
G01X-1106053Y529409D02*
G03I-709J0D01*
G01X-1097592Y533350D02*
X-1102316D01*
G01X-1101875Y550512D02*
X-1102072D01*
G01X-1102810D02*
X-1102957D01*
G01X-1102194Y551291D02*
X-1101752D01*
G01X-1102219Y551391D02*
X-1101727D01*
G01X-1102465Y551693D02*
X-1102318D01*
G01X-1102957D02*
X-1102810D01*
G01X-1102907Y554232D02*
X-1104088D01*
G01X-1109993D02*
X-1111174D01*
G01X-1117080D02*
X-1118261D01*
G01X-1124167D02*
X-1122789Y551846D01*
G01X-1117080Y554232D02*
X-1115702Y551846D01*
G01X-1109993Y554232D02*
X-1108615Y551846D01*
G01X-1102907Y554232D02*
X-1101529Y551846D01*
G01X-1102072Y550512D02*
X-1102465Y551693D01*
G01X-1101973Y550612D02*
X-1102194Y551291D01*
G01X-1102318Y551693D02*
X-1102219Y551391D01*
G01X-1122789Y551846D02*
Y535335D01*
G01X-1119639D02*
Y551846D01*
G01X-1115702D02*
Y535335D01*
G01X-1112552D02*
Y551846D01*
G01X-1108615D02*
Y535335D01*
G01X-1105466D02*
Y551846D01*
G01X-1102957Y550512D02*
Y551693D01*
G01X-1102810D02*
Y550713D01*
G01X-1102662Y550889D02*
Y550688D01*
G01X-1102316Y555236D02*
Y531811D01*
G01X-1101727Y551391D02*
X-1101629Y551693D01*
G01X-1101752Y551291D02*
X-1101973Y550612D01*
G01X-1101481Y551693D02*
X-1101875Y550512D01*
G01X-1119639Y551846D02*
X-1118261Y554232D01*
G01X-1112552Y551846D02*
X-1111174Y554232D01*
G01X-1105466Y551846D02*
X-1104088Y554232D01*
G01X-1102810Y550713D02*
X-1102662Y550889D01*
G01Y550688D02*
X-1102810Y550512D01*
G01X-1120226Y533740D02*
G03I-709J0D01*
G01X-1122789Y535335D02*
G03X-1119639I1575J0D01*
G01X-1120226Y539252D02*
G03I-709J0D01*
G01X-1106053Y533740D02*
G03I-709J0D01*
G01X-1115702Y535335D02*
G03X-1112552I1575J0D01*
G01X-1108615D02*
G03X-1105466I1574J0D01*
G01X-1106053Y539252D02*
G03I-709J0D01*
G01X-1113139Y534528D02*
G03I-709J0D01*
G01Y538858D02*
G03I-709J0D01*
G01X-1102316Y531811D02*
G03X-1101332Y530827I984J0D01*
G01X-1120226Y543583D02*
G03I-709J0D01*
G01X-1113139Y543189D02*
G03I-709J0D01*
G01Y548701D02*
G03I-709J0D01*
G01X-1120226Y547913D02*
G03I-709J0D01*
G01Y553425D02*
G03I-709J0D01*
G01X-1101489Y542306D02*
G03Y540526I1299J-890D01*
G01X-1106053Y543583D02*
G03I-709J0D01*
G01X-1101489Y549629D02*
G03Y547849I1299J-890D01*
G01X-1106053Y547913D02*
G03I-709J0D01*
G01Y553425D02*
G03I-709J0D01*
G01X-1120226Y557756D02*
G03I-709J0D01*
G01X-1106053D02*
G03I-709J0D01*
G01X-1113944Y576938D02*
X-1113861Y576960D01*
X-1113784Y576993D01*
X-1113717Y577037D01*
X-1113663Y577090D01*
X-1113625Y577149D01*
X-1113605Y577210D01*
G01X-1112823Y575308D02*
X-1112747Y575325D01*
X-1112683Y575367D01*
X-1112641Y575431D01*
X-1112626Y575505D01*
G01X-1113993Y576932D02*
X-1113986Y576933D01*
X-1113978D01*
X-1113969Y576935D01*
X-1113961D01*
X-1113953Y576937D01*
X-1113944Y576938D01*
G01X-1112626Y564921D02*
X-1116209D01*
G01X-1102036D02*
X-1098453D01*
G01X-1106052Y566417D02*
X-1108611D01*
G01X-1113138D02*
X-1115697D01*
G01X-1120225D02*
X-1122784D01*
G01X-1120225Y568055D02*
X-1115697D01*
G01X-1113138D02*
X-1108611D01*
G01X-1106052D02*
X-1101524D01*
G01Y568252D02*
X-1106052D01*
G01X-1108611D02*
X-1113138D01*
G01X-1115697D02*
X-1120225D01*
G01X-1101524Y570354D02*
X-1102804D01*
G01X-1115697D02*
X-1116978D01*
G01X-1117626Y570379D02*
X-1115697D01*
G01X-1103453D02*
X-1101524D01*
G01Y570748D02*
X-1102804D01*
G01X-1106445D02*
X-1108217D01*
G01X-1113008D02*
X-1113138D01*
G01X-1115697D02*
X-1116978D01*
G01X-1113532D02*
X-1115304D01*
G01X-1120618D02*
X-1122390D01*
G01X-1117626Y570761D02*
X-1115697D01*
G01X-1103453D02*
X-1101524D01*
G01X-1116934Y570945D02*
X-1115697D01*
G01X-1102761D02*
X-1101524D01*
G01Y571142D02*
X-1104215D01*
G01X-1115697D02*
X-1118388D01*
G01X-1116859Y571679D02*
X-1115697D01*
G01X-1102686D02*
X-1101524D01*
G01X-1117247Y571876D02*
X-1115697D01*
G01X-1103074D02*
X-1101524D01*
G01X-1101890Y574646D02*
X-1098599D01*
G01X-1102036Y575059D02*
X-1098453D01*
G01X-1098650Y575308D02*
X-1101839D01*
G01X-1112823D02*
X-1116012D01*
G01X-1118388Y575624D02*
X-1113008D01*
G01X-1104215D02*
X-1098835D01*
G01X-1098453Y575728D02*
X-1102036D01*
G01X-1112626D02*
X-1116209D01*
G01X-1117585Y575903D02*
X-1113811D01*
G01X-1103412D02*
X-1099638D01*
G01X-1103830Y575926D02*
X-1104218D01*
G01X-1118003D02*
X-1118391D01*
G01X-1113393D02*
X-1113005D01*
G01X-1105540Y576489D02*
X-1109122D01*
G01X-1119713D02*
X-1123296D01*
G01X-1099819Y576932D02*
X-1103231D01*
G01X-1113993D02*
X-1117404D01*
G01X-1117791Y577210D02*
X-1113605D01*
G01X-1103618D02*
X-1099432D01*
G01X-1110102Y565433D02*
X-1110147Y565438D01*
X-1110192Y565455D01*
X-1110232Y565483D01*
X-1110266Y565521D01*
X-1110294Y565566D01*
G01X-1116012Y575308D02*
X-1116059Y575314D01*
X-1116104Y575331D01*
X-1116145Y575360D01*
X-1116178Y575399D01*
X-1116201Y575448D01*
X-1116209Y575505D01*
G01X-1101839Y575308D02*
X-1101885Y575314D01*
X-1101931Y575331D01*
X-1101972Y575360D01*
X-1102005Y575399D01*
X-1102028Y575448D01*
X-1102036Y575505D01*
G01X-1116978Y570354D02*
X-1117285Y570415D01*
X-1117548Y570590D01*
X-1117720Y570849D01*
X-1117777Y571142D01*
G01X-1117585Y575903D02*
X-1117665Y575916D01*
X-1117742Y575940D01*
X-1117811Y575974D01*
X-1117872Y576017D01*
X-1117921Y576068D01*
X-1117955Y576123D01*
X-1117973Y576181D01*
G01X-1103412Y575903D02*
X-1103492Y575916D01*
X-1103568Y575940D01*
X-1103638Y575974D01*
X-1103699Y576017D01*
X-1103748Y576068D01*
X-1103781Y576123D01*
X-1103800Y576181D01*
G01X-1117452Y576938D02*
X-1117445Y576937D01*
X-1117429Y576935D01*
X-1117420Y576934D01*
X-1117404Y576932D01*
G01X-1103278Y576938D02*
X-1103272Y576937D01*
X-1103264Y576936D01*
X-1103255Y576935D01*
X-1103231Y576932D01*
G01X-1102804Y570354D02*
X-1103111Y570415D01*
X-1103375Y570590D01*
X-1103546Y570849D01*
X-1103604Y571142D01*
G01X-1116978Y570748D02*
X-1117186Y570802D01*
X-1117336Y570949D01*
X-1117389Y571142D01*
G01X-1102804Y570748D02*
X-1103013Y570802D01*
X-1103163Y570949D01*
X-1103216Y571142D01*
G01X-1101886Y565440D02*
X-1101871Y565436D01*
X-1101855Y565434D01*
X-1101839Y565433D01*
G01X-1102036Y565518D02*
X-1102004Y565485D01*
X-1101967Y565461D01*
X-1101927Y565446D01*
X-1101886Y565440D01*
G01X-1117322Y571142D02*
X-1117302Y571102D01*
X-1117268Y571063D01*
X-1117219Y571028D01*
X-1117159Y570998D01*
X-1117090Y570973D01*
X-1117014Y570955D01*
X-1116934Y570945D01*
G01X-1117247Y571876D02*
X-1117228Y571836D01*
X-1117193Y571798D01*
X-1117144Y571763D01*
X-1117084Y571732D01*
X-1117015Y571707D01*
X-1116939Y571690D01*
X-1116859Y571679D01*
G01X-1103149Y571142D02*
X-1103129Y571102D01*
X-1103094Y571063D01*
X-1103046Y571028D01*
X-1102986Y570998D01*
X-1102917Y570973D01*
X-1102841Y570955D01*
X-1102761Y570945D01*
G01X-1103074Y571876D02*
X-1103054Y571836D01*
X-1103020Y571798D01*
X-1102971Y571763D01*
X-1102911Y571732D01*
X-1102842Y571707D01*
X-1102766Y571690D01*
X-1102686Y571679D01*
G01X-1117791Y577210D02*
X-1117772Y577149D01*
X-1117734Y577091D01*
X-1117681Y577039D01*
X-1117614Y576994D01*
X-1117536Y576960D01*
X-1117452Y576938D01*
G01X-1103618Y577210D02*
X-1103598Y577149D01*
X-1103561Y577091D01*
X-1103507Y577039D01*
X-1103441Y576994D01*
X-1103363Y576960D01*
X-1103278Y576938D01*
G01X-1113811Y575903D02*
X-1113789Y575820D01*
X-1113775Y575725D01*
X-1113770Y575624D01*
G01X-1123296Y565630D02*
X-1123281Y565556D01*
X-1123238Y565491D01*
X-1123174Y565449D01*
X-1123099Y565433D01*
G01X-1116209Y565630D02*
X-1116194Y565556D01*
X-1116152Y565491D01*
X-1116087Y565449D01*
X-1116012Y565433D01*
G01X-1113393Y575926D02*
X-1113402Y576018D01*
X-1113411Y576104D01*
X-1113424Y576181D01*
G01X-1118391Y575926D02*
X-1118389Y575822D01*
Y575722D01*
X-1118388Y575624D01*
G01X-1113390Y575724D02*
X-1113391Y575826D01*
X-1113393Y575926D01*
G01X-1123296Y576489D02*
Y564842D01*
G01X-1123099Y576489D02*
Y565433D01*
G01X-1122784Y570354D02*
Y566417D01*
G01X-1120535Y600472D02*
Y576489D01*
G01X-1120225Y570354D02*
Y566417D01*
G01X-1119910Y576489D02*
Y565433D01*
G01X-1119724Y576489D02*
X-1119723Y565566D01*
G01X-1119713Y564842D02*
Y576489D01*
G01X-1118391Y599292D02*
Y575926D01*
G01X-1118388Y575624D02*
Y571142D01*
G01X-1118003Y599292D02*
Y575926D01*
G01X-1117791Y577210D02*
Y599292D01*
G01X-1117777Y571142D02*
Y601023D01*
G01X-1117626Y570379D02*
Y575624D01*
G01X-1117404Y576932D02*
Y599292D01*
G01X-1117389Y571142D02*
Y601023D01*
G01X-1117247D02*
Y571876D01*
G01X-1116978Y570748D02*
Y570354D01*
G01X-1116934Y570945D02*
Y570748D01*
G01X-1116859Y571679D02*
Y601023D01*
G01X-1116209Y575728D02*
Y564842D01*
G01X-1116012Y575308D02*
Y565433D01*
G01X-1115697Y571876D02*
Y566417D01*
G01X-1114498Y570748D02*
Y601023D01*
G01X-1114110D02*
Y570748D01*
G01X-1113993Y576932D02*
Y599292D01*
G01X-1113968Y601023D02*
Y570748D01*
G01X-1113770D02*
Y575624D01*
G01X-1113605Y599292D02*
Y577210D01*
G01X-1113580Y601023D02*
Y570748D01*
G01X-1113393Y575926D02*
Y599292D01*
G01X-1113390Y575724D02*
X-1113389Y570721D01*
G01X-1113138Y570354D02*
Y566417D01*
G01X-1113008Y570748D02*
Y575624D01*
G01X-1113005Y575926D02*
Y599292D01*
G01X-1112823Y565433D02*
Y575308D01*
G01X-1112626Y564842D02*
Y575728D01*
G01X-1110298Y565566D02*
Y564842D01*
G01X-1110288Y600472D02*
Y565566D01*
G01X-1110102Y565433D02*
Y600472D01*
G01X-1109122Y576489D02*
Y564842D01*
G01X-1108926Y576489D02*
Y565433D01*
G01X-1108611Y570354D02*
Y566417D01*
G01X-1113133Y570329D02*
X-1113132Y570748D01*
G01X-1113008Y575624D02*
X-1113006Y575926D01*
G01X-1118003D02*
X-1118005Y575829D01*
X-1118007Y575728D01*
Y571142D01*
G01X-1117626Y575624D02*
X-1117621Y575725D01*
X-1117607Y575820D01*
X-1117585Y575903D01*
G01X-1109122Y565630D02*
X-1109107Y565556D01*
X-1109065Y565491D01*
X-1109001Y565449D01*
X-1108926Y565433D01*
G01X-1113811Y575903D02*
X-1113993Y576932D01*
G01X-1113605Y577210D02*
X-1113424Y576181D01*
G01X-1102036Y574836D02*
X-1102028Y574779D01*
X-1102006Y574731D01*
X-1101974Y574692D01*
X-1101934Y574663D01*
X-1101890Y574646D01*
G01X-1117322Y571142D02*
X-1117313Y571055D01*
X-1117284Y570972D01*
X-1117238Y570897D01*
X-1117176Y570834D01*
X-1117103Y570787D01*
X-1117022Y570758D01*
X-1116934Y570748D01*
G01X-1103149Y571142D02*
X-1103139Y571055D01*
X-1103111Y570972D01*
X-1103065Y570897D01*
X-1103003Y570834D01*
X-1102930Y570787D01*
X-1102848Y570758D01*
X-1102761Y570748D01*
G01X-1101878Y564842D02*
X-1101886Y565439D01*
G01X-1104218Y575926D02*
X-1104216Y575822D01*
Y575722D01*
X-1104215Y575624D01*
G01X-1101890Y574646D02*
X-1101886Y565439D01*
G01X-1106361Y600472D02*
Y576489D01*
G01X-1106052Y570354D02*
Y566417D01*
G01X-1105737Y576489D02*
Y565433D01*
G01X-1105551Y576489D02*
X-1105550Y565566D01*
G01X-1105540Y564842D02*
Y576489D01*
G01X-1104218Y599292D02*
Y575926D01*
G01X-1104215Y575624D02*
Y571142D01*
G01X-1103830Y599292D02*
Y575926D01*
G01X-1103618Y577210D02*
Y599292D01*
G01X-1103604Y571142D02*
Y601023D01*
G01X-1103453Y570379D02*
Y575624D01*
G01X-1103231Y576932D02*
Y599292D01*
G01X-1103216Y571142D02*
Y601023D01*
G01X-1103074D02*
Y571876D01*
G01X-1102804Y570748D02*
Y570354D01*
G01X-1102761Y570945D02*
Y570748D01*
G01X-1102686Y571679D02*
Y601023D01*
G01X-1102036Y575728D02*
Y574836D01*
G01Y565518D02*
Y564842D01*
G01X-1101839Y575308D02*
Y565433D01*
G01X-1103830Y575926D02*
X-1103832Y575829D01*
X-1103833Y575728D01*
X-1103834Y571142D01*
G01X-1103453Y575624D02*
X-1103448Y575725D01*
X-1103434Y575820D01*
X-1103412Y575903D01*
G01X-1117247Y571876D02*
X-1117322Y571142D01*
G01X-1116934Y570945D02*
X-1116859Y571679D01*
G01X-1103074Y571876D02*
X-1103149Y571142D01*
G01X-1102761Y570945D02*
X-1102686Y571679D01*
G01X-1117973Y576181D02*
X-1117985Y576104D01*
X-1117995Y576018D01*
X-1118003Y575926D01*
G01X-1103800Y576181D02*
X-1103812Y576104D01*
X-1103822Y576018D01*
X-1103830Y575926D01*
G01X-1117973Y576181D02*
X-1117791Y577210D01*
G01X-1117404Y576932D02*
X-1117585Y575903D01*
G01X-1103800Y576181D02*
X-1103618Y577210D01*
G01X-1103231Y576932D02*
X-1103412Y575903D01*
G01X-1119713Y565630D02*
X-1119728Y565556D01*
X-1119770Y565491D01*
X-1119835Y565449D01*
X-1119910Y565433D01*
G01X-1112626Y565630D02*
X-1112641Y565556D01*
X-1112684Y565491D01*
X-1112748Y565449D01*
X-1112823Y565433D01*
G01X-1105540Y565630D02*
X-1105554Y565556D01*
X-1105597Y565491D01*
X-1105661Y565449D01*
X-1105737Y565433D01*
G01X-1113424Y576181D02*
X-1113441Y576124D01*
X-1113475Y576069D01*
X-1113523Y576018D01*
X-1113583Y575975D01*
X-1113654Y575940D01*
X-1113730Y575916D01*
X-1113811Y575903D01*
G01X-1119718Y565566D02*
X-1119762Y565500D01*
X-1119825Y565451D01*
X-1119910Y565433D01*
G01X-1105545Y565566D02*
X-1105589Y565500D01*
X-1105652Y565451D01*
X-1105737Y565433D01*
G01X-1118388Y571142D02*
G03X-1117626Y570379I762J-1D01*
G01X-1113138Y570354D02*
G03X-1113532Y570748I-394J0D01*
G01X-1115304D02*
G03X-1115697Y570354I1J-394D01*
G01X-1120225D02*
G03X-1120618Y570748I-394J0D01*
G01X-1122390D02*
G03X-1122784Y570354I0J-394D01*
G01X-1118007Y571142D02*
G03X-1117626Y570761I381J0D01*
G01X-1104215Y571142D02*
G03X-1103453Y570379I762J-1D01*
G01X-1106052Y570354D02*
G03X-1106445Y570748I-394J0D01*
G01X-1108217D02*
G03X-1108611Y570354I0J-394D01*
G01X-1103834Y571142D02*
G03X-1103453Y570761I381J0D01*
G01X-1163235Y605740D02*
X-1162968Y605787D01*
X-1162718Y605740D01*
G01X-1158348Y605017D02*
X-1157923Y605023D01*
X-1157737Y605024D01*
X-1157580D01*
X-1157463Y605023D01*
X-1157390Y605020D01*
G01X-1159589Y605591D02*
X-1162467D01*
G01X-1163536D02*
X-1166639D01*
G01X-1157390Y605020D02*
X-1157365Y605017D01*
G01X-1158348Y605984D02*
X-1158048Y605937D01*
X-1157776Y605800D01*
X-1157558Y605587D01*
X-1157417Y605317D01*
X-1157365Y605017D01*
G01X-1167153Y605766D02*
X-1166900Y605700D01*
G01X-1166639Y605591D02*
X-1166903Y605702D01*
G01X-1162467Y605591D02*
X-1162718Y605740D01*
G01X-1166577Y605591D02*
X-1166740Y605984D01*
G01X-1167127D02*
Y605591D01*
G01X-1167086D02*
Y605984D01*
G01X-1167004D02*
Y605591D01*
G01X-1166922D02*
Y605984D01*
G01X-1166840Y605591D02*
Y605984D01*
G01X-1166676Y605591D02*
Y605984D01*
G01X-1161230D02*
Y605591D01*
G01X-1161135Y605787D02*
Y605984D01*
G01X-1160983D02*
Y605591D01*
G01X-1160245Y605984D02*
Y605591D01*
G01X-1160204Y605984D02*
Y605591D01*
G01X-1160145Y605984D02*
Y682009D01*
G01X-1160081Y605984D02*
Y605591D01*
G01X-1160041Y605984D02*
Y605591D01*
G01X-1159999Y605984D02*
Y605591D01*
G01X-1159958Y605984D02*
Y605591D01*
G01X-1159876Y605984D02*
Y605591D01*
G01X-1159835Y605984D02*
Y605591D01*
G01X-1159753Y605984D02*
Y605591D01*
G01X-1159712Y605984D02*
Y605591D01*
G01X-1159630D02*
Y605984D01*
G01X-1159589Y605591D02*
Y605984D01*
G01X-1158348Y605017D02*
Y605984D01*
G01X-1158044Y598346D02*
Y605936D01*
G01X-1157365Y605017D02*
X-1157444Y605389D01*
X-1157659Y605702D01*
X-1157976Y605911D01*
X-1158348Y605984D01*
G01X-1166348Y605591D02*
X-1166282Y605984D01*
G01X-1166305Y605853D02*
X-1166282Y605984D01*
G01X-1161140Y605766D02*
X-1161155Y605700D01*
G01X-1161181Y605591D02*
X-1161155Y605702D01*
X-1161140Y605766D01*
X-1161135Y605787D01*
G01X-1162403Y605591D02*
X-1162266Y605984D01*
G01X-1163701Y605591D02*
X-1163473Y605984D01*
G01X-1162220Y605591D02*
X-1161900Y605984D01*
G01X-1161154Y605591D02*
X-1160796Y605984D01*
G01X-1163561Y605591D02*
X-1163192Y605984D01*
G01X-1161124Y605591D02*
X-1160735Y605984D01*
G01X-1160939D02*
X-1161135Y605787D01*
G01X-1161118Y605591D02*
X-1160724Y605984D01*
G01X-1162454Y597559D02*
X-1161667Y598346D01*
G01X-1163235Y605740D02*
X-1163536Y605591D01*
G01X-1157365Y605017D02*
G03X-1158348Y605984I-984J-17D01*
G01X-1126531Y603199D02*
X-1126455Y603218D01*
G01X-1140705Y603199D02*
X-1140628Y603218D01*
G01X-1126909Y603110D02*
X-1126531Y603199D01*
G01X-1141082Y603110D02*
X-1140705Y603199D01*
G01X-1125953Y603425D02*
X-1126016Y603419D01*
X-1126076Y603400D01*
X-1126130Y603369D01*
X-1126179Y603327D01*
X-1126217Y603276D01*
X-1126245Y603218D01*
G01X-1127523Y603425D02*
X-1127586Y603419D01*
X-1127646Y603400D01*
X-1127700Y603369D01*
X-1127749Y603327D01*
X-1127787Y603276D01*
X-1127815Y603218D01*
G01X-1140126Y603425D02*
X-1140189Y603419D01*
X-1140249Y603400D01*
X-1140304Y603369D01*
X-1140352Y603327D01*
X-1140390Y603276D01*
X-1140418Y603218D01*
G01X-1141696Y603425D02*
X-1141759Y603419D01*
X-1141819Y603400D01*
X-1141874Y603369D01*
X-1141922Y603327D01*
X-1141960Y603276D01*
X-1141988Y603218D01*
G01X-1131033Y601063D02*
X-1131421Y601056D01*
G01X-1145206Y601063D02*
X-1145594Y601056D01*
G01X-1119846Y595551D02*
X-1124373D01*
G01X-1124733D02*
X-1127096D01*
G01X-1138907D02*
X-1141269D01*
G01X-1134019D02*
X-1138546D01*
G01X-1148192D02*
X-1153605D01*
G01X-1146737Y599292D02*
X-1145750D01*
G01X-1142339D02*
X-1141352D01*
G01X-1132564D02*
X-1131577D01*
G01X-1128166D02*
X-1127179D01*
G01X-1132086Y599965D02*
X-1132296D01*
G01X-1146259D02*
X-1146469D01*
G01X-1127447D02*
X-1127657D01*
G01X-1141620D02*
X-1141830D01*
G01X-1120535Y600472D02*
X-1124461D01*
G01X-1134708D02*
X-1138634D01*
G01X-1142844Y601023D02*
X-1141926D01*
G01X-1128671D02*
X-1127753D01*
G01X-1146124D02*
X-1145206D01*
G01X-1131950D02*
X-1131033D01*
G01X-1131522Y601696D02*
X-1131683D01*
G01X-1145696D02*
X-1145856D01*
G01X-1142354D02*
X-1142194D01*
G01X-1128181D02*
X-1128021D01*
G01X-1126801Y602080D02*
X-1131618D01*
G01X-1133888D02*
X-1137103D01*
G01X-1140974D02*
X-1145791D01*
G01X-1148061D02*
X-1151276D01*
G01X-1119846Y602937D02*
X-1124373D01*
G01X-1124733D02*
X-1127096D01*
G01X-1138907D02*
X-1141269D01*
G01X-1134019D02*
X-1138546D01*
G01X-1148192D02*
X-1153605D01*
G01X-1112735Y603110D02*
X-1125870D01*
G01X-1126909D02*
X-1140044D01*
G01X-1153605D02*
X-1141082D01*
G01X-1146418Y603218D02*
X-1146062D01*
G01X-1132245D02*
X-1131889D01*
G01X-1126245D02*
X-1126455D01*
G01X-1133288D02*
X-1133498D01*
G01X-1140418D02*
X-1140628D01*
G01X-1147461D02*
X-1147671D01*
G01X-1141988D02*
X-1141632D01*
G01X-1127815D02*
X-1127459D01*
G01X-1153605Y603425D02*
X-1097306D01*
G01X-1142844Y601063D02*
X-1142456Y601056D01*
G01X-1128670Y601063D02*
X-1128283Y601056D01*
G01X-1142494Y601677D02*
X-1142433Y601676D01*
X-1142385Y601682D01*
X-1142354Y601696D01*
G01X-1128321Y601677D02*
X-1128259Y601676D01*
X-1128212Y601682D01*
X-1128181Y601696D01*
G01X-1147461Y603218D02*
X-1147385Y603199D01*
X-1147007Y603110D01*
G01X-1133288Y603218D02*
X-1133211Y603199D01*
X-1132834Y603110D01*
G01X-1141632Y603218D02*
X-1141269Y603113D01*
G01X-1140418Y603218D02*
X-1140044Y603110D01*
G01X-1127459Y603218D02*
X-1127096Y603113D01*
G01X-1126245Y603218D02*
X-1125870Y603110D01*
G01X-1141830Y599965D02*
X-1142194Y600100D01*
G01X-1141620Y599965D02*
X-1141255Y599831D01*
G01X-1142194Y601696D02*
X-1141830Y601561D01*
G01X-1127657Y599965D02*
X-1128021Y600100D01*
G01X-1127082Y599831D02*
X-1127447Y599965D01*
G01X-1128021Y601696D02*
X-1127657Y601561D01*
G01X-1145696Y601696D02*
X-1145665Y601682D01*
X-1145617Y601676D01*
X-1145556Y601677D01*
G01X-1131522Y601696D02*
X-1131492Y601682D01*
X-1131444Y601676D01*
X-1131383Y601677D01*
G01X-1142450Y603425D02*
X-1142356Y603332D01*
X-1142348Y603063D01*
X-1142428Y602637D01*
X-1142592Y602080D01*
G01X-1128277Y603425D02*
X-1128183Y603332D01*
X-1128175Y603063D01*
X-1128255Y602637D01*
X-1128418Y602080D01*
G01X-1151276D02*
X-1152621Y603425D01*
G01X-1144190Y602080D02*
X-1145535Y603425D01*
G01X-1137103Y602080D02*
X-1138448Y603425D01*
G01X-1130017Y602080D02*
X-1131361Y603425D01*
G01X-1122930Y602080D02*
X-1124275Y603425D01*
G01X-1141988Y603218D02*
X-1142077Y603324D01*
X-1142224Y603394D01*
X-1142450Y603425D01*
G01X-1127815Y603218D02*
X-1127904Y603324D01*
X-1128050Y603394D01*
X-1128277Y603425D01*
G01X-1145644Y601812D02*
X-1145421Y601470D01*
X-1145304Y601266D01*
X-1145206Y601063D01*
G01X-1131471Y601812D02*
X-1131248Y601470D01*
X-1131130Y601266D01*
X-1131033Y601063D01*
G01X-1145791Y602080D02*
X-1145723Y601946D01*
X-1145644Y601812D01*
G01X-1131618Y602080D02*
X-1131550Y601946D01*
X-1131471Y601812D01*
G01X-1147671Y603218D02*
X-1147699Y603275D01*
X-1147737Y603326D01*
X-1147784Y603368D01*
X-1147840Y603399D01*
X-1147900Y603418D01*
X-1147963Y603425D01*
G01X-1147461Y603218D02*
X-1147489Y603275D01*
X-1147527Y603326D01*
X-1147574Y603368D01*
X-1147630Y603399D01*
X-1147689Y603418D01*
X-1147753Y603425D01*
G01X-1146418Y603218D02*
X-1146445Y603275D01*
X-1146483Y603326D01*
X-1146532Y603368D01*
X-1146587Y603399D01*
X-1146646Y603418D01*
X-1146709Y603425D01*
G01X-1146062Y603218D02*
X-1146089Y603275D01*
X-1146127Y603326D01*
X-1146176Y603368D01*
X-1146230Y603399D01*
X-1146290Y603418D01*
X-1146354Y603425D01*
G01X-1133498Y603218D02*
X-1133526Y603275D01*
X-1133563Y603326D01*
X-1133611Y603368D01*
X-1133667Y603399D01*
X-1133726Y603418D01*
X-1133790Y603425D01*
G01X-1133288Y603218D02*
X-1133315Y603275D01*
X-1133354Y603326D01*
X-1133401Y603368D01*
X-1133456Y603399D01*
X-1133516Y603418D01*
X-1133580Y603425D01*
G01X-1132245Y603218D02*
X-1132272Y603275D01*
X-1132310Y603326D01*
X-1132359Y603368D01*
X-1132413Y603399D01*
X-1132473Y603418D01*
X-1132536Y603425D01*
G01X-1131889Y603218D02*
X-1131916Y603275D01*
X-1131954Y603326D01*
X-1132002Y603368D01*
X-1132057Y603399D01*
X-1132117Y603418D01*
X-1132180Y603425D01*
G01X-1146834Y599831D02*
X-1148046Y603110D01*
G01X-1147671Y603218D02*
X-1146469Y599965D01*
G01X-1146259D02*
X-1147461Y603218D01*
G01X-1147007Y603110D02*
X-1145895Y600100D01*
G01X-1146793Y603110D02*
X-1146220Y601561D01*
G01X-1145856Y601696D02*
X-1146418Y603218D01*
G01X-1146138Y599292D02*
X-1146152Y599520D01*
X-1146192Y599746D01*
X-1146259Y599965D01*
G01X-1145750Y599292D02*
X-1145767Y599566D01*
X-1145815Y599837D01*
X-1145895Y600100D01*
G01X-1146350Y599292D02*
X-1146363Y599521D01*
X-1146403Y599746D01*
X-1146469Y599965D01*
G01X-1145736Y601023D02*
X-1145749Y601251D01*
X-1145789Y601477D01*
X-1145856Y601696D01*
G01X-1148192Y603425D02*
Y595551D01*
G01X-1148046Y603425D02*
Y603110D01*
G01X-1132661Y599831D02*
X-1133872Y603110D01*
G01X-1133498Y603218D02*
X-1132296Y599965D01*
G01X-1132086D02*
X-1133288Y603218D01*
G01X-1132834Y603110D02*
X-1131722Y600100D01*
G01X-1132619Y603110D02*
X-1132047Y601561D01*
G01X-1131683Y601696D02*
X-1132245Y603218D01*
G01X-1145458Y602080D02*
X-1145623Y602642D01*
X-1145702Y603068D01*
X-1145693Y603334D01*
X-1145600Y603425D01*
G01X-1131285Y602080D02*
X-1131450Y602642D01*
X-1131529Y603068D01*
X-1131520Y603334D01*
X-1131426Y603425D01*
G01X-1145696Y601696D02*
X-1145641Y601485D01*
X-1145607Y601270D01*
X-1145594Y601056D01*
G01X-1131522Y601696D02*
X-1131468Y601485D01*
X-1131434Y601270D01*
X-1131421Y601056D01*
G01X-1146062Y603218D02*
X-1145993Y602797D01*
X-1145878Y602315D01*
X-1145696Y601696D01*
G01X-1131889Y603218D02*
X-1131820Y602797D01*
X-1131705Y602315D01*
X-1131522Y601696D01*
G01X-1131965Y599292D02*
X-1131978Y599520D01*
X-1132019Y599746D01*
X-1132086Y599965D01*
G01X-1131577Y599292D02*
X-1131593Y599566D01*
X-1131642Y599837D01*
X-1131722Y600100D01*
G01X-1132176Y599292D02*
X-1132190Y599521D01*
X-1132230Y599746D01*
X-1132296Y599965D01*
G01X-1131563Y601023D02*
X-1131576Y601251D01*
X-1131616Y601477D01*
X-1131683Y601696D01*
G01X-1145206Y601063D02*
Y601023D01*
G01X-1131033Y601063D02*
Y601023D01*
G01X-1145594Y601056D02*
Y601023D01*
G01X-1131421Y601056D02*
X-1131420Y601023D01*
G01X-1147007Y603110D02*
Y603425D01*
G01X-1146793Y603110D02*
Y603425D01*
G01X-1141269D02*
Y595551D01*
G01X-1141082Y603110D02*
Y603425D01*
G01X-1140044Y603110D02*
Y603425D01*
G01X-1138907D02*
Y595551D01*
G01X-1138546D02*
Y603425D01*
G01X-1134019D02*
Y595551D01*
G01X-1133872Y603425D02*
Y603110D01*
G01X-1132834D02*
Y603425D01*
G01X-1132619D02*
Y603110D01*
G01X-1127096Y603425D02*
Y595551D01*
G01X-1126909Y603110D02*
Y603425D01*
G01X-1125870Y603110D02*
Y603425D01*
G01X-1124733D02*
Y595551D01*
G01X-1124373D02*
Y603425D01*
G01X-1142844Y601023D02*
Y601063D01*
G01X-1142456Y601056D02*
Y601023D01*
G01X-1128671D02*
X-1128670Y601063D01*
G01X-1128283Y601056D02*
Y601023D01*
G01X-1141740Y599292D02*
X-1141726Y599520D01*
X-1141686Y599746D01*
X-1141620Y599965D01*
G01X-1127567Y599292D02*
X-1127553Y599520D01*
X-1127513Y599746D01*
X-1127447Y599965D01*
G01X-1142456Y601056D02*
X-1142443Y601270D01*
X-1142409Y601485D01*
X-1142354Y601696D01*
G01X-1128283Y601056D02*
X-1128269Y601270D01*
X-1128235Y601485D01*
X-1128181Y601696D01*
G01X-1141988Y603218D02*
X-1142057Y602794D01*
X-1142173Y602311D01*
X-1142354Y601696D01*
G01X-1127815Y603218D02*
X-1127884Y602794D01*
X-1128000Y602311D01*
X-1128181Y601696D01*
G01X-1142194D02*
X-1142261Y601477D01*
X-1142301Y601251D01*
X-1142314Y601023D01*
G01X-1128021Y601696D02*
X-1128087Y601477D01*
X-1128128Y601251D01*
X-1128141Y601023D01*
G01X-1142194Y600100D02*
X-1142274Y599837D01*
X-1142323Y599566D01*
X-1142339Y599292D01*
G01X-1128021Y600100D02*
X-1128101Y599837D01*
X-1128150Y599566D01*
X-1128166Y599292D01*
G01X-1141830Y599965D02*
X-1141897Y599746D01*
X-1141938Y599520D01*
X-1141952Y599292D01*
G01X-1127657Y599965D02*
X-1127724Y599746D01*
X-1127765Y599520D01*
X-1127778Y599292D01*
G01X-1141632Y603218D02*
X-1142194Y601696D01*
G01X-1141830Y601561D02*
X-1141269Y603079D01*
G01X-1142194Y600100D02*
X-1141082Y603110D01*
G01X-1140628Y603218D02*
X-1141830Y599965D01*
G01X-1141620D02*
X-1140418Y603218D01*
G01X-1140044Y603110D02*
X-1141255Y599831D01*
G01X-1127459Y603218D02*
X-1128021Y601696D01*
G01X-1127657Y601561D02*
X-1127096Y603079D01*
G01X-1128021Y600100D02*
X-1126909Y603110D01*
G01X-1126455Y603218D02*
X-1127657Y599965D01*
G01X-1127447D02*
X-1126245Y603218D01*
G01X-1125870Y603110D02*
X-1127082Y599831D01*
G01X-1141632Y603218D02*
X-1141605Y603275D01*
X-1141567Y603326D01*
X-1141519Y603368D01*
X-1141463Y603399D01*
X-1141404Y603418D01*
X-1141341Y603425D01*
G01X-1140628Y603218D02*
X-1140601Y603275D01*
X-1140563Y603326D01*
X-1140515Y603368D01*
X-1140460Y603399D01*
X-1140400Y603418D01*
X-1140337Y603425D01*
G01X-1127459Y603218D02*
X-1127431Y603275D01*
X-1127393Y603326D01*
X-1127346Y603368D01*
X-1127290Y603399D01*
X-1127231Y603418D01*
X-1127167Y603425D01*
G01X-1126455Y603218D02*
X-1126428Y603275D01*
X-1126389Y603326D01*
X-1126342Y603368D01*
X-1126287Y603399D01*
X-1126227Y603418D01*
X-1126163Y603425D01*
G01X-1142844Y601063D02*
X-1142746Y601266D01*
X-1142629Y601470D01*
G01X-1128670Y601063D02*
X-1128573Y601266D01*
X-1128456Y601470D01*
G01X-1142629D02*
X-1142406Y601812D01*
X-1142327Y601946D01*
X-1142259Y602080D01*
G01X-1146062Y603218D02*
X-1145981Y603318D01*
X-1145822Y603395D01*
X-1145600Y603425D01*
G01X-1128456Y601470D02*
X-1128233Y601812D01*
X-1128154Y601946D01*
X-1128086Y602080D01*
G01X-1131889Y603218D02*
X-1131807Y603318D01*
X-1131649Y603395D01*
X-1131426Y603425D01*
G01X-1146716D02*
X-1148061Y602080D01*
G01X-1139629Y603425D02*
X-1140974Y602080D01*
G01X-1132543Y603425D02*
X-1133888Y602080D01*
G01X-1125456Y603425D02*
X-1126801Y602080D01*
G01X-1145856Y601696D02*
X-1146220Y601561D01*
G01X-1146469Y599965D02*
X-1146834Y599831D01*
G01X-1145895Y600100D02*
X-1146259Y599965D01*
G01X-1131683Y601696D02*
X-1132047Y601561D01*
G01X-1132296Y599965D02*
X-1132661Y599831D01*
G01X-1131722Y600100D02*
X-1132086Y599965D01*
G01X-1148046Y603110D02*
X-1147671Y603218D01*
G01X-1146418D02*
X-1146793Y603110D01*
G01X-1133872D02*
X-1133498Y603218D01*
G01X-1132245D02*
X-1132619Y603110D01*
G01X-1146124Y601023D02*
G03X-1146220Y601561I-1553J0D01*
G01X-1146737Y599292D02*
G03X-1146833Y599831I-1554J1D01*
G01X-1127083D02*
G03X-1127179Y599292I1458J-538D01*
G01X-1141256Y599831D02*
G03X-1141352Y599292I1458J-538D01*
G01X-1131950Y601023D02*
G03X-1132047Y601561I-1554J-2D01*
G01X-1132564Y599292D02*
G03X-1132660Y599831I-1554J1D01*
G01X-1141830Y601561D02*
G03X-1141926Y601023I1457J-538D01*
G01X-1127657Y601561D02*
G03X-1127753Y601023I1457J-538D01*
G01X-1112358Y603199D02*
X-1112281Y603218D01*
G01X-1112735Y603110D02*
X-1112358Y603199D01*
G01X-1111780Y603425D02*
X-1111843Y603419D01*
X-1111902Y603400D01*
X-1111957Y603369D01*
X-1112005Y603327D01*
X-1112044Y603276D01*
X-1112072Y603218D01*
G01X-1113350Y603425D02*
X-1113413Y603419D01*
X-1113472Y603400D01*
X-1113527Y603369D01*
X-1113576Y603327D01*
X-1113614Y603276D01*
X-1113641Y603218D01*
G01X-1102687Y601063D02*
X-1103074Y601056D01*
G01X-1116860Y601063D02*
X-1117248Y601056D01*
G01X-1105672Y595551D02*
X-1110200D01*
G01X-1110560D02*
X-1112922D01*
G01X-1118391Y599292D02*
X-1117404D01*
G01X-1113993D02*
X-1113005D01*
G01X-1104218D02*
X-1103231D01*
G01X-1103739Y599965D02*
X-1103950D01*
G01X-1117913D02*
X-1118123D01*
G01X-1113274D02*
X-1113483D01*
G01X-1106361Y600472D02*
X-1110287D01*
G01X-1114498Y601023D02*
X-1113580D01*
G01X-1117777D02*
X-1116859D01*
G01X-1103604D02*
X-1102686D01*
G01X-1103176Y601696D02*
X-1103336D01*
G01X-1117349D02*
X-1117509D01*
G01X-1114008D02*
X-1113848D01*
G01X-1099045Y602080D02*
X-1103271D01*
G01X-1105541D02*
X-1108757D01*
G01X-1112628D02*
X-1117444D01*
G01X-1119715D02*
X-1122930D01*
G01X-1105672Y602937D02*
X-1110200D01*
G01X-1110560D02*
X-1112922D01*
G01X-1098562Y603110D02*
X-1111697D01*
G01X-1103898Y603218D02*
X-1103542D01*
G01X-1118072D02*
X-1117715D01*
G01X-1104942D02*
X-1105152D01*
G01X-1112072D02*
X-1112281D01*
G01X-1119115D02*
X-1119325D01*
G01X-1113641D02*
X-1113285D01*
G01X-1114497Y601063D02*
X-1114109Y601056D01*
G01X-1114148Y601677D02*
X-1114086Y601676D01*
X-1114039Y601682D01*
X-1114008Y601696D01*
G01X-1119115Y603218D02*
X-1119038Y603199D01*
X-1118661Y603110D01*
G01X-1104942Y603218D02*
X-1104865Y603199D01*
X-1104488Y603110D01*
G01X-1113285Y603218D02*
X-1112922Y603113D01*
G01X-1112072Y603218D02*
X-1111697Y603110D01*
G01X-1113483Y599965D02*
X-1113848Y600100D01*
G01X-1112909Y599831D02*
X-1113274Y599965D01*
G01X-1113848Y601696D02*
X-1113483Y601561D01*
G01X-1117349Y601696D02*
X-1117318Y601682D01*
X-1117270Y601676D01*
X-1117209Y601677D01*
G01X-1103176Y601696D02*
X-1103145Y601682D01*
X-1103097Y601676D01*
X-1103036Y601677D01*
G01X-1114104Y603425D02*
X-1114009Y603332D01*
X-1114002Y603063D01*
X-1114082Y602637D01*
X-1114245Y602080D01*
G01X-1115843D02*
X-1117188Y603425D01*
G01X-1110102D02*
X-1108757Y602080D01*
G01X-1103015Y603425D02*
X-1101670Y602080D01*
G01X-1113641Y603218D02*
X-1113730Y603324D01*
X-1113877Y603394D01*
X-1114104Y603425D01*
G01X-1117298Y601812D02*
X-1117074Y601470D01*
X-1116957Y601266D01*
X-1116860Y601063D01*
G01X-1103124Y601812D02*
X-1102901Y601470D01*
X-1102784Y601266D01*
X-1102687Y601063D01*
G01X-1117444Y602080D02*
X-1117376Y601946D01*
X-1117298Y601812D01*
G01X-1103271Y602080D02*
X-1103203Y601946D01*
X-1103124Y601812D01*
G01X-1119325Y603218D02*
X-1119352Y603275D01*
X-1119390Y603326D01*
X-1119438Y603368D01*
X-1119493Y603399D01*
X-1119553Y603418D01*
X-1119617Y603425D01*
G01X-1119115Y603218D02*
X-1119142Y603275D01*
X-1119180Y603326D01*
X-1119228Y603368D01*
X-1119283Y603399D01*
X-1119343Y603418D01*
X-1119406Y603425D01*
G01X-1118072Y603218D02*
X-1118099Y603275D01*
X-1118137Y603326D01*
X-1118185Y603368D01*
X-1118240Y603399D01*
X-1118300Y603418D01*
X-1118363Y603425D01*
G01X-1117715Y603218D02*
X-1117743Y603275D01*
X-1117781Y603326D01*
X-1117829Y603368D01*
X-1117884Y603399D01*
X-1117944Y603418D01*
X-1118007Y603425D01*
G01X-1105152Y603218D02*
X-1105179Y603275D01*
X-1105217Y603326D01*
X-1105265Y603368D01*
X-1105320Y603399D01*
X-1105380Y603418D01*
X-1105443Y603425D01*
G01X-1104942Y603218D02*
X-1104969Y603275D01*
X-1105007Y603326D01*
X-1105054Y603368D01*
X-1105110Y603399D01*
X-1105170Y603418D01*
X-1105233Y603425D01*
G01X-1103898Y603218D02*
X-1103926Y603275D01*
X-1103964Y603326D01*
X-1104012Y603368D01*
X-1104067Y603399D01*
X-1104126Y603418D01*
X-1104190Y603425D01*
G01X-1103542Y603218D02*
X-1103570Y603275D01*
X-1103607Y603326D01*
X-1103656Y603368D01*
X-1103711Y603399D01*
X-1103770Y603418D01*
X-1103834Y603425D01*
G01X-1118487Y599831D02*
X-1119699Y603110D01*
G01X-1119325Y603218D02*
X-1118123Y599965D01*
G01X-1117913D02*
X-1119115Y603218D01*
G01X-1118661Y603110D02*
X-1117548Y600100D01*
G01X-1118446Y603110D02*
X-1117874Y601561D01*
G01X-1117509Y601696D02*
X-1118072Y603218D01*
G01X-1104314Y599831D02*
X-1105526Y603110D01*
G01X-1105152Y603218D02*
X-1103950Y599965D01*
G01X-1103739D02*
X-1104942Y603218D01*
G01X-1104488Y603110D02*
X-1103375Y600100D01*
G01X-1104273Y603110D02*
X-1103700Y601561D01*
G01X-1103336Y601696D02*
X-1103898Y603218D01*
G01X-1117112Y602080D02*
X-1117276Y602642D01*
X-1117356Y603068D01*
X-1117347Y603334D01*
X-1117253Y603425D01*
G01X-1117349Y601696D02*
X-1117295Y601485D01*
X-1117261Y601270D01*
X-1117248Y601056D01*
G01X-1117791Y599292D02*
X-1117805Y599520D01*
X-1117846Y599746D01*
X-1117913Y599965D01*
G01X-1103618Y599292D02*
X-1103632Y599520D01*
X-1103672Y599746D01*
X-1103739Y599965D01*
G01X-1117404Y599292D02*
X-1117420Y599566D01*
X-1117468Y599837D01*
X-1117548Y600100D01*
G01X-1103231Y599292D02*
X-1103247Y599566D01*
X-1103295Y599837D01*
X-1103375Y600100D01*
G01X-1118003Y599292D02*
X-1118017Y599521D01*
X-1118057Y599746D01*
X-1118123Y599965D01*
G01X-1103830Y599292D02*
X-1103843Y599521D01*
X-1103883Y599746D01*
X-1103950Y599965D01*
G01X-1117389Y601023D02*
X-1117403Y601251D01*
X-1117443Y601477D01*
X-1117509Y601696D01*
G01X-1103216Y601023D02*
X-1103230Y601251D01*
X-1103270Y601477D01*
X-1103336Y601696D01*
G01X-1116860Y601063D02*
X-1116859Y601023D01*
G01X-1117248Y601056D02*
X-1117247Y601023D01*
G01X-1119846Y603425D02*
Y595551D01*
G01X-1119699Y603425D02*
Y603110D01*
G01X-1118661D02*
Y603425D01*
G01X-1118446D02*
Y603110D01*
G01X-1112922Y603425D02*
Y595551D01*
G01X-1112735Y603110D02*
Y603425D01*
G01X-1111697Y603110D02*
Y603425D01*
G01X-1110560D02*
Y595551D01*
G01X-1110200D02*
Y603425D01*
G01X-1114498Y601023D02*
X-1114497Y601063D01*
G01X-1114109Y601056D02*
X-1114110Y601023D01*
G01X-1102939Y602080D02*
X-1103103Y602642D01*
X-1103183Y603068D01*
X-1103174Y603334D01*
X-1103080Y603425D01*
G01X-1103176Y601696D02*
X-1103122Y601485D01*
X-1103088Y601270D01*
X-1103074Y601056D01*
G01X-1117715Y603218D02*
X-1117647Y602797D01*
X-1117531Y602315D01*
X-1117349Y601696D01*
G01X-1103542Y603218D02*
X-1103474Y602797D01*
X-1103358Y602315D01*
X-1103176Y601696D01*
G01X-1102687Y601063D02*
X-1102686Y601023D01*
G01X-1103074Y601056D02*
Y601023D01*
G01X-1105672Y603425D02*
Y595551D01*
G01X-1105526Y603425D02*
Y603110D01*
G01X-1104488D02*
Y603425D01*
G01X-1104273D02*
Y603110D01*
G01X-1113393Y599292D02*
X-1113380Y599520D01*
X-1113340Y599746D01*
X-1113274Y599965D01*
G01X-1114109Y601056D02*
X-1114096Y601270D01*
X-1114062Y601485D01*
X-1114008Y601696D01*
G01X-1113641Y603218D02*
X-1113711Y602794D01*
X-1113827Y602311D01*
X-1114008Y601696D01*
G01X-1113848D02*
X-1113914Y601477D01*
X-1113954Y601251D01*
X-1113968Y601023D01*
G01X-1113848Y600100D02*
X-1113928Y599837D01*
X-1113976Y599566D01*
X-1113993Y599292D01*
G01X-1113483Y599965D02*
X-1113551Y599746D01*
X-1113591Y599520D01*
X-1113605Y599292D01*
G01X-1113285Y603218D02*
X-1113848Y601696D01*
G01X-1113483Y601561D02*
X-1112922Y603079D01*
G01X-1113848Y600100D02*
X-1112735Y603110D01*
G01X-1112281Y603218D02*
X-1113483Y599965D01*
G01X-1113274D02*
X-1112072Y603218D01*
G01X-1111697Y603110D02*
X-1112909Y599831D01*
G01X-1113285Y603218D02*
X-1113258Y603275D01*
X-1113220Y603326D01*
X-1113173Y603368D01*
X-1113117Y603399D01*
X-1113057Y603418D01*
X-1112994Y603425D01*
G01X-1112281Y603218D02*
X-1112254Y603275D01*
X-1112216Y603326D01*
X-1112169Y603368D01*
X-1112113Y603399D01*
X-1112054Y603418D01*
X-1111990Y603425D01*
G01X-1114497Y601063D02*
X-1114400Y601266D01*
X-1114283Y601470D01*
G01D02*
X-1114059Y601812D01*
X-1113981Y601946D01*
X-1113913Y602080D01*
G01X-1117715Y603218D02*
X-1117634Y603318D01*
X-1117476Y603395D01*
X-1117253Y603425D01*
G01X-1103542Y603218D02*
X-1103461Y603318D01*
X-1103303Y603395D01*
X-1103080Y603425D01*
G01X-1118369D02*
X-1119715Y602080D01*
G01X-1111283Y603425D02*
X-1112628Y602080D01*
G01X-1104196Y603425D02*
X-1105541Y602080D01*
G01X-1117509Y601696D02*
X-1117874Y601561D01*
G01X-1118123Y599965D02*
X-1118487Y599831D01*
G01X-1117548Y600100D02*
X-1117913Y599965D01*
G01X-1103336Y601696D02*
X-1103700Y601561D01*
G01X-1119699Y603110D02*
X-1119325Y603218D01*
G01X-1118072D02*
X-1118446Y603110D01*
G01X-1105526D02*
X-1105152Y603218D01*
G01X-1103898D02*
X-1104273Y603110D01*
G01X-1103950Y599965D02*
X-1104314Y599831D01*
G01X-1103375Y600100D02*
X-1103739Y599965D01*
G01X-1112909Y599831D02*
G03X-1113006Y599292I1457J-540D01*
G01X-1117777Y601023D02*
G03X-1117874Y601561I-1553J-2D01*
G01X-1103604Y601023D02*
G03X-1103700Y601561I-1554J0D01*
G01X-1104217Y599292D02*
G03X-1104314Y599831I-1554J-1D01*
G01X-1118391Y599292D02*
G03X-1118487Y599831I-1553J1D01*
G01X-1113483Y601561D02*
G03X-1113580Y601023I1456J-540D01*
G01X-1165690Y691614D02*
X-1160145Y682009D01*
G01X-1159699Y1340060D02*
Y1321123D01*
G01X-1093469Y-606825D02*
X-1052518Y-804725D01*
G01D02*
X-1049368D01*
G01D02*
X-708686D01*
G01X-1094283Y-601354D02*
X-1046113Y-771483D01*
G01D02*
X-1042964D01*
G01D02*
X-936140D01*
G01X-1095463Y-601124D02*
Y-690100D01*
G01X-1091526Y-597187D02*
X-765148D01*
G01X-1091133D02*
G03I-4330J0D01*
G01X-1060818Y-475061D02*
G03I-11811J0D01*
G01X-1066723D02*
G03I-5906J0D01*
G01X-1067391Y379094D02*
X-1094950D01*
G01Y404094D02*
Y379094D01*
G01X-1075462Y374173D02*
X-1086880D01*
G01X-1074872Y378701D02*
X-1087470D01*
G01Y386575D02*
Y378701D01*
G01X-1086880D02*
Y374173D01*
G01X-1075462Y378701D02*
Y374173D01*
G01X-1074872Y386575D02*
Y378701D01*
G01X-1086880Y374173D02*
G03X-1075462I5709J0D01*
G01X-1074872Y386575D02*
X-1087470D01*
G01D02*
X-1092391D01*
G01X-1074872D02*
X-1069950D01*
G01X-1092982Y404094D02*
Y379094D01*
G01X-1092391Y386575D02*
Y379094D01*
G01X-1087318Y386575D02*
Y379094D01*
G01X-1075024Y386575D02*
Y379094D01*
G01X-1069950Y386575D02*
Y379094D01*
G01X-1069360D02*
Y404094D01*
G01X-1067391D02*
Y379094D01*
G01X-1003887Y352402D02*
X-1048179D01*
G01X-1003494Y352795D02*
X-1048572D01*
G01X-1040009Y355866D02*
X-1044734D01*
G01Y362283D02*
X-1040009D01*
G01X-1003494Y363189D02*
X-1048572D01*
G01X-1003887Y370512D02*
X-1048179D01*
G01X-1046210Y370668D02*
X-1005856D01*
G01X-1046210Y370752D02*
X-1005856D01*
G01X-1004872Y371496D02*
X-1047194D01*
G01X-1046210Y375905D02*
X-1005856D01*
G01X-1046210Y375947D02*
X-1005856D01*
G01X-1046210Y377126D02*
X-1005856D01*
G01X-1046210Y377338D02*
X-1005856D01*
G01X-1046210Y377385D02*
X-1005856D01*
G01X-1046210Y377402D02*
X-1005856D01*
G01X-1051643Y377126D02*
X-1050796Y375905D01*
G01X-1051320Y377350D02*
X-1050423Y376059D01*
G01X-1050226Y370669D02*
X-1048572Y363189D01*
G01X-1049840Y370705D02*
X-1048179Y363189D01*
G01X-1050796Y375905D02*
X-1050226Y370669D01*
G01X-1050423Y376059D02*
X-1049840Y370705D01*
G01X-1048572Y363189D02*
Y352795D01*
G01X-1048179D02*
Y352402D01*
G01Y363189D02*
Y502008D01*
G01X-1047194Y501024D02*
Y352402D01*
G01X-1046210Y502008D02*
Y352402D01*
G01X-1044734Y355866D02*
Y362283D01*
G01X-1040009D02*
Y355866D01*
G01X-1051320Y377350D02*
X-1051643Y377126D01*
G01X-1042811Y389493D02*
X-1042647Y389535D01*
G01X-1043180Y390959D02*
X-1043344Y390917D01*
G01X-1042606Y389283D02*
X-1042811Y389241D01*
G01X-1043385Y391168D02*
X-1043180Y391210D01*
G01X-1049004Y390163D02*
X-1049209Y390121D01*
G01X-1049179Y383661D02*
X-1048179D01*
G01X-1041417Y389241D02*
X-1041663D01*
G01X-1042811D02*
X-1043180D01*
G01X-1048101D02*
X-1048347D01*
G01X-1046133D02*
X-1046502D01*
G01X-1047527D02*
X-1047773D01*
G01X-1049947D02*
X-1050193D01*
G01X-1043180Y389493D02*
X-1042811D01*
G01X-1042483Y390079D02*
X-1042852D01*
G01X-1049209Y390121D02*
X-1049947D01*
G01X-1042852Y390330D02*
X-1042237D01*
G01X-1049947Y390372D02*
X-1049167D01*
G01X-1042237Y390707D02*
X-1042483D01*
G01X-1042811Y390959D02*
X-1043180D01*
G01X-1049167Y391000D02*
X-1049947D01*
G01X-1050193Y391210D02*
X-1049209D01*
G01X-1048347D02*
X-1048101D01*
G01X-1046379D02*
X-1046133D01*
G01X-1047773D02*
X-1047404D01*
G01X-1043180D02*
X-1042811D01*
G01X-1041663D02*
X-1041417D01*
G01X-1047194Y393287D02*
X-1048179D01*
G01X-1049179Y394764D02*
X-1048179D01*
G01X-1043180Y389241D02*
X-1043385Y389283D01*
G01X-1049209Y391210D02*
X-1049004Y391168D01*
G01X-1042811Y391210D02*
X-1042606Y391168D01*
G01X-1043344Y389535D02*
X-1043180Y389493D01*
G01X-1042647Y390917D02*
X-1042811Y390959D01*
G01X-1049044D02*
X-1049167Y391000D01*
G01X-1043385Y389283D02*
X-1043549Y389367D01*
G01X-1042606Y391168D02*
X-1042442Y391084D01*
G01X-1043467Y389618D02*
X-1043344Y389535D01*
G01X-1042524Y390833D02*
X-1042647Y390917D01*
G01X-1049004Y391168D02*
X-1048839Y391042D01*
G01X-1048963Y390875D02*
X-1049044Y390959D01*
G01X-1043549Y389367D02*
X-1043713Y389535D01*
G01X-1042442Y391084D02*
X-1042278Y390917D01*
G01X-1048839Y391042D02*
X-1048717Y390875D01*
G01X-1043549Y389744D02*
X-1043467Y389618D01*
G01X-1047404Y391210D02*
X-1046379Y389535D01*
G01X-1046502Y389241D02*
X-1047527Y390959D01*
G01X-1043713Y389535D02*
X-1043795Y389702D01*
G01X-1048921Y390749D02*
X-1048963Y390875D01*
G01X-1048717D02*
X-1048675Y390749D01*
G01X-1042483Y390707D02*
X-1042524Y390833D01*
G01X-1043590Y389911D02*
X-1043549Y389744D01*
G01X-1043795Y389702D02*
X-1043836Y389911D01*
G01X-1042278Y390917D02*
X-1042237Y390707D01*
G01X-1050193Y389241D02*
Y391210D01*
G01X-1049947Y390121D02*
Y389241D01*
G01Y391000D02*
Y390372D01*
G01X-1049179Y431811D02*
Y383661D01*
G01X-1048921Y390624D02*
Y390749D01*
G01X-1048675D02*
Y390582D01*
G01X-1048347Y389241D02*
Y391210D01*
G01X-1048101D02*
Y389241D01*
G01X-1047773D02*
Y391210D01*
G01X-1047527Y390959D02*
Y389241D01*
G01X-1046379Y389535D02*
Y391210D01*
G01X-1046133D02*
Y389241D01*
G01X-1043836Y389911D02*
Y390540D01*
G01X-1043590D02*
Y389911D01*
G01X-1042852Y390079D02*
Y390330D01*
G01X-1042483Y389744D02*
Y390079D01*
G01X-1042237Y390330D02*
Y389702D01*
G01X-1041909Y390582D02*
Y390917D01*
G01X-1041663Y389241D02*
Y390875D01*
G01X-1041417Y391210D02*
Y389241D01*
G01X-1043836Y390540D02*
X-1043795Y390749D01*
G01X-1043549Y390707D02*
X-1043590Y390540D01*
G01X-1042237Y389702D02*
X-1042278Y389535D01*
G01X-1048963Y390498D02*
X-1048921Y390624D01*
G01X-1048675Y390582D02*
X-1048717Y390456D01*
G01X-1042524Y389618D02*
X-1042483Y389744D01*
G01X-1043795Y390749D02*
X-1043713Y390917D01*
G01X-1043467Y390833D02*
X-1043549Y390707D01*
G01X-1048717Y390456D02*
X-1048839Y390289D01*
G01X-1041909Y390917D02*
X-1041663Y391210D01*
G01Y390875D02*
X-1041909Y390582D01*
G01X-1049044Y390414D02*
X-1048963Y390498D01*
G01X-1043713Y390917D02*
X-1043549Y391084D01*
G01X-1042278Y389535D02*
X-1042442Y389367D01*
G01X-1048839Y390289D02*
X-1049004Y390163D01*
G01X-1043344Y390917D02*
X-1043467Y390833D01*
G01X-1042647Y389535D02*
X-1042524Y389618D01*
G01X-1043549Y391084D02*
X-1043385Y391168D01*
G01X-1042442Y389367D02*
X-1042606Y389283D01*
G01X-1049167Y390372D02*
X-1049044Y390414D01*
G01X-1044885Y394724D02*
G03I-2688J0D01*
G01X-1094950Y404094D02*
X-1092155D01*
G01X-1094015Y405039D02*
X-1094281D01*
G01Y407165D02*
X-1093218D01*
G01X-1094281Y405039D02*
Y407165D01*
G01X-1092997Y406035D02*
X-1093218Y405989D01*
G01X-1069793Y398110D02*
X-1072549D01*
G01X-1079793D02*
X-1082549D01*
G01X-1089793D02*
X-1092549D01*
G01X-1069793Y400079D02*
X-1072549D01*
G01X-1079793D02*
X-1082549D01*
G01X-1089793D02*
X-1092549D01*
G01X-1072155Y404094D02*
X-1080187D01*
G01X-1082155D02*
X-1090187D01*
G01X-1070187D02*
X-1067391D01*
G01X-1086885Y405039D02*
X-1087150D01*
G01X-1089896D02*
X-1090295D01*
G01X-1091402D02*
X-1091668D01*
G01X-1092022D02*
X-1092288D01*
G01X-1093218Y405989D02*
X-1094015D01*
G01Y406261D02*
X-1093174D01*
G01Y406939D02*
X-1094015D01*
G01X-1092288Y407165D02*
X-1092022D01*
G01X-1090162D02*
X-1089896D01*
G01X-1091668D02*
X-1091269D01*
G01X-1087150D02*
X-1086885D01*
G01X-1093218D02*
X-1092997Y407120D01*
G01X-1093041Y406894D02*
X-1093174Y406939D01*
G01X-1092997Y407120D02*
X-1092820Y406984D01*
G01X-1092952Y406804D02*
X-1093041Y406894D01*
G01X-1092820Y406984D02*
X-1092687Y406804D01*
G01X-1091269Y407165D02*
X-1090162Y405356D01*
G01X-1090295Y405039D02*
X-1091402Y406894D01*
G01X-1092908Y406668D02*
X-1092952Y406804D01*
G01X-1092687D02*
X-1092643Y406668D01*
G01X-1094015Y405989D02*
Y405039D01*
G01Y406939D02*
Y406261D01*
G01X-1092908Y406532D02*
Y406668D01*
G01X-1092643D02*
Y406487D01*
G01X-1092549Y400079D02*
Y398110D01*
G01X-1092288Y405039D02*
Y407165D01*
G01X-1092155Y400079D02*
Y398110D01*
G01Y400079D02*
Y404094D01*
G01X-1092022Y407165D02*
Y405039D01*
G01X-1091668D02*
Y407165D01*
G01X-1091402Y406894D02*
Y405039D01*
G01X-1090187Y400079D02*
Y398110D01*
G01Y400079D02*
Y404094D01*
G01X-1090162Y405356D02*
Y407165D01*
G01X-1089896D02*
Y405039D01*
G01X-1089793Y400079D02*
Y398110D01*
G01X-1087416Y406487D02*
Y406849D01*
G01X-1087150Y405039D02*
Y406804D01*
G01X-1086885Y407165D02*
Y405039D01*
G01X-1082549Y400079D02*
Y398110D01*
G01X-1082155Y404094D02*
Y400079D01*
G01D02*
Y398110D01*
G01X-1080187Y400079D02*
Y398110D01*
G01Y400079D02*
Y404094D01*
G01X-1079793Y400079D02*
Y398110D01*
G01X-1072549Y400079D02*
Y398110D01*
G01X-1072155Y400079D02*
Y398110D01*
G01Y400079D02*
Y404094D01*
G01X-1070187Y400079D02*
Y398110D01*
G01Y400079D02*
Y404094D01*
G01X-1069793Y400079D02*
Y398110D01*
G01X-1092952Y406396D02*
X-1092908Y406532D01*
G01X-1092643Y406487D02*
X-1092687Y406351D01*
G01D02*
X-1092820Y406170D01*
G01X-1087416Y406849D02*
X-1087150Y407165D01*
G01Y406804D02*
X-1087416Y406487D01*
G01X-1093041Y406306D02*
X-1092952Y406396D01*
G01X-1092820Y406170D02*
X-1092997Y406035D01*
G01X-1093174Y406261D02*
X-1093041Y406306D01*
G01X-1047194Y396161D02*
X-1048179D01*
G01X-1008415Y406083D02*
X-1043651D01*
G01X-1048769Y407402D02*
X-1048966D01*
G01X-1049557Y407992D02*
Y414842D01*
G01X-1048966Y415433D02*
Y407402D01*
G01X-1048769D02*
Y415433D01*
G01X-1048572Y408374D02*
Y414461D01*
G01X-1043651Y439468D02*
Y406083D01*
G01X-1042667D02*
X-1041486Y410020D01*
G01X-1047194Y406811D02*
G03X-1048572Y408374I-1575J0D01*
G01X-1048179Y406811D02*
G03X-1048769Y407402I-591J0D01*
G01X-1049557Y407992D02*
G03X-1048966Y407402I590J0D01*
G01X-1049557Y409961D02*
X-1047194D01*
G01X-1010580Y410020D02*
X-1041486D01*
G01X-1049557Y412874D02*
X-1047194D01*
G01X-1048769Y415433D02*
X-1048966D01*
G01X-1010580Y430216D02*
X-1041486D01*
G01X-1049179Y431811D02*
X-1048179D01*
G01X-1008415Y431831D02*
X-1043651D01*
G01X-1041486Y430216D02*
Y410020D01*
G01X-1048572Y414461D02*
G03X-1047194Y416024I-197J1563D01*
G01X-1048769Y415433D02*
G03X-1048179Y416024I-1J591D01*
G01X-1048966Y415433D02*
G03X-1049557Y414842I0J-591D01*
G01X-1004872Y438976D02*
X-1047194D01*
G01X-1006840Y439468D02*
X-1045226D01*
G01X-1047194Y445689D02*
X-1048179D01*
G01X-1047194Y448563D02*
X-1048179D01*
G01X-1038194Y448937D02*
X-1037494D01*
G01Y450866D02*
X-1038194D01*
G01X-1045226Y501083D02*
Y439468D01*
G01X-1038194Y450866D02*
Y448937D01*
G01X-1037494D02*
Y450866D01*
G01X-1099600Y488760D02*
X-1100308D01*
G01X-1098418Y489941D02*
X-1101489D01*
G01X-1096958Y497421D02*
X-1099227D01*
G01D02*
X-1099009Y497247D01*
X-1098807Y497019D01*
X-1098634Y496741D01*
X-1098502Y496420D01*
X-1098418Y496070D01*
X-1098389Y495706D01*
G01X-1101489Y489941D02*
X-1100308Y488760D01*
G01X-1098389Y496278D02*
X-1098442Y496605D01*
X-1098598Y496919D01*
X-1098861Y497199D01*
X-1099227Y497421D01*
G01X-1101519Y496278D02*
Y490335D01*
G01X-1101489Y492697D02*
Y489941D01*
G01X-1098418Y492697D02*
Y489941D01*
G01X-1098389Y496278D02*
Y490335D01*
G01X-1096979Y495177D02*
Y492697D01*
G01Y491122D02*
Y487776D01*
G01X-1096958D02*
Y564842D01*
G01X-1101519Y495706D02*
X-1101490Y496070D01*
X-1101406Y496420D01*
X-1101274Y496741D01*
X-1101101Y497019D01*
X-1100900Y497247D01*
X-1100681Y497421D01*
G01X-1101519Y496278D02*
X-1101425Y496714D01*
X-1101143Y497114D01*
X-1100681Y497421D01*
G01X-1098418Y489941D02*
X-1099600Y488760D01*
G01X-1099227Y497421D02*
G03X-1100681I-727J-1386D01*
G01X-1098966Y496339D02*
G03I-709J0D01*
G01Y500669D02*
G03I-709J0D01*
G01Y506181D02*
G03I-709J0D01*
G01Y510512D02*
G03I-709J0D01*
G01Y514843D02*
G03I-709J0D01*
G01Y520354D02*
G03I-709J0D01*
G01Y524685D02*
G03I-709J0D01*
G01X-1038194Y463898D02*
X-1037494D01*
G01Y465827D02*
X-1038194D01*
G01X-1045226Y465965D02*
X-1046899D01*
G01X-1048769Y466457D02*
X-1048966D01*
G01X-1049557Y467047D02*
Y473898D01*
G01X-1048966Y474488D02*
Y466457D01*
G01X-1048769D02*
Y474488D01*
G01X-1048572Y473516D02*
Y467429D01*
G01X-1046899Y465965D02*
Y501024D01*
G01X-1038194Y465827D02*
Y463898D01*
G01X-1037494D02*
Y465827D01*
G01X-1047194Y465866D02*
G03X-1048572Y467429I-1575J0D01*
G01X-1048179Y465866D02*
G03X-1048769Y466457I-591J0D01*
G01X-1049557Y467047D02*
G03X-1048966Y466457I590J0D01*
G01X-1049557Y469016D02*
X-1047194D01*
G01X-1049557Y471929D02*
X-1047194D01*
G01X-1048769Y474488D02*
X-1048966D01*
G01X-1038194Y478858D02*
X-1037494D01*
G01Y480787D02*
X-1038194D01*
G01X-1049179Y490197D02*
X-1048179D01*
G01X-1038194Y493819D02*
X-1037494D01*
G01Y495748D02*
X-1038194D01*
G01X-1049179Y502008D02*
Y490197D01*
G01X-1038194Y495748D02*
Y493819D01*
G01Y480787D02*
Y478858D01*
G01X-1037494D02*
Y480787D01*
G01Y493819D02*
Y495748D01*
G01X-1048572Y473516D02*
G03X-1047194Y475079I-197J1563D01*
G01X-1048769Y474488D02*
G03X-1048179Y475079I-1J591D01*
G01X-1048966Y474488D02*
G03X-1049557Y473898I0J-591D01*
G01X-1004872Y501024D02*
X-1047194D01*
G01X-1033415Y501083D02*
X-1045226D01*
G01X-1049179Y502008D02*
X-1002887D01*
G01X-1098966Y529016D02*
G03I-709J0D01*
G01X-1098381Y551140D02*
X-1098257Y551165D01*
G01X-1098576Y530827D02*
X-1101332D01*
G01X-1099975Y533760D02*
X-1098533D01*
G01X-1099206Y536928D02*
X-1100702D01*
G01X-1097667Y550512D02*
X-1098257D01*
G01X-1098774D02*
X-1098922D01*
G01X-1099955D02*
X-1100103D01*
G01X-1099119D02*
X-1099340D01*
G01X-1098282Y550637D02*
X-1097815D01*
G01Y551015D02*
X-1098282D01*
G01X-1098257Y551165D02*
X-1097815D01*
G01X-1098922Y551693D02*
X-1098774D01*
G01X-1100103D02*
X-1099881D01*
G01X-1099267D02*
X-1099119D01*
G01X-1101629D02*
X-1101481D01*
G01X-1097815D02*
X-1097667D01*
G01X-1096979Y555236D02*
X-1098418D01*
G01X-1098257Y550512D02*
X-1098381Y550537D01*
G01X-1098356Y550663D02*
X-1098282Y550637D01*
G01X-1098381Y550537D02*
X-1098479Y550612D01*
G01X-1098405Y550713D02*
X-1098356Y550663D01*
G01X-1098479Y550612D02*
X-1098553Y550713D01*
G01X-1099340Y550512D02*
X-1099955Y551517D01*
G01X-1099881Y551693D02*
X-1099267Y550663D01*
G01X-1101489Y538292D02*
X-1100702Y536928D01*
G01X-1098553Y550713D02*
X-1098578Y550788D01*
G01X-1098430D02*
X-1098405Y550713D01*
G01X-1101529Y551846D02*
Y549568D01*
G01Y547909D02*
Y542246D01*
G01Y540587D02*
Y535335D01*
G01X-1101489Y555236D02*
Y549629D01*
G01Y547849D02*
Y542306D01*
G01Y540526D02*
Y538292D01*
G01X-1100103Y550512D02*
Y551693D01*
G01X-1099955Y551517D02*
Y550512D01*
G01X-1099267Y550663D02*
Y551693D01*
G01X-1099119D02*
Y550512D01*
G01X-1098922D02*
Y551693D01*
G01X-1098774D02*
Y550512D01*
G01X-1098578Y550788D02*
Y550889D01*
G01X-1098430Y550864D02*
Y550788D01*
G01X-1098418Y555236D02*
Y549629D01*
G01Y547849D02*
Y542306D01*
G01Y540526D02*
Y538292D01*
G01X-1097815Y551165D02*
Y551693D01*
G01Y550637D02*
Y551015D01*
G01X-1097667Y551693D02*
Y550512D01*
G01X-1097592Y555236D02*
Y531811D01*
G01X-1098578Y550889D02*
X-1098553Y550964D01*
G01X-1098405Y550939D02*
X-1098430Y550864D01*
G01X-1098418Y538292D02*
X-1099206Y536928D01*
G01X-1098553Y550964D02*
X-1098479Y551065D01*
G01X-1098356Y550989D02*
X-1098405Y550939D01*
G01X-1098479Y551065D02*
X-1098381Y551140D01*
G01X-1098282Y551015D02*
X-1098356Y550989D01*
G01X-1096958Y532185D02*
G03X-1098533Y533760I-1575J0D01*
G01X-1098576Y530827D02*
G03X-1097592Y531811I0J984D01*
G01X-1101529Y535335D02*
G03X-1099975Y533760I1575J0D01*
G01X-1098966Y534528D02*
G03I-709J0D01*
G01Y538858D02*
G03I-709J0D01*
G01X-1098418Y540526D02*
G03Y542306I-1300J890D01*
G01X-1098966Y543189D02*
G03I-709J0D01*
G01X-1098418Y547849D02*
G03Y549629I-1300J890D01*
G01X-1098198Y548701D02*
G03I-1477J0D01*
G01X-1098966D02*
G03I-709J0D01*
G01X-1098603Y565439D02*
X-1098618Y565436D01*
X-1098634Y565434D01*
X-1098650Y565433D01*
G01X-1099771Y576938D02*
X-1099688Y576960D01*
X-1099611Y576993D01*
X-1099544Y577037D01*
X-1099490Y577090D01*
X-1099452Y577149D01*
X-1099432Y577210D01*
G01X-1099638Y575903D02*
X-1099558Y575916D01*
X-1099481Y575940D01*
X-1099412Y575974D01*
X-1099351Y576017D01*
X-1099302Y576068D01*
X-1099268Y576123D01*
X-1099250Y576181D01*
G01X-1099819Y576932D02*
X-1099813Y576933D01*
X-1099804D01*
X-1099796Y576935D01*
X-1099788D01*
X-1099780Y576937D01*
X-1099771Y576938D01*
G01X-1098965Y566417D02*
X-1101524D01*
G01X-1099063Y566654D02*
X-1101426D01*
G01X-1098965Y568055D02*
X-1097306D01*
G01X-1099063Y568228D02*
X-1101426D01*
G01X-1098965Y568252D02*
X-1097306D01*
G01X-1101426Y569733D02*
X-1099063D01*
G01Y570591D02*
X-1101426D01*
G01X-1098835Y570748D02*
X-1098965D01*
G01X-1101130D02*
X-1099359D01*
G01X-1098832Y575926D02*
X-1099220D01*
G01X-1096979Y576489D02*
X-1097306D01*
G01X-1099220Y575926D02*
X-1099228Y576018D01*
X-1099238Y576104D01*
X-1099250Y576181D01*
G01X-1099597Y575624D02*
X-1099602Y575725D01*
X-1099616Y575820D01*
X-1099638Y575903D01*
G01D02*
X-1099819Y576932D01*
G01X-1099432Y577210D02*
X-1099250Y576181D01*
G01X-1099217Y575724D02*
X-1099218Y575826D01*
X-1099220Y575926D01*
G01X-1101524Y571876D02*
Y566417D01*
G01X-1101426Y570591D02*
Y566654D01*
G01X-1100324Y570748D02*
Y601023D01*
G01X-1099937D02*
Y570748D01*
G01X-1099819Y576932D02*
Y599292D01*
G01X-1099794Y601023D02*
Y570748D01*
G01X-1099597D02*
Y575624D01*
G01X-1099432Y599292D02*
Y577210D01*
G01X-1099407Y601023D02*
Y570748D01*
G01X-1099220Y599292D02*
Y575926D01*
G01X-1099216Y570721D02*
X-1099217Y575724D01*
G01X-1099063Y570591D02*
Y566654D01*
G01X-1098965Y570354D02*
Y566417D01*
G01X-1098835Y570748D02*
Y575624D01*
G01X-1098832Y575926D02*
Y599292D01*
G01X-1098650Y565433D02*
Y575308D01*
G01X-1098453Y575728D02*
Y574836D01*
G01Y565518D02*
Y564842D01*
G01X-1097306D02*
Y603425D01*
G01X-1096979Y576489D02*
Y564055D01*
G01X-1098599Y574646D02*
X-1098603Y565439D01*
G01X-1098959Y570329D02*
Y570748D01*
G01X-1098835Y575624D02*
X-1098833Y575926D01*
G01X-1098603Y565439D02*
X-1098611Y564842D01*
G01X-1098453Y575505D02*
X-1098468Y575431D01*
X-1098511Y575366D01*
X-1098575Y575324D01*
X-1098650Y575308D01*
G01X-1098453Y565518D02*
X-1098485Y565485D01*
X-1098522Y565461D01*
X-1098562Y565446D01*
X-1098603Y565439D01*
G01X-1098599Y574646D02*
X-1098555Y574663D01*
X-1098516Y574692D01*
X-1098483Y574731D01*
X-1098462Y574779D01*
X-1098453Y574836D01*
G01X-1098965Y570354D02*
G03X-1099359Y570748I-394J0D01*
G01X-1101130D02*
G03X-1101524Y570354I0J-394D01*
G01X-1087864Y1098165D02*
Y563661D01*
G01Y1098165D02*
Y563661D01*
G01X-1091801D02*
G03X-1087864I1968J0D01*
G01X-1091801D02*
G03X-1087864I1968J0D01*
G01X-1098185Y603199D02*
X-1098108Y603218D01*
G01X-1098562Y603110D02*
X-1098185Y603199D01*
G01X-1097607Y603425D02*
X-1097669Y603419D01*
X-1097729Y603400D01*
X-1097784Y603369D01*
X-1097832Y603327D01*
X-1097870Y603276D01*
X-1097898Y603218D01*
G01X-1099177Y603425D02*
X-1099239Y603419D01*
X-1099299Y603400D01*
X-1099354Y603369D01*
X-1099402Y603327D01*
X-1099441Y603276D01*
X-1099468Y603218D01*
G01X-1097306Y595551D02*
X-1098749D01*
G01X-1098832Y599292D02*
X-1099819D01*
G01X-1099100Y599965D02*
X-1099310D01*
G01X-1100324Y601023D02*
X-1099407D01*
G01X-1099835Y601696D02*
X-1099674D01*
G01X-1097306Y602937D02*
X-1098749D01*
G01X-1097306Y603110D02*
X-1097524D01*
G01X-1097898Y603218D02*
X-1098108D01*
G01X-1099468D02*
X-1099112D01*
G01X-1100324Y601063D02*
X-1099936Y601056D01*
G01X-1099974Y601677D02*
X-1099913Y601676D01*
X-1099865Y601682D01*
X-1099835Y601696D01*
G01X-1099112Y603218D02*
X-1098749Y603113D01*
G01X-1097524Y603110D02*
X-1097898Y603218D01*
G01X-1099310Y599965D02*
X-1099675Y600100D01*
G01X-1098736Y599831D02*
X-1099100Y599965D01*
G01X-1099674Y601696D02*
X-1099310Y601561D01*
G01X-1099931Y603425D02*
X-1099836Y603332D01*
X-1099828Y603063D01*
X-1099909Y602637D01*
X-1100072Y602080D01*
G01X-1099468Y603218D02*
X-1099557Y603324D01*
X-1099704Y603394D01*
X-1099931Y603425D01*
G01X-1098749D02*
Y595551D01*
G01X-1098562Y603110D02*
Y603425D01*
G01X-1097524Y603110D02*
Y603425D01*
G01X-1100324Y601023D02*
Y601063D01*
G01X-1099936Y601056D02*
X-1099937Y601023D01*
G01X-1099220Y599292D02*
X-1099207Y599520D01*
X-1099167Y599746D01*
X-1099100Y599965D01*
G01X-1099936Y601056D02*
X-1099923Y601270D01*
X-1099889Y601485D01*
X-1099835Y601696D01*
G01X-1099468Y603218D02*
X-1099538Y602794D01*
X-1099654Y602311D01*
X-1099835Y601696D01*
G01X-1099674D02*
X-1099741Y601477D01*
X-1099781Y601251D01*
X-1099794Y601023D01*
G01X-1099675Y600100D02*
X-1099755Y599837D01*
X-1099803Y599566D01*
X-1099819Y599292D01*
G01X-1099310Y599965D02*
X-1099378Y599746D01*
X-1099418Y599520D01*
X-1099432Y599292D01*
G01X-1099112Y603218D02*
X-1099674Y601696D01*
G01X-1099310Y601561D02*
X-1098749Y603079D01*
G01X-1099675Y600100D02*
X-1098562Y603110D01*
G01X-1098108Y603218D02*
X-1099310Y599965D01*
G01X-1099100D02*
X-1097898Y603218D01*
G01X-1097524Y603110D02*
X-1098736Y599831D01*
G01X-1099112Y603218D02*
X-1099085Y603275D01*
X-1099047Y603326D01*
X-1099000Y603368D01*
X-1098944Y603399D01*
X-1098884Y603418D01*
X-1098821Y603425D01*
G01X-1098108Y603218D02*
X-1098081Y603275D01*
X-1098043Y603326D01*
X-1097996Y603368D01*
X-1097940Y603399D01*
X-1097880Y603418D01*
X-1097817Y603425D01*
G01X-1100324Y601063D02*
X-1100227Y601266D01*
X-1100109Y601470D01*
G01D02*
X-1099886Y601812D01*
X-1099807Y601946D01*
X-1099739Y602080D01*
G01X-1097700Y603425D02*
X-1099045Y602080D01*
G01X-1098736Y599831D02*
G03X-1098833Y599292I1457J-540D01*
G01X-1099310Y601561D02*
G03X-1099407Y601023I1456J-540D01*
G01X-1025068Y807756D02*
G03I-18701J0D01*
G01X-1043769Y811693D02*
Y840228D01*
G01X-1039832Y807756D02*
X-1000391D01*
G01X-1036880D02*
G03I-6889J0D01*
G01X-1009202Y904646D02*
X-1087864D01*
G01X-1069163Y965945D02*
Y977756D01*
G01X-1067687D02*
Y972981D01*
G01Y971474D02*
Y965945D01*
G01D02*
X-1069163D01*
G01X-1060797Y971474D02*
X-1067687D01*
G01Y972981D02*
X-1060797D01*
G01X-1069163Y977756D02*
X-1067687D01*
G01X-1036683Y973735D02*
X-1035944Y973987D01*
G01Y972981D02*
X-1036683Y972730D01*
G01X-1057352Y971976D02*
X-1052677Y974489D01*
G01X-1052185Y973735D02*
X-1055630Y971976D01*
G01X-1050216Y970971D02*
X-1044311Y977756D01*
G01X-1048494Y970971D02*
X-1044311Y975746D01*
G01X-1037175Y973233D02*
X-1036683Y973735D01*
G01Y972730D02*
X-1037175Y972228D01*
G01X-1052185Y970217D02*
X-1052677Y969463D01*
G01X-1060797Y965945D02*
Y971474D01*
G01Y972981D02*
Y977756D01*
G01X-1059320D02*
Y965945D01*
G01X-1050216Y969463D02*
Y970971D01*
G01X-1044311Y975746D02*
Y970971D01*
G01Y965945D02*
Y969463D01*
G01X-1042834Y977756D02*
Y970971D01*
G01Y969463D02*
Y965945D01*
G01X-1040374Y970971D02*
Y969463D01*
G01X-1038405Y965945D02*
Y973987D01*
G01X-1037175D02*
Y973233D01*
G01Y972228D02*
Y965945D01*
G01D02*
X-1038405D01*
G01X-1042834D02*
X-1044311D01*
G01X-1059320D02*
X-1060797D01*
G01X-1040374Y969463D02*
X-1042834D01*
G01X-1044311D02*
X-1050216D01*
G01X-1044311Y970971D02*
X-1048494D01*
G01X-1042834D02*
X-1040374D01*
G01X-1038405Y973987D02*
X-1037175D01*
G01X-1060797Y977756D02*
X-1059320D01*
G01X-1044311D02*
X-1042834D01*
G01X-1052677Y974489D02*
X-1052185Y973735D01*
G01X-1055630Y971976D02*
X-1052185Y970217D01*
G01X-1052677Y969463D02*
X-1057352Y971976D01*
G01X-1087448Y1099926D02*
G03X-1087864Y1098165I3521J-1761D01*
G01X-1087448Y1099926D02*
G03X-1087864Y1098165I3521J-1761D01*
G01Y1102102D02*
Y1173504D01*
G01X-1069267Y1136288D02*
X-1087448Y1099926D01*
G01X-1069267Y1136288D02*
X-1087448Y1099926D01*
G01X-1025068Y1114843D02*
G03I-18701J0D01*
G01X-1036880D02*
G03I-6889J0D01*
G01X-752896Y1138465D02*
X-1065746D01*
G01X-752896D02*
X-1065746D01*
G01D02*
G03X-1069267Y1136288I1J-3937D01*
G01X-1065746Y1138465D02*
G03X-1069267Y1136288I1J-3937D01*
G01X-1043769Y1118779D02*
Y1173504D01*
G01X-1016723Y-601124D02*
Y-690100D01*
G01X-1006881Y-597187D02*
G03I-9842J0D01*
G01X-1012392D02*
G03I-4331J0D01*
G01X-1013252Y-599776D02*
X-886350Y-694431D01*
G01X-1009937Y-604316D02*
X-886684Y-733801D01*
G01X-1007332Y355866D02*
X-1012057D01*
G01X-1031683Y360669D02*
X-1020383D01*
G01X-1012057Y362283D02*
X-1007332D01*
G01X-1020383Y365591D02*
X-1031683D01*
G01D02*
Y360669D01*
G01X-1030268Y365591D02*
Y360669D01*
G01X-1029557Y365591D02*
Y360669D01*
G01X-1029143Y365591D02*
Y360669D01*
G01X-1022924Y365591D02*
Y360669D01*
G01X-1022509Y365591D02*
Y360669D01*
G01X-1021798Y365591D02*
Y360669D01*
G01X-1020383Y365591D02*
Y360669D01*
G01X-1012057Y355866D02*
Y362283D01*
G01X-1007332D02*
Y355866D01*
G01X-1005856Y352402D02*
Y502008D01*
G01X-1004872Y501024D02*
Y352402D01*
G01Y393287D02*
X-1003887D01*
G01X-1000423Y377126D02*
X-1000755Y377338D01*
G01X-1003887Y502008D02*
Y363189D01*
G01Y352795D02*
Y352402D01*
G01X-1003494Y363189D02*
Y352795D01*
G01X-1001643Y375947D02*
X-1002216Y370752D01*
G01X-1001264Y375905D02*
X-1001840Y370669D01*
G01X-1002216Y370752D02*
X-1003887Y363189D01*
G01X-1001840Y370669D02*
X-1003494Y363189D01*
G01X-1000755Y377338D02*
X-1001643Y375947D01*
G01X-1000423Y377126D02*
X-1001264Y375905D01*
G01X-1002887Y383661D02*
X-1003887D01*
G01X-1002887Y394764D02*
X-1003887D01*
G01X-1002887Y431811D02*
Y383661D01*
G01X-972903Y377126D02*
X-972056Y375905D01*
G01X-972580Y377350D02*
X-971683Y376059D01*
G01X-971486Y370669D02*
X-969832Y363189D01*
G01X-971100Y370705D02*
X-969439Y363189D01*
G01X-972056Y375905D02*
X-971486Y370669D01*
G01X-971683Y376059D02*
X-971100Y370705D01*
G01X-972580Y377350D02*
X-972903Y377126D01*
G01X-971207Y389241D02*
X-971453D01*
G01X-970468Y390121D02*
X-971207D01*
G01Y390372D02*
X-970427D01*
G01Y391000D02*
X-971207D01*
G01X-971453Y391210D02*
X-970468D01*
G01X-971453Y389241D02*
Y391210D01*
G01X-971207Y390121D02*
Y389241D01*
G01Y391000D02*
Y390372D01*
G01X-966144Y394724D02*
G03I-2688J0D01*
G01X-1035242Y443425D02*
X-1034541D01*
G01Y445354D02*
X-1035242D01*
G01Y458386D02*
X-1034541D01*
G01Y460315D02*
X-1035242D01*
G01D02*
Y458386D01*
G01Y445354D02*
Y443425D01*
G01X-1034541D02*
Y445354D01*
G01Y458386D02*
Y460315D01*
G01X-1003887Y396161D02*
X-1004872D01*
G01X-1023576Y407913D02*
X-1024576D01*
G01X-1009399Y406083D02*
X-1010580Y410020D01*
G01X-1024576Y407913D02*
Y414803D01*
G01X-1023576D02*
Y407913D01*
G01X-1008415Y439468D02*
Y406083D01*
G01X-1003494Y408374D02*
G03X-1004872Y406811I197J-1563D01*
G01Y409961D02*
X-1002509D01*
G01X-1004872Y412874D02*
X-1002509D01*
G01X-1024576Y414803D02*
X-1023576D01*
G01X-1033710Y424882D02*
X-1018356D01*
G01X-1033710Y439468D02*
Y424882D01*
G01X-1018356D02*
Y439468D01*
G01X-1010580Y430216D02*
Y410020D01*
G01X-1021722Y432559D02*
G03I-4331J0D01*
G01X-1022096D02*
G03I-3937J0D01*
G01X-1004872Y416024D02*
G03X-1003494Y414461I1575J0D01*
G01X-1026383Y443425D02*
X-1025683D01*
G01X-1017525D02*
X-1016824D01*
G01Y445354D02*
X-1017525D01*
G01X-1025683D02*
X-1026383D01*
G01X-1004872Y445689D02*
X-1003887D01*
G01X-1032289Y446181D02*
X-1031588D01*
G01X-1023431D02*
X-1022730D01*
G01X-1014572D02*
X-1013872D01*
G01Y448110D02*
X-1014572D01*
G01X-1022730D02*
X-1023431D01*
G01X-1031588D02*
X-1032289D01*
G01X-1003887Y448563D02*
X-1004872D01*
G01X-1029336Y448937D02*
X-1028635D01*
G01X-1020478D02*
X-1019777D01*
G01Y450866D02*
X-1020478D01*
G01X-1028635D02*
X-1029336D01*
G01X-1026383Y458386D02*
X-1025683D01*
G01X-1017525D02*
X-1016824D01*
G01Y460315D02*
X-1017525D01*
G01X-1025683D02*
X-1026383D01*
G01X-1032289Y461142D02*
X-1031588D01*
G01X-1023431D02*
X-1022730D01*
G01X-1014572D02*
X-1013872D01*
G01X-1032289Y463071D02*
Y461142D01*
G01Y448110D02*
Y446181D01*
G01X-1031588D02*
Y448110D01*
G01Y461142D02*
Y463071D01*
G01X-1029336Y450866D02*
Y448937D01*
G01X-1028635D02*
Y450866D01*
G01X-1026383Y460315D02*
Y458386D01*
G01Y445354D02*
Y443425D01*
G01X-1025683D02*
Y445354D01*
G01Y458386D02*
Y460315D01*
G01X-1023431Y463071D02*
Y461142D01*
G01Y448110D02*
Y446181D01*
G01X-1022730D02*
Y448110D01*
G01Y461142D02*
Y463071D01*
G01X-1020478Y450866D02*
Y448937D01*
G01X-1019777D02*
Y450866D01*
G01X-1017525Y460315D02*
Y458386D01*
G01Y445354D02*
Y443425D01*
G01X-1016824D02*
Y445354D01*
G01Y458386D02*
Y460315D01*
G01X-1014572Y463071D02*
Y461142D01*
G01Y448110D02*
Y446181D01*
G01X-1013872D02*
Y448110D01*
G01Y461142D02*
Y463071D01*
G01X-1006840Y501083D02*
Y439468D01*
G01X-1003100Y407402D02*
X-1003297D01*
G01X-1003494Y408374D02*
Y414461D01*
G01X-1003297Y415433D02*
Y407402D01*
G01X-1003100D02*
Y415433D01*
G01X-1002509Y414842D02*
Y407992D01*
G01X-1003297Y407402D02*
G03X-1003887Y406811I1J-591D01*
G01X-1003100Y407402D02*
G03X-1002509Y407992I0J591D01*
G01X-1003100Y415433D02*
X-1003297D01*
G01X-1002887Y431811D02*
X-1003887D01*
G01Y416024D02*
G03X-1003297Y415433I590J-1D01*
G01X-1002509Y414842D02*
G03X-1003100Y415433I-591J0D01*
G01X-970817Y407992D02*
Y414842D01*
G01Y407992D02*
G03X-970226Y407402I591J1D01*
G01X-970817Y409961D02*
X-968454D01*
G01X-970817Y412874D02*
X-968454D01*
G01X-970226Y415433D02*
G03X-970817Y414842I0J-591D01*
G01X-1035242Y473346D02*
X-1034541D01*
G01Y475276D02*
X-1035242D01*
G01Y488307D02*
X-1034541D01*
G01Y490236D02*
X-1035242D01*
G01D02*
Y488307D01*
G01Y475276D02*
Y473346D01*
G01X-1034541D02*
Y475276D01*
G01Y488307D02*
Y490236D01*
G01X-1013872Y463071D02*
X-1014572D01*
G01X-1022730D02*
X-1023431D01*
G01X-1031588D02*
X-1032289D01*
G01X-1029336Y463898D02*
X-1028635D01*
G01X-1020478D02*
X-1019777D01*
G01Y465827D02*
X-1020478D01*
G01X-1028635D02*
X-1029336D01*
G01X-1005167Y465965D02*
X-1006840D01*
G01X-1029336Y465827D02*
Y463898D01*
G01X-1028635D02*
Y465827D01*
G01X-1020478D02*
Y463898D01*
G01X-1019777D02*
Y465827D01*
G01X-1005167Y465965D02*
Y501024D01*
G01X-1003494Y467429D02*
G03X-1004872Y465866I197J-1563D01*
G01Y469016D02*
X-1002509D01*
G01X-1004872Y471929D02*
X-1002509D01*
G01X-1026383Y473346D02*
X-1025683D01*
G01X-1017525D02*
X-1016824D01*
G01Y475276D02*
X-1017525D01*
G01X-1025683D02*
X-1026383D01*
G01X-1032289Y476102D02*
X-1031588D01*
G01X-1023431D02*
X-1022730D01*
G01X-1014572D02*
X-1013872D01*
G01Y478031D02*
X-1014572D01*
G01X-1022730D02*
X-1023431D01*
G01X-1031588D02*
X-1032289D01*
G01X-1029336Y478858D02*
X-1028635D01*
G01X-1020478D02*
X-1019777D01*
G01Y480787D02*
X-1020478D01*
G01X-1028635D02*
X-1029336D01*
G01X-1026383Y488307D02*
X-1025683D01*
G01X-1017525D02*
X-1016824D01*
G01Y490236D02*
X-1017525D01*
G01X-1025683D02*
X-1026383D01*
G01X-1032289Y491063D02*
X-1031588D01*
G01X-1023431D02*
X-1022730D01*
G01X-1014572D02*
X-1013872D01*
G01Y492992D02*
X-1014572D01*
G01X-1022730D02*
X-1023431D01*
G01X-1031588D02*
X-1032289D01*
G01X-1029336Y493819D02*
X-1028635D01*
G01X-1020478D02*
X-1019777D01*
G01Y495748D02*
X-1020478D01*
G01X-1028635D02*
X-1029336D01*
G01X-1032289Y492992D02*
Y491063D01*
G01Y478031D02*
Y476102D01*
G01X-1031588D02*
Y478031D01*
G01Y491063D02*
Y492992D01*
G01X-1029336Y495748D02*
Y493819D01*
G01Y480787D02*
Y478858D01*
G01X-1028635D02*
Y480787D01*
G01Y493819D02*
Y495748D01*
G01X-1026383Y490236D02*
Y488307D01*
G01Y475276D02*
Y473346D01*
G01X-1025683D02*
Y475276D01*
G01Y488307D02*
Y490236D01*
G01X-1023431Y492992D02*
Y491063D01*
G01Y478031D02*
Y476102D01*
G01X-1022730D02*
Y478031D01*
G01Y491063D02*
Y492992D01*
G01X-1020478Y495748D02*
Y493819D01*
G01Y480787D02*
Y478858D01*
G01X-1019777D02*
Y480787D01*
G01Y493819D02*
Y495748D01*
G01X-1017525Y490236D02*
Y488307D01*
G01Y475276D02*
Y473346D01*
G01X-1016824D02*
Y475276D01*
G01Y488307D02*
Y490236D01*
G01X-1014572Y492992D02*
Y491063D01*
G01Y478031D02*
Y476102D01*
G01X-1013872D02*
Y478031D01*
G01Y491063D02*
Y492992D01*
G01X-1004872Y475079D02*
G03X-1003494Y473516I1575J0D01*
G01X-1006840Y501083D02*
X-1012824D01*
G01X-1015698D02*
X-1030541D01*
G01X-1018966Y508937D02*
X-774872D01*
G01X-1033415Y502008D02*
Y501024D01*
G01X-1030541D02*
Y502008D01*
G01X-1018966Y508937D02*
Y753031D01*
G01X-1015698Y502008D02*
Y501024D01*
G01X-1012824D02*
Y502008D01*
G01X-1003100Y466457D02*
X-1003297D01*
G01X-1003494Y473516D02*
Y467429D01*
G01X-1003297Y474488D02*
Y466457D01*
G01X-1003100D02*
Y474488D01*
G01X-1002509Y473898D02*
Y467047D01*
G01X-1003297Y466457D02*
G03X-1003887Y465866I0J-590D01*
G01X-1003100Y466457D02*
G03X-1002509Y467047I0J591D01*
G01X-1003100Y474488D02*
X-1003297D01*
G01X-1002887Y490197D02*
X-1003887D01*
G01X-1002887Y502008D02*
Y490197D01*
G01X-1003887Y475079D02*
G03X-1003297Y474488I590J-1D01*
G01X-1002509Y473898D02*
G03X-1003100Y474488I-591J-1D01*
G01X-1002509Y548822D02*
X-998788Y518092D01*
G01D02*
X-995639D01*
G01D02*
X-888815D01*
G01X-970817Y467047D02*
Y473898D01*
G01Y467047D02*
G03X-970226Y466457I591J1D01*
G01X-970817Y469016D02*
X-968454D01*
G01X-970817Y471929D02*
X-968454D01*
G01X-970226Y474488D02*
G03X-970817Y473898I0J-591D01*
G01X-1007155Y554685D02*
X-1034560D01*
G01X-991407D02*
G03I-11811J0D01*
G01X-997313D02*
G03I-5905J0D01*
G01X-994268Y546978D02*
X-984694Y538734D01*
G01D02*
X-981544D01*
G01D02*
X-734405D01*
G01X-1003218Y558622D02*
Y606562D01*
G01X-774872Y753031D02*
X-1018966D01*
G01X-985462Y834842D02*
X-989399D01*
G01X-967090Y849585D02*
X-985462D01*
G01Y853606D02*
X-967090D01*
G01X-989399Y834842D02*
Y866339D01*
G01X-985462D02*
Y853606D01*
G01Y849585D02*
Y834842D01*
G01X-1009202Y1138465D02*
Y904646D01*
G01X-989399Y866339D02*
X-985462D01*
G01X-1034468Y965945D02*
Y971976D01*
G01X-1033238Y965945D02*
X-1034468D01*
G01X-1035452Y972981D02*
X-1035944D01*
G01Y973987D02*
X-1034960D01*
G01X-1034468Y971976D02*
X-1034714Y972479D01*
G01X-1034960Y973987D02*
X-1034222Y973735D01*
G01X-1034960Y972730D02*
X-1035452Y972981D01*
G01X-1034714Y972479D02*
X-1034960Y972730D01*
G01X-1032746Y973735D02*
X-1032007Y973987D01*
G01X-1025610Y973735D02*
X-1024872Y973987D01*
G01Y972981D02*
X-1025610Y972730D01*
G01X-1021673Y973735D02*
X-1020935Y973987D01*
G01X-1032254Y972981D02*
X-1032746Y972730D01*
G01X-1021181Y972981D02*
X-1021673Y972730D01*
G01X-1033484Y972981D02*
X-1032746Y973735D01*
G01Y972730D02*
X-1032992Y972479D01*
G01X-1026102Y973233D02*
X-1025610Y973735D01*
G01Y972730D02*
X-1026102Y972228D01*
G01X-1022411Y972981D02*
X-1021673Y973735D01*
G01Y972730D02*
X-1021919Y972479D01*
G01X-1032992D02*
X-1033238Y971976D01*
G01X-1021919Y972479D02*
X-1022165Y971976D01*
G01X-1033238D02*
Y965945D01*
G01X-1030531D02*
Y971976D01*
G01X-1029301D02*
Y965945D01*
G01X-1027332D02*
Y973987D01*
G01X-1026102D02*
Y973233D01*
G01Y972228D02*
Y965945D01*
G01X-1023395D02*
Y971976D01*
G01X-1022165D02*
Y965945D01*
G01X-1019458D02*
Y971976D01*
G01X-1018228D02*
Y965945D01*
G01D02*
X-1019458D01*
G01X-1022165D02*
X-1023395D01*
G01X-1026102D02*
X-1027332D01*
G01X-1029301D02*
X-1030531D01*
G01X-1020443Y972981D02*
X-1021181D01*
G01X-1024380D02*
X-1024872D01*
G01X-1031515D02*
X-1032254D01*
G01X-1032007Y973987D02*
X-1031023D01*
G01X-1027332D02*
X-1026102D01*
G01X-1024872D02*
X-1023887D01*
G01X-1020935D02*
X-1019950D01*
G01X-1030531Y971976D02*
X-1030777Y972479D01*
G01X-1029793Y973233D02*
X-1029301Y971976D01*
G01X-1018720Y973233D02*
X-1018228Y971976D01*
G01X-1031023Y973987D02*
X-1030285Y973735D01*
G01X-1023887Y973987D02*
X-1023149Y973735D01*
G01X-1019950Y973987D02*
X-1019212Y973735D01*
G01X-1031023Y972730D02*
X-1031515Y972981D01*
G01X-1023887Y972730D02*
X-1024380Y972981D01*
G01X-1019950Y972730D02*
X-1020443Y972981D01*
G01X-1034222Y973735D02*
X-1033484Y972981D01*
G01X-1030777Y972479D02*
X-1031023Y972730D01*
G01X-1030285Y973735D02*
X-1029793Y973233D01*
G01X-1023641Y972479D02*
X-1023887Y972730D01*
G01X-1023149Y973735D02*
X-1022411Y972981D01*
G01X-1019704Y972479D02*
X-1019950Y972730D01*
G01X-1019212Y973735D02*
X-1018720Y973233D01*
G01X-1023395Y971976D02*
X-1023641Y972479D01*
G01X-1019458Y971976D02*
X-1019704Y972479D01*
G01X-940029Y-837696D02*
Y-856633D01*
G01X-925147Y352402D02*
X-969439D01*
G01X-924754Y352795D02*
X-969832D01*
G01X-961269Y355866D02*
X-965994D01*
G01X-952943Y360669D02*
X-941643D01*
G01X-965994Y362283D02*
X-961269D01*
G01X-924754Y363189D02*
X-969832D01*
G01X-941643Y365591D02*
X-952943D01*
G01X-925147Y370512D02*
X-969439D01*
G01X-967470Y370668D02*
X-927116D01*
G01X-967470Y370752D02*
X-927116D01*
G01X-926131Y371496D02*
X-968454D01*
G01X-967470Y375905D02*
X-927116D01*
G01X-967470Y375947D02*
X-927116D01*
G01X-967470Y377126D02*
X-927116D01*
G01X-967470Y377338D02*
X-927116D01*
G01X-967470Y377385D02*
X-927116D01*
G01X-967470Y377402D02*
X-927116D01*
G01X-969832Y363189D02*
Y352795D01*
G01X-969439D02*
Y352402D01*
G01Y363189D02*
Y502008D01*
G01X-968454Y501024D02*
Y352402D01*
G01X-967470Y502008D02*
Y352402D01*
G01X-965994Y355866D02*
Y362283D01*
G01X-961269D02*
Y355866D01*
G01X-952943Y365591D02*
Y360669D01*
G01X-951528Y365591D02*
Y360669D01*
G01X-950817Y365591D02*
Y360669D01*
G01X-950402Y365591D02*
Y360669D01*
G01X-964071Y389493D02*
X-963907Y389535D01*
G01X-964440Y390959D02*
X-964604Y390917D01*
G01X-963866Y389283D02*
X-964071Y389241D01*
G01X-964645Y391168D02*
X-964440Y391210D01*
G01X-970263Y390163D02*
X-970468Y390121D01*
G01X-970439Y383661D02*
X-969439D01*
G01X-962676Y389241D02*
X-962922D01*
G01X-964071D02*
X-964440D01*
G01X-967393D02*
X-967762D01*
G01X-968787D02*
X-969033D01*
G01X-969361D02*
X-969607D01*
G01X-964440Y389493D02*
X-964071D01*
G01X-963743Y390079D02*
X-964112D01*
G01Y390330D02*
X-963496D01*
G01Y390707D02*
X-963743D01*
G01X-964071Y390959D02*
X-964440D01*
G01X-969607Y391210D02*
X-969361D01*
G01X-967639D02*
X-967393D01*
G01X-969033D02*
X-968664D01*
G01X-964440D02*
X-964071D01*
G01X-962922D02*
X-962676D01*
G01X-968454Y393287D02*
X-969439D01*
G01X-970439Y394764D02*
X-969439D01*
G01X-964440Y389241D02*
X-964645Y389283D01*
G01X-970468Y391210D02*
X-970263Y391168D01*
G01X-964071Y391210D02*
X-963866Y391168D01*
G01X-964604Y389535D02*
X-964440Y389493D01*
G01X-963907Y390917D02*
X-964071Y390959D01*
G01X-970304D02*
X-970427Y391000D01*
G01X-964645Y389283D02*
X-964809Y389367D01*
G01X-963866Y391168D02*
X-963702Y391084D01*
G01X-964727Y389618D02*
X-964604Y389535D01*
G01X-963783Y390833D02*
X-963907Y390917D01*
G01X-970263Y391168D02*
X-970099Y391042D01*
G01X-970222Y390875D02*
X-970304Y390959D01*
G01X-964809Y389367D02*
X-964973Y389535D01*
G01X-963702Y391084D02*
X-963537Y390917D01*
G01X-970099Y391042D02*
X-969976Y390875D01*
G01X-964809Y389744D02*
X-964727Y389618D01*
G01X-968664Y391210D02*
X-967639Y389535D01*
G01X-967762Y389241D02*
X-968787Y390959D01*
G01X-964973Y389535D02*
X-965055Y389702D01*
G01X-970181Y390749D02*
X-970222Y390875D01*
G01X-969976D02*
X-969935Y390749D01*
G01X-963743Y390707D02*
X-963783Y390833D01*
G01X-964850Y389911D02*
X-964809Y389744D01*
G01X-965055Y389702D02*
X-965096Y389911D01*
G01X-963537Y390917D02*
X-963496Y390707D01*
G01X-970439Y431811D02*
Y383661D01*
G01X-970181Y390624D02*
Y390749D01*
G01X-969935D02*
Y390582D01*
G01X-969607Y389241D02*
Y391210D01*
G01X-969361D02*
Y389241D01*
G01X-969033D02*
Y391210D01*
G01X-968787Y390959D02*
Y389241D01*
G01X-967639Y389535D02*
Y391210D01*
G01X-967393D02*
Y389241D01*
G01X-965096Y389911D02*
Y390540D01*
G01X-964850D02*
Y389911D01*
G01X-964112Y390079D02*
Y390330D01*
G01X-963743Y389744D02*
Y390079D01*
G01X-963496Y390330D02*
Y389702D01*
G01X-963168Y390582D02*
Y390917D01*
G01X-962922Y389241D02*
Y390875D01*
G01X-962676Y391210D02*
Y389241D01*
G01X-965096Y390540D02*
X-965055Y390749D01*
G01X-964809Y390707D02*
X-964850Y390540D01*
G01X-963496Y389702D02*
X-963537Y389535D01*
G01X-970222Y390498D02*
X-970181Y390624D01*
G01X-969935Y390582D02*
X-969976Y390456D01*
G01X-963783Y389618D02*
X-963743Y389744D01*
G01X-965055Y390749D02*
X-964973Y390917D01*
G01X-964727Y390833D02*
X-964809Y390707D01*
G01X-969976Y390456D02*
X-970099Y390289D01*
G01X-963168Y390917D02*
X-962922Y391210D01*
G01Y390875D02*
X-963168Y390582D01*
G01X-970304Y390414D02*
X-970222Y390498D01*
G01X-970427Y390372D02*
X-970304Y390414D01*
G01X-964973Y390917D02*
X-964809Y391084D01*
G01X-963537Y389535D02*
X-963702Y389367D01*
G01X-970099Y390289D02*
X-970263Y390163D01*
G01X-964604Y390917D02*
X-964727Y390833D01*
G01X-963907Y389535D02*
X-963783Y389618D01*
G01X-964809Y391084D02*
X-964645Y391168D01*
G01X-963702Y389367D02*
X-963866Y389283D01*
G01X-928592Y355866D02*
X-933317D01*
G01Y362283D02*
X-928592D01*
G01X-921683Y377126D02*
X-922015Y377338D01*
G01X-944184Y365591D02*
Y360669D01*
G01X-943769Y365591D02*
Y360669D01*
G01X-943058Y365591D02*
Y360669D01*
G01X-941643Y365591D02*
Y360669D01*
G01X-933317Y355866D02*
Y362283D01*
G01X-928592D02*
Y355866D01*
G01X-927116Y352402D02*
Y502008D01*
G01X-926131Y501024D02*
Y352402D01*
G01X-925147Y502008D02*
Y363189D01*
G01Y352795D02*
Y352402D01*
G01X-924754Y363189D02*
Y352795D01*
G01X-922903Y375947D02*
X-923476Y370752D01*
G01X-922524Y375905D02*
X-923100Y370669D01*
G01X-923476Y370752D02*
X-925147Y363189D01*
G01X-923100Y370669D02*
X-924754Y363189D01*
G01X-922015Y377338D02*
X-922903Y375947D01*
G01X-921683Y377126D02*
X-922524Y375905D01*
G01X-924147Y383661D02*
X-925147D01*
G01X-926131Y393287D02*
X-925147D01*
G01X-924147Y394764D02*
X-925147D01*
G01X-924147Y431811D02*
Y383661D01*
G01X-878415Y379094D02*
X-905974D01*
G01Y404094D02*
Y379094D01*
G01X-968454Y396161D02*
X-969439D01*
G01X-929675Y406083D02*
X-964911D01*
G01X-970029Y407402D02*
X-970226D01*
G01X-944836Y407913D02*
X-945836D01*
G01X-970226Y415433D02*
Y407402D01*
G01X-970029D02*
Y415433D01*
G01X-969832Y408374D02*
Y414461D01*
G01X-964911Y439468D02*
Y406083D01*
G01X-945836Y407913D02*
Y414803D01*
G01X-944836D02*
Y407913D01*
G01X-963927Y406083D02*
X-962746Y410020D01*
G01X-968454Y406811D02*
G03X-969832Y408374I-1575J0D01*
G01X-969439Y406811D02*
G03X-970029Y407402I-591J0D01*
G01X-931840Y410020D02*
X-962746D01*
G01X-945836Y414803D02*
X-944836D01*
G01X-970029Y415433D02*
X-970226D01*
G01X-954970Y424882D02*
X-939616D01*
G01X-931840Y430216D02*
X-962746D01*
G01X-970439Y431811D02*
X-969439D01*
G01X-929675Y431831D02*
X-964911D01*
G01X-962746Y430216D02*
Y410020D01*
G01X-954970Y439468D02*
Y424882D01*
G01X-969832Y414461D02*
G03X-968454Y416024I-197J1563D01*
G01X-970029Y415433D02*
G03X-969439Y416024I0J590D01*
G01X-942982Y432559D02*
G03I-4331J0D01*
G01X-943356D02*
G03I-3937J0D01*
G01X-926131Y438976D02*
X-968454D01*
G01X-928100Y439468D02*
X-966486D01*
G01X-956502Y443425D02*
X-955801D01*
G01X-947643D02*
X-946943D01*
G01Y445354D02*
X-947643D01*
G01X-955801D02*
X-956502D01*
G01X-968454Y445689D02*
X-969439D01*
G01X-953549Y446181D02*
X-952848D01*
G01X-944691D02*
X-943990D01*
G01Y448110D02*
X-944691D01*
G01X-952848D02*
X-953549D01*
G01X-968454Y448563D02*
X-969439D01*
G01X-959454Y448937D02*
X-958754D01*
G01X-950596D02*
X-949895D01*
G01Y450866D02*
X-950596D01*
G01X-958754D02*
X-959454D01*
G01X-956502Y458386D02*
X-955801D01*
G01X-947643D02*
X-946943D01*
G01Y460315D02*
X-947643D01*
G01X-955801D02*
X-956502D01*
G01X-953549Y461142D02*
X-952848D01*
G01X-944691D02*
X-943990D01*
G01X-966486Y501083D02*
Y439468D01*
G01X-959454Y450866D02*
Y448937D01*
G01X-958754D02*
Y450866D01*
G01X-956502Y460315D02*
Y458386D01*
G01Y445354D02*
Y443425D01*
G01X-955801D02*
Y445354D01*
G01Y458386D02*
Y460315D01*
G01X-953549Y463071D02*
Y461142D01*
G01Y448110D02*
Y446181D01*
G01X-952848D02*
Y448110D01*
G01Y461142D02*
Y463071D01*
G01X-950596Y450866D02*
Y448937D01*
G01X-949895D02*
Y450866D01*
G01X-947643Y460315D02*
Y458386D01*
G01Y445354D02*
Y443425D01*
G01X-946943D02*
Y445354D01*
G01Y458386D02*
Y460315D01*
G01X-944691Y463071D02*
Y461142D01*
G01Y448110D02*
Y446181D01*
G01X-925147Y396161D02*
X-926131D01*
G01X-924360Y407402D02*
X-924557D01*
G01X-930659Y406083D02*
X-931840Y410020D01*
G01X-929675Y439468D02*
Y406083D01*
G01X-924754Y408374D02*
Y414461D01*
G01X-924557Y415433D02*
Y407402D01*
G01X-924360D02*
Y415433D01*
G01X-923769Y414842D02*
Y407992D01*
G01X-924754Y408374D02*
G03X-926131Y406811I198J-1562D01*
G01X-924557Y407402D02*
G03X-925147Y406811I1J-591D01*
G01X-924360Y407402D02*
G03X-923769Y407992I0J591D01*
G01X-926131Y409961D02*
X-923769D01*
G01X-926131Y412874D02*
X-923769D01*
G01X-924360Y415433D02*
X-924557D01*
G01X-924147Y431811D02*
X-925147D01*
G01X-939616Y424882D02*
Y439468D01*
G01X-931840Y430216D02*
Y410020D01*
G01X-926131Y416024D02*
G03X-924754Y414461I1575J-1D01*
G01X-925147Y416024D02*
G03X-924557Y415433I590J-1D01*
G01X-923769Y414842D02*
G03X-924360Y415433I-591J0D01*
G01X-938785Y443425D02*
X-938084D01*
G01Y445354D02*
X-938785D01*
G01X-926131Y445689D02*
X-925147D01*
G01X-935832Y446181D02*
X-935131D01*
G01Y448110D02*
X-935832D01*
G01X-925147Y448563D02*
X-926131D01*
G01X-941738Y448937D02*
X-941037D01*
G01Y450866D02*
X-941738D01*
G01X-938785Y458386D02*
X-938084D01*
G01Y460315D02*
X-938785D01*
G01X-935832Y461142D02*
X-935131D01*
G01X-943990Y446181D02*
Y448110D01*
G01Y461142D02*
Y463071D01*
G01X-941738Y450866D02*
Y448937D01*
G01X-941037D02*
Y450866D01*
G01X-938785Y460315D02*
Y458386D01*
G01Y445354D02*
Y443425D01*
G01X-938084D02*
Y445354D01*
G01Y458386D02*
Y460315D01*
G01X-935832Y463071D02*
Y461142D01*
G01Y448110D02*
Y446181D01*
G01X-935131D02*
Y448110D01*
G01Y461142D02*
Y463071D01*
G01X-928100Y501083D02*
Y439468D01*
G01X-905974Y404094D02*
X-903179D01*
G01X-905039Y405039D02*
X-905305D01*
G01Y407165D02*
X-904242D01*
G01X-905305Y405039D02*
Y407165D01*
G01X-943990Y463071D02*
X-944691D01*
G01X-952848D02*
X-953549D01*
G01X-959454Y463898D02*
X-958754D01*
G01X-950596D02*
X-949895D01*
G01Y465827D02*
X-950596D01*
G01X-958754D02*
X-959454D01*
G01X-966486Y465965D02*
X-968159D01*
G01X-970029Y466457D02*
X-970226D01*
G01Y474488D02*
Y466457D01*
G01X-970029D02*
Y474488D01*
G01X-969832Y473516D02*
Y467429D01*
G01X-968159Y465965D02*
Y501024D01*
G01X-959454Y465827D02*
Y463898D01*
G01X-958754D02*
Y465827D01*
G01X-950596D02*
Y463898D01*
G01X-949895D02*
Y465827D01*
G01X-968454Y465866D02*
G03X-969832Y467429I-1575J0D01*
G01X-969439Y465866D02*
G03X-970029Y466457I-591J0D01*
G01X-956502Y473346D02*
X-955801D01*
G01X-947643D02*
X-946943D01*
G01X-970029Y474488D02*
X-970226D01*
G01X-946943Y475276D02*
X-947643D01*
G01X-955801D02*
X-956502D01*
G01X-953549Y476102D02*
X-952848D01*
G01X-944691D02*
X-943990D01*
G01Y478031D02*
X-944691D01*
G01X-952848D02*
X-953549D01*
G01X-959454Y478858D02*
X-958754D01*
G01X-950596D02*
X-949895D01*
G01Y480787D02*
X-950596D01*
G01X-958754D02*
X-959454D01*
G01X-956502Y488307D02*
X-955801D01*
G01X-947643D02*
X-946943D01*
G01X-970439Y490197D02*
X-969439D01*
G01X-946943Y490236D02*
X-947643D01*
G01X-955801D02*
X-956502D01*
G01X-953549Y491063D02*
X-952848D01*
G01X-944691D02*
X-943990D01*
G01Y492992D02*
X-944691D01*
G01X-952848D02*
X-953549D01*
G01X-959454Y493819D02*
X-958754D01*
G01X-950596D02*
X-949895D01*
G01Y495748D02*
X-950596D01*
G01X-958754D02*
X-959454D01*
G01X-970439Y502008D02*
Y490197D01*
G01X-959454Y495748D02*
Y493819D01*
G01Y480787D02*
Y478858D01*
G01X-958754D02*
Y480787D01*
G01Y493819D02*
Y495748D01*
G01X-956502Y490236D02*
Y488307D01*
G01Y475276D02*
Y473346D01*
G01X-955801D02*
Y475276D01*
G01Y488307D02*
Y490236D01*
G01X-953549Y492992D02*
Y491063D01*
G01Y478031D02*
Y476102D01*
G01X-952848D02*
Y478031D01*
G01Y491063D02*
Y492992D01*
G01X-950596Y495748D02*
Y493819D01*
G01Y480787D02*
Y478858D01*
G01X-949895D02*
Y480787D01*
G01Y493819D02*
Y495748D01*
G01X-947643Y490236D02*
Y488307D01*
G01Y475276D02*
Y473346D01*
G01X-946943D02*
Y475276D01*
G01Y488307D02*
Y490236D01*
G01X-944691Y492992D02*
Y491063D01*
G01Y478031D02*
Y476102D01*
G01X-969832Y473516D02*
G03X-968454Y475079I-197J1563D01*
G01X-970029Y474488D02*
G03X-969439Y475079I-1J591D01*
G01X-926131Y501024D02*
X-968454D01*
G01X-936958Y501083D02*
X-951801D01*
G01X-954675D02*
X-966486D01*
G01X-970439Y502008D02*
X-924147D01*
G01X-954675D02*
Y501024D01*
G01X-951801D02*
Y502008D01*
G01X-935131Y463071D02*
X-935832D01*
G01X-941738Y463898D02*
X-941037D01*
G01Y465827D02*
X-941738D01*
G01X-926427Y465965D02*
X-928100D01*
G01X-924360Y466457D02*
X-924557D01*
G01X-941738Y465827D02*
Y463898D01*
G01X-941037D02*
Y465827D01*
G01X-926427Y465965D02*
Y501024D01*
G01X-924754Y473516D02*
Y467429D01*
G01X-924557Y474488D02*
Y466457D01*
G01X-924360D02*
Y474488D01*
G01X-923769Y473898D02*
Y467047D01*
G01X-924754Y467429D02*
G03X-926131Y465866I198J-1562D01*
G01X-924557Y466457D02*
G03X-925147Y465866I1J-591D01*
G01X-924360Y466457D02*
G03X-923769Y467047I0J591D01*
G01X-926131Y469016D02*
X-923769D01*
G01X-926131Y471929D02*
X-923769D01*
G01X-938785Y473346D02*
X-938084D01*
G01X-924360Y474488D02*
X-924557D01*
G01X-938084Y475276D02*
X-938785D01*
G01X-935832Y476102D02*
X-935131D01*
G01Y478031D02*
X-935832D01*
G01X-941738Y478858D02*
X-941037D01*
G01Y480787D02*
X-941738D01*
G01X-938785Y488307D02*
X-938084D01*
G01X-924147Y490197D02*
X-925147D01*
G01X-938084Y490236D02*
X-938785D01*
G01X-935832Y491063D02*
X-935131D01*
G01Y492992D02*
X-935832D01*
G01X-941738Y493819D02*
X-941037D01*
G01Y495748D02*
X-941738D01*
G01X-943990Y476102D02*
Y478031D01*
G01Y491063D02*
Y492992D01*
G01X-941738Y495748D02*
Y493819D01*
G01Y480787D02*
Y478858D01*
G01X-941037D02*
Y480787D01*
G01Y493819D02*
Y495748D01*
G01X-938785Y490236D02*
Y488307D01*
G01Y475276D02*
Y473346D01*
G01X-938084D02*
Y475276D01*
G01Y488307D02*
Y490236D01*
G01X-935832Y492992D02*
Y491063D01*
G01Y478031D02*
Y476102D01*
G01X-935131D02*
Y478031D01*
G01Y491063D02*
Y492992D01*
G01X-924147Y502008D02*
Y490197D01*
G01X-926131Y475079D02*
G03X-924754Y473516I1575J-1D01*
G01X-925147Y475079D02*
G03X-924557Y474488I590J-1D01*
G01X-923769Y473898D02*
G03X-924360Y474488I-591J-1D01*
G01X-928100Y501083D02*
X-934084D01*
G01X-936958Y502008D02*
Y501024D01*
G01X-934084D02*
Y502008D01*
G01X-847706Y581772D02*
X-946131D01*
G01Y680197D02*
Y581772D01*
G01X-877037Y608819D02*
X-916801D01*
G01Y653150D02*
Y608819D01*
G01X-877037Y653150D02*
X-916801D01*
G01X-847706Y680197D02*
X-946131D01*
G01X-921328Y691890D02*
X-924281D01*
G01X-938061D02*
X-941013D01*
G01X-924281Y702947D02*
X-938061D01*
G01Y705963D02*
X-924281D01*
G01X-908041Y698926D02*
X-917391Y703952D01*
G01D02*
X-908041Y708978D01*
G01X-941013Y691890D02*
Y715512D01*
G01X-938061D02*
Y705963D01*
G01Y702947D02*
Y691890D01*
G01X-924281D02*
Y702947D01*
G01Y705963D02*
Y715512D01*
G01X-921328D02*
Y691890D01*
G01X-941013Y715512D02*
X-938061D01*
G01X-924281D02*
X-921328D01*
G01X-913946Y703952D02*
X-907057Y700434D01*
G01Y707470D02*
X-913946Y703952D01*
G01X-908041Y708978D02*
X-907057Y707470D01*
G01Y700434D02*
X-908041Y698926D01*
G01X-957903Y850926D02*
X-945436Y857627D01*
G01X-944124Y855616D02*
X-953310Y850926D01*
G01X-963153Y834842D02*
X-967090D01*
G01X-944124Y846235D02*
X-945436Y844224D01*
G01X-953310Y850926D02*
X-944124Y846235D01*
G01X-945436Y844224D02*
X-957903Y850926D01*
G01X-967090Y834842D02*
Y849585D01*
G01Y853606D02*
Y866339D01*
G01X-963153D02*
Y834842D01*
G01X-938874Y848245D02*
X-923126Y866339D01*
G01X-919189Y834842D02*
X-923126D01*
G01X-912628Y844224D02*
X-919189D01*
G01X-923126D02*
X-938874D01*
G01X-923126Y848245D02*
X-934281D01*
G01X-919189D02*
X-912628D01*
G01X-934281D02*
X-923126Y860978D01*
G01X-938874Y844224D02*
Y848245D01*
G01X-923126Y860978D02*
Y848245D01*
G01Y834842D02*
Y844224D01*
G01X-919189Y866339D02*
Y848245D01*
G01Y844224D02*
Y834842D01*
G01X-904098D02*
X-907378D01*
G01X-912628Y848245D02*
Y844224D01*
G01X-907378Y834842D02*
Y856287D01*
G01X-945436Y857627D02*
X-944124Y855616D01*
G01X-967090Y866339D02*
X-963153D01*
G01X-923126D02*
X-919189D01*
G01X-907378Y856287D02*
X-904098D01*
G01X-940029Y1340060D02*
Y1321123D01*
G01X-886684Y-733801D02*
X-883534D01*
G01D02*
X-550647D01*
G01X-886350Y-694431D02*
X-883200D01*
G01D02*
X-776376D01*
G01X-830700Y-596006D02*
G03I-18700J0D01*
G01X-841526D02*
G03I-7874J0D01*
G01X-848219Y-322463D02*
G03I-11811J0D01*
G01X-854125D02*
G03I-5905J0D01*
G01X-830700Y-221990D02*
G03I-18700J0D01*
G01X-842511D02*
G03I-6889J0D01*
G01X-830700Y85096D02*
G03I-18700J0D01*
G01X-842511D02*
G03I-6889J0D01*
G01X-845081Y103292D02*
X-825100Y187459D01*
G01X-886486Y374173D02*
X-897903D01*
G01X-885895Y378701D02*
X-898494D01*
G01Y386575D02*
Y378701D01*
G01X-897903D02*
Y374173D01*
G01X-886486Y378701D02*
Y374173D01*
G01X-885895Y386575D02*
Y378701D01*
G01X-897903Y374173D02*
G03X-886486I5709J0D01*
G01X-885895Y386575D02*
X-898494D01*
G01D02*
X-903415D01*
G01X-885895D02*
X-880974D01*
G01X-904005Y404094D02*
Y379094D01*
G01X-903415Y386575D02*
Y379094D01*
G01X-898341Y386575D02*
Y379094D01*
G01X-886048Y386575D02*
Y379094D01*
G01X-831171D02*
X-858730D01*
G01X-851250Y386575D02*
X-856171D01*
G01X-880974D02*
Y379094D01*
G01X-880383D02*
Y404094D01*
G01X-878415D02*
Y379094D01*
G01X-858730Y404094D02*
Y379094D01*
G01X-856761Y404094D02*
Y379094D01*
G01X-856171Y386575D02*
Y379094D01*
G01X-839242Y374173D02*
X-850659D01*
G01X-838651Y378701D02*
X-851250D01*
G01Y386575D02*
Y378701D01*
G01X-850659D02*
Y374173D01*
G01D02*
G03X-839242I5709J0D01*
G01X-838651Y386575D02*
X-851250D01*
G01X-851097D02*
Y379094D01*
G01X-904020Y406035D02*
X-904242Y405989D01*
G01X-890817Y398110D02*
X-893572D01*
G01X-900817D02*
X-903572D01*
G01X-890817Y400079D02*
X-893572D01*
G01X-900817D02*
X-903572D01*
G01X-883179Y404094D02*
X-891210D01*
G01X-893179D02*
X-901210D01*
G01X-897908Y405039D02*
X-898174D01*
G01X-903046D02*
X-903312D01*
G01X-900920D02*
X-901318D01*
G01X-902426D02*
X-902692D01*
G01X-904242Y405989D02*
X-905039D01*
G01Y406261D02*
X-904198D01*
G01Y406939D02*
X-905039D01*
G01X-903312Y407165D02*
X-903046D01*
G01X-901186D02*
X-900920D01*
G01X-902692D02*
X-902293D01*
G01X-898174D02*
X-897908D01*
G01X-904242D02*
X-904020Y407120D01*
G01X-904065Y406894D02*
X-904198Y406939D01*
G01X-904020Y407120D02*
X-903843Y406984D01*
G01X-903976Y406804D02*
X-904065Y406894D01*
G01X-903843Y406984D02*
X-903710Y406804D01*
G01X-902293Y407165D02*
X-901186Y405356D01*
G01X-901318Y405039D02*
X-902426Y406894D01*
G01X-903932Y406668D02*
X-903976Y406804D01*
G01X-903710D02*
X-903666Y406668D01*
G01X-905039Y405989D02*
Y405039D01*
G01Y406939D02*
Y406261D01*
G01X-903932Y406532D02*
Y406668D01*
G01X-903666D02*
Y406487D01*
G01X-903572Y400079D02*
Y398110D01*
G01X-903312Y405039D02*
Y407165D01*
G01X-903179Y400079D02*
Y398110D01*
G01Y400079D02*
Y404094D01*
G01X-903046Y407165D02*
Y405039D01*
G01X-902692D02*
Y407165D01*
G01X-902426Y406894D02*
Y405039D01*
G01X-901210Y400079D02*
Y398110D01*
G01Y400079D02*
Y404094D01*
G01X-901186Y405356D02*
Y407165D01*
G01X-900920D02*
Y405039D01*
G01X-900817Y400079D02*
Y398110D01*
G01X-898440Y406487D02*
Y406849D01*
G01X-898174Y405039D02*
Y406804D01*
G01X-897908Y407165D02*
Y405039D01*
G01X-893572Y400079D02*
Y398110D01*
G01X-893179Y404094D02*
Y400079D01*
G01D02*
Y398110D01*
G01X-891210Y400079D02*
Y398110D01*
G01Y400079D02*
Y404094D01*
G01X-890817Y400079D02*
Y398110D01*
G01X-903976Y406396D02*
X-903932Y406532D01*
G01X-903666Y406487D02*
X-903710Y406351D01*
G01D02*
X-903843Y406170D01*
G01X-898440Y406849D02*
X-898174Y407165D01*
G01Y406804D02*
X-898440Y406487D01*
G01X-904065Y406306D02*
X-903976Y406396D01*
G01X-903843Y406170D02*
X-904020Y406035D01*
G01X-904198Y406261D02*
X-904065Y406306D01*
G01X-856776Y406035D02*
X-856998Y405989D01*
G01X-853572Y398110D02*
X-856328D01*
G01X-880817D02*
X-883572D01*
G01X-853572Y400079D02*
X-856328D01*
G01X-880817D02*
X-883572D01*
G01X-881210Y404094D02*
X-878415D01*
G01X-858730D02*
X-855935D01*
G01X-855802Y405039D02*
X-856068D01*
G01X-855182D02*
X-855448D01*
G01X-857795D02*
X-858061D01*
G01X-856998Y405989D02*
X-857795D01*
G01Y406261D02*
X-856954D01*
G01Y406939D02*
X-857795D01*
G01X-858061Y407165D02*
X-856998D01*
G01X-856068D02*
X-855802D01*
G01X-855448D02*
X-855049D01*
G01X-856998D02*
X-856776Y407120D01*
G01X-856820Y406894D02*
X-856954Y406939D01*
G01X-856776Y407120D02*
X-856599Y406984D01*
G01X-856732Y406804D02*
X-856820Y406894D01*
G01X-856599Y406984D02*
X-856466Y406804D01*
G01X-855049Y407165D02*
X-853942Y405356D01*
G01X-854074Y405039D02*
X-855182Y406894D01*
G01X-856688Y406668D02*
X-856732Y406804D01*
G01X-856466D02*
X-856422Y406668D01*
G01X-883572Y400079D02*
Y398110D01*
G01X-883179Y400079D02*
Y398110D01*
G01Y400079D02*
Y404094D01*
G01X-881210Y400079D02*
Y398110D01*
G01Y400079D02*
Y404094D01*
G01X-880817Y400079D02*
Y398110D01*
G01X-858061Y405039D02*
Y407165D01*
G01X-857795Y405989D02*
Y405039D01*
G01Y406939D02*
Y406261D01*
G01X-856688Y406532D02*
Y406668D01*
G01X-856422D02*
Y406487D01*
G01X-856328Y400079D02*
Y398110D01*
G01X-856068Y405039D02*
Y407165D01*
G01X-855935Y400079D02*
Y398110D01*
G01Y400079D02*
Y404094D01*
G01X-855802Y407165D02*
Y405039D01*
G01X-855448D02*
Y407165D01*
G01X-855182Y406894D02*
Y405039D01*
G01X-856732Y406396D02*
X-856688Y406532D01*
G01X-856422Y406487D02*
X-856466Y406351D01*
G01X-856954Y406261D02*
X-856820Y406306D01*
G01X-856466Y406351D02*
X-856599Y406170D01*
G01X-856820Y406306D02*
X-856732Y406396D01*
G01X-856599Y406170D02*
X-856776Y406035D01*
G01X-843572Y398110D02*
X-846328D01*
G01X-843572Y400079D02*
X-846328D01*
G01X-835935Y404094D02*
X-843966D01*
G01X-845935D02*
X-853966D01*
G01X-850664Y405039D02*
X-850930D01*
G01X-853676D02*
X-854074D01*
G01X-853942Y407165D02*
X-853676D01*
G01X-850930D02*
X-850664D01*
G01X-853966Y400079D02*
Y398110D01*
G01Y400079D02*
Y404094D01*
G01X-853942Y405356D02*
Y407165D01*
G01X-853676D02*
Y405039D01*
G01X-853572Y400079D02*
Y398110D01*
G01X-851196Y406487D02*
Y406849D01*
G01X-850930Y405039D02*
Y406804D01*
G01X-850664Y407165D02*
Y405039D01*
G01X-846328Y400079D02*
Y398110D01*
G01X-845935Y404094D02*
Y400079D01*
G01D02*
Y398110D01*
G01X-843966Y400079D02*
Y398110D01*
G01Y400079D02*
Y404094D01*
G01X-843572Y400079D02*
Y398110D01*
G01X-851196Y406849D02*
X-850930Y407165D01*
G01Y406804D02*
X-851196Y406487D01*
G01X-850107Y582486D02*
X-848447D01*
G01D02*
Y584146D01*
G01X-847706Y680197D02*
Y581772D01*
G01X-848447Y584146D02*
X-850107Y582486D01*
G01X-877037Y653150D02*
Y608819D01*
G01X-894261Y694403D02*
X-891801Y694905D01*
G01X-894261Y691890D02*
X-891309Y692392D01*
G01X-897214D02*
X-894261Y691890D01*
G01X-896722Y694905D02*
X-894261Y694403D01*
G01X-899675Y693900D02*
X-897214Y692392D01*
G01X-898198Y695911D02*
X-896722Y694905D01*
G01X-891309Y692392D02*
X-888848Y693900D01*
G01X-901151Y695408D02*
X-899675Y693900D01*
G01X-891801Y694905D02*
X-890324Y695911D01*
G01X-900167Y698926D02*
X-898198Y695911D01*
G01X-888356Y708476D02*
X-890324Y711491D01*
G01X-902135Y697418D02*
X-901151Y695408D01*
G01X-902135Y709983D02*
X-902628Y708476D01*
G01X-898198Y711491D02*
X-900167Y708476D01*
G01X-890324Y695911D02*
X-888356Y698926D01*
G01X-888848Y693900D02*
X-887372Y695408D01*
G01X-902628Y698926D02*
X-902135Y697418D01*
G01X-885895Y708476D02*
X-886387Y709983D01*
G01X-903120Y701439D02*
X-902628Y698926D01*
G01X-900659Y701942D02*
X-900167Y698926D01*
G01X-903120Y705963D02*
Y701439D01*
G01X-900659Y705460D02*
Y701942D01*
G01X-887864D02*
Y705460D01*
G01X-885403Y701439D02*
Y705963D01*
G01X-900167Y708476D02*
X-900659Y705460D01*
G01X-888356Y698926D02*
X-887864Y701942D01*
G01X-902628Y708476D02*
X-903120Y705963D01*
G01X-885895Y698926D02*
X-885403Y701439D01*
G01X-886387Y697418D02*
X-885895Y698926D01*
G01X-887372Y695408D02*
X-886387Y697418D01*
G01X-885403Y705963D02*
X-885895Y708476D01*
G01X-887864Y705460D02*
X-888356Y708476D01*
G01X-894261Y712999D02*
X-896722Y712496D01*
G01X-894261Y715512D02*
X-897214Y715009D01*
G01X-891309D02*
X-894261Y715512D01*
G01X-891801Y712496D02*
X-894261Y712999D01*
G01X-888848Y713502D02*
X-891309Y715009D01*
G01X-890324Y711491D02*
X-891801Y712496D01*
G01X-896722D02*
X-898198Y711491D01*
G01X-897214Y715009D02*
X-899675Y713502D01*
G01X-887372Y711994D02*
X-888848Y713502D01*
G01X-899675D02*
X-901151Y711994D01*
G01D02*
X-902135Y709983D01*
G01X-886387D02*
X-887372Y711994D01*
G01X-862765Y694905D02*
X-864734Y694403D01*
G01X-869655Y703952D02*
X-867687Y704455D01*
G01X-864734Y691890D02*
X-862273Y692392D01*
G01X-867687Y706968D02*
X-870147Y706465D01*
G01X-879005Y691890D02*
X-881466D01*
G01X-867687D02*
X-864734D01*
G01Y694403D02*
X-867687D01*
G01X-881466D02*
X-879005D01*
G01X-872116Y697921D02*
X-875068D01*
G01Y702444D02*
X-871624D01*
G01X-867687Y704455D02*
X-864734D01*
G01Y706968D02*
X-867687D01*
G01X-870147Y692392D02*
X-867687Y691890D01*
G01X-862273Y706465D02*
X-864734Y706968D01*
G01X-867687Y694403D02*
X-869655Y694905D01*
G01X-864734Y704455D02*
X-862765Y703952D01*
G01X-872608Y693900D02*
X-870147Y692392D01*
G01X-859813Y704957D02*
X-862273Y706465D01*
G01X-869655Y694905D02*
X-871131Y695911D01*
G01X-862765Y703952D02*
X-861289Y702947D01*
G01X-870147Y706465D02*
X-872608Y704957D01*
G01X-871624Y702444D02*
X-869655Y703952D01*
G01X-861289Y695911D02*
X-862765Y694905D01*
G01X-862273Y692392D02*
X-859813Y693900D01*
G01X-874084Y695911D02*
X-872608Y693900D01*
G01X-858336Y702947D02*
X-859813Y704957D01*
G01X-861289Y702947D02*
X-860305Y701439D01*
G01X-875068Y697921D02*
X-874084Y695911D01*
G01X-871131D02*
X-872116Y697921D01*
G01X-881466Y691890D02*
Y694403D01*
G01X-879005D02*
Y691890D01*
G01X-875068Y715512D02*
Y702444D01*
G01X-872608Y704957D02*
Y712999D01*
G01X-860305Y697418D02*
X-861289Y695911D01*
G01X-859813Y693900D02*
X-858336Y695911D01*
G01X-857352Y700434D02*
X-858336Y702947D01*
G01X-860305Y701439D02*
X-859813Y699931D01*
G01D02*
Y698926D01*
G01X-857352Y698424D02*
Y700434D01*
G01X-859813Y698926D02*
X-860305Y697418D01*
G01X-858336Y695911D02*
X-857352Y698424D01*
G01X-872608Y712999D02*
X-858336D01*
G01Y715512D02*
X-875068D01*
G01X-858336Y712999D02*
Y715512D01*
G01X-843080Y691890D02*
X-845541D01*
G01X-850954D02*
X-853415D01*
G01X-839635Y705963D02*
X-841112D01*
G01X-847509D02*
X-848494D01*
G01X-853415Y707973D02*
X-850954D01*
G01X-848494D02*
X-846525D01*
G01X-840620D02*
X-838651D01*
G01X-846525D02*
X-845049Y707470D01*
G01X-846525Y705460D02*
X-847509Y705963D01*
G01X-838651Y705460D02*
X-839635Y705963D01*
G01X-849970Y707470D02*
X-848494Y707973D01*
G01Y705963D02*
X-849970Y705460D01*
G01X-842096Y707470D02*
X-840620Y707973D01*
G01X-841112Y705963D02*
X-842096Y705460D01*
G01X-846033Y704957D02*
X-846525Y705460D01*
G01X-845049Y707470D02*
X-843572Y705963D01*
G01X-850954Y706465D02*
X-849970Y707470D01*
G01Y705460D02*
X-850954Y704455D01*
G01X-843572Y705963D02*
X-842096Y707470D01*
G01Y705460D02*
X-842588Y704957D01*
G01X-845541Y703952D02*
X-846033Y704957D01*
G01X-853415Y691890D02*
Y707973D01*
G01X-850954D02*
Y706465D01*
G01Y704455D02*
Y691890D01*
G01X-845541D02*
Y703952D01*
G01X-843080D02*
Y691890D01*
G01X-842588Y704957D02*
X-843080Y703952D01*
G01X-900817Y853606D02*
X-902785Y852936D01*
G01X-890974Y853606D02*
X-892287Y852936D01*
G01X-883100Y834842D02*
X-886381D01*
G01X-893599D02*
X-896880D01*
G01X-889005Y853606D02*
X-890974D01*
G01X-899504D02*
X-900817D01*
G01X-904098Y854276D02*
X-902785Y855616D01*
G01Y852936D02*
X-904098Y851596D01*
G01X-894255Y853606D02*
X-892287Y855616D01*
G01Y852936D02*
X-892943Y852266D01*
G01D02*
X-893599Y850926D01*
G01X-898192Y852936D02*
X-899504Y853606D01*
G01X-887693Y852936D02*
X-889005Y853606D01*
G01X-897536Y852266D02*
X-898192Y852936D01*
G01X-904098Y856287D02*
Y854276D01*
G01Y851596D02*
Y834842D01*
G01X-896880D02*
Y850926D01*
G01X-893599D02*
Y834842D01*
G01X-886381D02*
Y850926D01*
G01X-896224Y855616D02*
X-894255Y853606D01*
G01X-887037Y852266D02*
X-887693Y852936D01*
G01X-885725Y855616D02*
X-884413Y854276D01*
G01X-896880Y850926D02*
X-897536Y852266D01*
G01X-886381Y850926D02*
X-887037Y852266D01*
G01X-884413Y854276D02*
X-883100Y850926D01*
G01X-871289Y853606D02*
X-873257Y852936D01*
G01X-861446Y853606D02*
X-862759Y852936D01*
G01X-853572Y834842D02*
X-856854D01*
G01X-864071D02*
X-867352D01*
G01X-874570D02*
X-877851D01*
G01X-859478Y853606D02*
X-861446D01*
G01X-869977D02*
X-871289D01*
G01X-874570Y854276D02*
X-873257Y855616D01*
G01Y852936D02*
X-874570Y851596D01*
G01X-864728Y853606D02*
X-862759Y855616D01*
G01Y852936D02*
X-863415Y852266D01*
G01X-868665Y852936D02*
X-869977Y853606D01*
G01X-858166Y852936D02*
X-859478Y853606D01*
G01X-863415Y852266D02*
X-864071Y850926D01*
G01X-883100D02*
Y834842D01*
G01X-877851D02*
Y856287D01*
G01X-874570D02*
Y854276D01*
G01Y851596D02*
Y834842D01*
G01X-867352D02*
Y850926D01*
G01X-868008Y852266D02*
X-868665Y852936D01*
G01X-866696Y855616D02*
X-864728Y853606D01*
G01X-857509Y852266D02*
X-858166Y852936D01*
G01X-856197Y855616D02*
X-854885Y854276D01*
G01X-864071Y850926D02*
Y834842D01*
G01X-856854D02*
Y850926D01*
G01X-867352D02*
X-868008Y852266D01*
G01X-856854Y850926D02*
X-857509Y852266D01*
G01X-854885Y854276D02*
X-853572Y850926D01*
G01D02*
Y834842D01*
G01X-902785Y855616D02*
X-900817Y856287D01*
G01X-892287Y855616D02*
X-890318Y856287D01*
G01X-900817D02*
X-898192D01*
G01X-890318D02*
X-887693D01*
G01X-898192D02*
X-896224Y855616D01*
G01X-887693Y856287D02*
X-885725Y855616D01*
G01X-897824Y904646D02*
X-771840D01*
G01X-897824Y1138465D02*
Y904646D01*
G01X-873257Y855616D02*
X-871289Y856287D01*
G01X-862759Y855616D02*
X-860791Y856287D01*
G01X-877851D02*
X-874570D01*
G01X-871289D02*
X-868665D01*
G01X-860791D02*
X-858166D01*
G01X-868665D02*
X-866696Y855616D01*
G01X-858166Y856287D02*
X-856197Y855616D01*
G01X-855974Y962375D02*
X-848182Y966563D01*
G01X-859255Y952323D02*
X-861716D01*
G01X-873198D02*
X-875659D01*
G01X-861716Y961537D02*
X-873198D01*
G01Y964050D02*
X-861716D01*
G01X-875659Y972008D02*
X-873198D01*
G01X-861716D02*
X-859255D01*
G01X-875659Y952323D02*
Y972008D01*
G01X-873198D02*
Y964050D01*
G01Y961537D02*
Y952323D01*
G01X-861716D02*
Y961537D01*
G01Y964050D02*
Y972008D01*
G01X-859255D02*
Y952323D01*
G01X-848182Y958187D02*
X-855974Y962375D01*
G01X-847362Y965307D02*
X-853104Y962375D01*
G01X-844081Y960700D02*
X-834239Y972008D01*
G01X-841210Y960700D02*
X-834239Y968657D01*
G01X-847362Y959443D02*
X-848182Y958187D01*
G01X-834239D02*
X-844081D01*
G01X-834239Y960700D02*
X-841210D01*
G01X-844081Y958187D02*
Y960700D01*
G01X-853104Y962375D02*
X-847362Y959443D01*
G01X-848182Y966563D02*
X-847362Y965307D01*
G01X-819873Y-655061D02*
X-804125D01*
G01X-819873Y107877D02*
Y-655061D01*
G01X-804125D02*
G03X-800188Y-651124I0J3937D01*
G01X-804125Y-655061D02*
G03X-800188Y-651124I0J3937D01*
G01D02*
Y68419D01*
G01Y-651124D02*
Y68419D01*
G01X-838178Y-581046D02*
X-788384Y-514666D01*
G01D02*
X-785234D01*
G01D02*
X-499119D01*
G01X-810767Y-131837D02*
X-810256Y-131586D01*
G01Y-135589D02*
X-804125D01*
G01Y-134338D02*
X-810256D01*
G01Y-131586D02*
X-804125D01*
G01Y-130335D02*
X-810256D01*
G01X-811278Y-131336D02*
X-812045Y-132087D01*
G01X-811023D02*
X-810767Y-131837D01*
G01X-811534Y-135089D02*
X-810256Y-135589D01*
G01Y-134338D02*
X-810767Y-134088D01*
G01X-811278Y-132587D02*
X-811023Y-132087D01*
G01X-810256Y-130335D02*
X-810767Y-130085D01*
G01X-812045Y-128084D02*
X-812300Y-128835D01*
G01X-811278D02*
X-811023Y-128084D01*
G01X-812045Y-132087D02*
X-812300Y-132837D01*
G01X-812045Y-134588D02*
X-811534Y-135089D01*
G01X-810767Y-134088D02*
X-811023Y-133838D01*
G01X-812045Y-130586D02*
X-811278Y-131336D01*
G01X-810767Y-130085D02*
X-811023Y-129835D01*
G01X-812300Y-128835D02*
Y-129835D01*
G01Y-132837D02*
Y-133838D01*
G01X-811278Y-133337D02*
Y-132587D01*
G01Y-129335D02*
Y-128835D01*
G01X-804125Y-135589D02*
Y-134338D01*
G01Y-131586D02*
Y-130335D01*
G01X-811023Y-133838D02*
X-811278Y-133337D01*
G01X-811023Y-129835D02*
X-811278Y-129335D01*
G01X-812300Y-133838D02*
X-812045Y-134588D01*
G01X-812300Y-129835D02*
X-812045Y-130586D01*
G01X-806935Y-112574D02*
X-807702Y-112824D01*
G01X-805913Y-112074D02*
X-806935Y-112574D01*
G01X-810767Y-120579D02*
X-810256Y-120329D01*
G01X-807702Y-112824D02*
X-808979Y-113074D01*
G01X-806168Y-110572D02*
X-807702Y-111573D01*
G01D02*
X-809235Y-111823D01*
G01X-812300Y-127584D02*
X-811534D01*
G01X-810512D02*
X-804125D01*
G01Y-126333D02*
X-812300D01*
G01X-810256Y-124331D02*
X-804125D01*
G01Y-123081D02*
X-810256D01*
G01Y-120329D02*
X-804125D01*
G01Y-119078D02*
X-810256D01*
G01X-812300Y-116326D02*
X-811534D01*
G01X-810512D02*
X-804125D01*
G01Y-115076D02*
X-812300D01*
G01X-808979Y-113074D02*
X-811278D01*
G01X-809235Y-111823D02*
X-811023D01*
G01X-811534Y-116326D02*
X-812045Y-116827D01*
G01X-811023D02*
X-810512Y-116326D01*
G01X-805147Y-111323D02*
X-805913Y-112074D01*
G01X-811278Y-120079D02*
X-812045Y-120829D01*
G01X-811023D02*
X-810767Y-120579D01*
G01X-811534Y-127584D02*
X-812045Y-128084D01*
G01X-811023D02*
X-810512Y-127584D01*
G01X-811023Y-111823D02*
X-812556Y-111573D01*
G01X-811278Y-113074D02*
X-812556Y-112824D01*
G01X-804380Y-110072D02*
X-805147Y-111323D01*
G01X-812556Y-112824D02*
X-813322Y-112574D01*
G01X-811534Y-123831D02*
X-810256Y-124331D01*
G01X-811278Y-121330D02*
X-811023Y-120829D01*
G01X-810256Y-123081D02*
X-810767Y-122831D01*
G01X-810256Y-119078D02*
X-810767Y-118828D01*
G01X-813322Y-112574D02*
X-814344Y-112074D01*
G01X-812045Y-116827D02*
X-812300Y-117577D01*
G01X-811278D02*
X-811023Y-116827D01*
G01X-812045Y-120829D02*
X-812300Y-121580D01*
G01X-812556Y-111573D02*
X-814089Y-110572D01*
G01X-812045Y-123331D02*
X-811534Y-123831D01*
G01X-810767Y-122831D02*
X-811023Y-122580D01*
G01X-812045Y-119328D02*
X-811278Y-120079D01*
G01X-810767Y-118828D02*
X-811023Y-118578D01*
G01X-814344Y-112074D02*
X-815111Y-111323D01*
G01X-812300Y-115076D02*
Y-116326D01*
G01Y-117577D02*
Y-118578D01*
G01Y-121580D02*
Y-122580D01*
G01Y-126333D02*
Y-127584D01*
G01X-811278Y-122080D02*
Y-121330D01*
G01Y-118078D02*
Y-117577D01*
G01X-804125Y-127584D02*
Y-126333D01*
G01Y-124331D02*
Y-123081D01*
G01Y-120329D02*
Y-119078D01*
G01Y-116326D02*
Y-115076D01*
G01X-815111Y-111323D02*
X-815877Y-110072D01*
G01X-811023Y-122580D02*
X-811278Y-122080D01*
G01X-811023Y-118578D02*
X-811278Y-118078D01*
G01X-812300Y-122580D02*
X-812045Y-123331D01*
G01X-812300Y-118578D02*
X-812045Y-119328D01*
G01X-813322Y-104569D02*
X-812556Y-104319D01*
G01X-814344Y-105069D02*
X-813322Y-104569D01*
G01X-812556Y-104319D02*
X-811278Y-104068D01*
G01X-814089Y-106570D02*
X-812556Y-105569D01*
G01D02*
X-811023Y-105319D01*
G01X-815111Y-105819D02*
X-814344Y-105069D01*
G01X-811023Y-105319D02*
X-809235D01*
G01X-811278Y-104068D02*
X-808979D01*
G01X-812300Y-102067D02*
X-811278D01*
G01X-809235D02*
X-808213D01*
G01Y-98064D02*
X-809235D01*
G01X-811278D02*
X-812300D01*
G01X-816133Y-96063D02*
X-804125D01*
G01Y-94562D02*
X-809745D01*
G01X-811278D02*
X-816133D01*
G01Y-87557D02*
X-811278D01*
G01X-809745D02*
X-804125D01*
G01Y-86056D02*
X-816133D01*
G01X-809235Y-105319D02*
X-807702Y-105569D01*
G01X-814600Y-107320D02*
X-814089Y-106570D01*
G01X-808979Y-104068D02*
X-807702Y-104319D01*
G01X-815877Y-107070D02*
X-815111Y-105819D01*
G01X-805657Y-109822D02*
X-806168Y-110572D01*
G01X-807702Y-104319D02*
X-806935Y-104569D01*
G01D02*
X-805913Y-105069D01*
G01X-807702Y-105569D02*
X-806168Y-106570D01*
G01X-816133Y-108571D02*
X-815877Y-107070D01*
G01X-804125Y-108571D02*
X-804380Y-110072D01*
G01X-814855Y-108571D02*
X-814600Y-107320D01*
G01X-805402Y-108571D02*
X-805657Y-109822D01*
G01X-805913Y-105069D02*
X-805147Y-105819D01*
G01X-816133Y-86056D02*
Y-87557D01*
G01Y-94562D02*
Y-96063D01*
G01X-812300Y-98064D02*
Y-102067D01*
G01X-811278Y-87557D02*
Y-94562D01*
G01Y-102067D02*
Y-98064D01*
G01X-809745Y-94562D02*
Y-87557D01*
G01X-809235Y-98064D02*
Y-102067D01*
G01X-808213D02*
Y-98064D01*
G01X-804125Y-96063D02*
Y-94562D01*
G01Y-87557D02*
Y-86056D01*
G01X-814089Y-110572D02*
X-814600Y-109822D01*
G01X-806168Y-106570D02*
X-805657Y-107320D01*
G01X-805147Y-105819D02*
X-804380Y-107070D01*
G01X-814600Y-109822D02*
X-814855Y-108571D01*
G01X-805657Y-107320D02*
X-805402Y-108571D01*
G01X-815877Y-110072D02*
X-816133Y-108571D01*
G01X-804380Y-107070D02*
X-804125Y-108571D01*
G01X-818785Y106542D02*
X-800603Y70180D01*
G01D02*
X-818785Y106542D01*
G01D02*
G03X-822306Y108719I-3522J-1760D01*
G01X-818785Y106542D02*
G03X-819873Y107877I-3522J-1759D01*
G01X-800188Y68419D02*
G03X-800603Y70180I-3937J2D01*
G01X-800188Y68419D02*
G03X-800603Y70180I-3937J2D01*
G01X-825100Y187459D02*
X-821951D01*
G01D02*
X-520245D01*
G01X-779990Y429803D02*
Y317362D01*
G01X-839242Y378701D02*
Y374173D01*
G01X-838651Y386575D02*
Y378701D01*
G01Y386575D02*
X-833730D01*
G01X-838804D02*
Y379094D01*
G01X-833730Y386575D02*
Y379094D01*
G01X-833139D02*
Y404094D01*
G01X-831171D02*
Y379094D01*
G01X-833572Y398110D02*
X-836328D01*
G01X-833572Y400079D02*
X-836328D01*
G01X-833966Y404094D02*
X-831171D01*
G01X-836328Y400079D02*
Y398110D01*
G01X-835935Y400079D02*
Y398110D01*
G01Y400079D02*
Y404094D01*
G01X-833966Y400079D02*
Y398110D01*
G01Y400079D02*
Y404094D01*
G01X-833572Y400079D02*
Y398110D01*
G01X-761289Y433740D02*
G03I-18701J0D01*
G01X-776053D02*
X-695738D01*
G01X-772116D02*
G03I-7874J0D01*
G01X-774568Y439450D02*
X-698931Y519120D01*
G01X-774872Y753031D02*
Y508937D01*
G01X-828809Y691890D02*
X-831269D01*
G01X-835206D02*
X-837667D01*
G01X-825364Y705963D02*
X-826348D01*
G01X-831269Y707973D02*
X-828809D01*
G01X-826348D02*
X-824380D01*
G01X-838651D02*
X-837175Y707470D01*
G01X-824380Y707973D02*
X-822903Y707470D01*
G01X-827824D02*
X-826348Y707973D01*
G01Y705963D02*
X-827824Y705460D01*
G01X-824380D02*
X-825364Y705963D01*
G01X-838159Y704957D02*
X-838651Y705460D01*
G01X-837175Y707470D02*
X-836191Y706465D01*
G01X-823887Y704957D02*
X-824380Y705460D01*
G01X-828809Y706465D02*
X-827824Y707470D01*
G01Y705460D02*
X-828809Y704455D01*
G01X-837667Y703952D02*
X-838159Y704957D01*
G01X-836191Y706465D02*
X-835206Y703952D01*
G01X-837667Y691890D02*
Y703952D01*
G01X-835206D02*
Y691890D01*
G01X-831269D02*
Y707973D01*
G01X-828809D02*
Y706465D01*
G01Y704455D02*
Y691890D01*
G01X-813061D02*
X-815521D01*
G01X-820935D02*
X-823395D01*
G01X-817490Y705963D02*
X-818966D01*
G01X-818474Y707973D02*
X-816505D01*
G01D02*
X-815029Y707470D01*
G01X-819950D02*
X-818474Y707973D01*
G01X-816505Y705460D02*
X-817490Y705963D01*
G01X-818966D02*
X-819950Y705460D01*
G01X-822903Y707470D02*
X-821427Y705963D01*
G01X-816013Y704957D02*
X-816505Y705460D01*
G01X-815029Y707470D02*
X-814045Y706465D01*
G01X-821427Y705963D02*
X-819950Y707470D01*
G01Y705460D02*
X-820443Y704957D01*
G01X-823395Y703952D02*
X-823887Y704957D01*
G01X-815521Y703952D02*
X-816013Y704957D01*
G01X-820443D02*
X-820935Y703952D01*
G01X-814045Y706465D02*
X-813061Y703952D01*
G01X-823395Y691890D02*
Y703952D01*
G01X-820935D02*
Y691890D01*
G01X-815521D02*
Y703952D01*
G01X-813061D02*
Y691890D01*
G01X-778809Y707283D02*
G03I-11811J0D01*
G01X-784714D02*
G03I-5906J0D01*
G01X-790620Y703346D02*
Y666262D01*
G01X-785119Y705135D02*
X-725054Y681679D01*
G01X-786683Y707283D02*
X-695738D01*
G01X-781933Y715285D02*
X-723229Y769357D01*
G01X-761289Y807756D02*
G03I-18701J0D01*
G01X-779990Y811693D02*
Y839602D01*
G01X-773100Y807756D02*
G03I-6890J0D01*
G01X-822346Y952323D02*
X-824396D01*
G01X-831778D02*
X-834239D01*
G01X-827677Y958187D02*
X-831778D01*
G01Y960700D02*
X-827677D01*
G01X-824396Y965726D02*
X-822346D01*
G01X-834239Y972008D02*
X-831778D01*
G01X-834239Y968657D02*
Y960700D01*
G01Y952323D02*
Y958187D01*
G01X-831778Y972008D02*
Y960700D01*
G01Y958187D02*
Y952323D01*
G01X-827677Y960700D02*
Y958187D01*
G01X-824396Y952323D02*
Y965726D01*
G01X-821525Y965307D02*
X-820295Y965726D01*
G01Y964050D02*
X-821525Y963631D01*
G01X-814964Y965307D02*
X-813733Y965726D01*
G01X-803070Y965307D02*
X-801840Y965726D01*
G01Y964050D02*
X-803070Y963631D01*
G01X-796509Y965307D02*
X-795279Y965726D01*
G01X-814143Y964050D02*
X-814964Y963631D01*
G01X-795689Y964050D02*
X-796509Y963631D01*
G01X-822346Y964469D02*
X-821525Y965307D01*
G01Y963631D02*
X-822346Y962794D01*
G01X-816194Y964050D02*
X-814964Y965307D01*
G01Y963631D02*
X-815374Y963213D01*
G01X-803891Y964469D02*
X-803070Y965307D01*
G01Y963631D02*
X-803891Y962794D01*
G01X-797739Y964050D02*
X-796509Y965307D01*
G01Y963631D02*
X-796919Y963213D01*
G01X-797329Y952323D02*
X-799380D01*
G01X-803891D02*
X-805941D01*
G01X-809222D02*
X-811273D01*
G01X-815784D02*
X-817834D01*
G01X-815374Y963213D02*
X-815784Y962375D01*
G01X-794458Y964050D02*
X-795689D01*
G01X-801020D02*
X-801840D01*
G01X-812913D02*
X-814143D01*
G01X-819475D02*
X-820295D01*
G01Y965726D02*
X-818655D01*
G01X-813733D02*
X-812093D01*
G01X-805941D02*
X-803891D01*
G01X-801840D02*
X-800200D01*
G01X-795279D02*
X-793638D01*
G01X-796919Y963213D02*
X-797329Y962375D01*
G01X-818655Y965726D02*
X-817424Y965307D01*
G01X-812093Y965726D02*
X-810863Y965307D01*
G01X-800200Y965726D02*
X-798970Y965307D01*
G01X-818655Y963631D02*
X-819475Y964050D01*
G01X-812093Y963631D02*
X-812913Y964050D01*
G01X-822346Y965726D02*
Y964469D01*
G01Y962794D02*
Y952323D01*
G01X-817834D02*
Y962375D01*
G01X-815784D02*
Y952323D01*
G01X-811273D02*
Y962375D01*
G01X-809222D02*
Y952323D01*
G01X-805941D02*
Y965726D01*
G01X-803891D02*
Y964469D01*
G01Y962794D02*
Y952323D01*
G01X-799380D02*
Y962375D01*
G01X-797329D02*
Y952323D01*
G01X-800200Y963631D02*
X-801020Y964050D01*
G01X-793638Y963631D02*
X-794458Y964050D01*
G01X-818244Y963213D02*
X-818655Y963631D01*
G01X-817424Y965307D02*
X-816194Y964050D01*
G01X-811683Y963213D02*
X-812093Y963631D01*
G01X-810863Y965307D02*
X-810043Y964469D01*
G01X-799790Y963213D02*
X-800200Y963631D01*
G01X-798970Y965307D02*
X-797739Y964050D01*
G01X-817834Y962375D02*
X-818244Y963213D01*
G01X-811273Y962375D02*
X-811683Y963213D01*
G01X-799380Y962375D02*
X-799790Y963213D01*
G01X-810043Y964469D02*
X-809222Y962375D01*
G01X-790767Y952323D02*
X-792818D01*
G01X-793638Y965726D02*
X-792408Y965307D01*
G01X-792818Y952323D02*
Y962375D01*
G01X-790767D02*
Y952323D01*
G01X-793228Y963213D02*
X-793638Y963631D01*
G01X-792408Y965307D02*
X-791588Y964469D01*
G01X-792818Y962375D02*
X-793228Y963213D01*
G01X-791588Y964469D02*
X-790767Y962375D01*
G01X-761289Y1114843D02*
G03I-18701J0D01*
G01X-773100D02*
G03I-6890J0D01*
G01X-774584Y1119115D02*
X-700281Y1177835D01*
G01X-779990Y1118779D02*
Y1173504D01*
G01X-776609Y1133235D02*
X-754191Y1255178D01*
G01X-720360Y-837696D02*
Y-856633D01*
G01X-773031Y416382D02*
X-731600Y313031D01*
G01D02*
X-728450D01*
G01D02*
X-442335D01*
G01X-750462Y1137623D02*
Y374685D01*
G01X-734714D02*
G03X-730777Y378622I0J3937D01*
G01X-734714Y374685D02*
G03X-730777Y378622I0J3937D01*
G01D02*
Y1098165D01*
G01Y378622D02*
Y1098165D01*
G01X-725054Y681679D02*
X-721904D01*
G01D02*
X-615080D01*
G01X-723229Y769357D02*
X-720080D01*
G01D02*
X-472940D01*
G01X-769163Y807756D02*
X-706924D01*
G01X-739570Y828010D02*
X-738489Y828221D01*
G01D02*
X-737841Y828433D01*
G01X-740434Y808965D02*
X-745621D01*
G01Y810022D02*
X-740434D01*
G01Y812350D02*
X-745621D01*
G01Y813408D02*
X-740434D01*
G01X-738705Y815736D02*
X-739354D01*
G01X-740218D02*
X-745621D01*
G01Y816794D02*
X-738705D01*
G01X-740434Y818487D02*
X-745621D01*
G01Y819545D02*
X-740434D01*
G01Y821873D02*
X-745621D01*
G01Y822931D02*
X-740434D01*
G01X-738705Y825259D02*
X-739354D01*
G01X-740218D02*
X-745621D01*
G01Y826317D02*
X-738705D01*
G01X-741515Y828010D02*
X-739570D01*
G01X-737841Y828433D02*
X-736976Y828856D01*
G01X-739354Y818910D02*
X-740434Y818487D01*
G01X-739354Y809388D02*
X-740434Y808965D01*
G01Y822931D02*
X-740002Y823142D01*
G01X-740434Y819545D02*
X-740002Y819757D01*
G01X-740434Y813408D02*
X-740002Y813620D01*
G01X-740434Y810022D02*
X-740002Y810234D01*
G01X-742596Y828221D02*
X-741515Y828010D01*
G01X-743244Y828433D02*
X-742596Y828221D01*
G01X-740002Y823142D02*
X-739786Y823354D01*
G01X-738922Y822719D02*
X-739570Y822085D01*
G01X-740002Y819757D02*
X-739786Y819968D01*
G01X-738922Y819333D02*
X-739354Y818910D01*
G01X-740002Y813620D02*
X-739786Y813831D01*
G01X-738922Y813197D02*
X-739570Y812562D01*
G01X-740002Y810234D02*
X-739786Y810446D01*
G01X-738922Y809811D02*
X-739354Y809388D01*
G01X-740002Y812139D02*
X-740434Y812350D01*
G01X-740002Y821661D02*
X-740434Y821873D01*
G01X-744108Y828856D02*
X-743244Y828433D01*
G01X-739786Y823354D02*
X-739570Y823778D01*
G01X-739786Y811927D02*
X-740002Y812139D01*
G01X-739570Y812562D02*
X-738922Y811927D01*
G01X-739786Y815313D02*
X-740218Y815736D01*
G01X-739354D02*
X-738922Y815313D01*
G01X-738705Y823354D02*
X-738922Y822719D01*
G01X-738705Y819968D02*
X-738922Y819333D01*
G01X-738705Y813831D02*
X-738922Y813197D01*
G01X-738705Y810446D02*
X-738922Y809811D01*
G01X-739786Y819968D02*
X-739570Y820392D01*
G01X-739786Y813831D02*
X-739570Y814255D01*
G01X-739786Y810446D02*
X-739570Y810869D01*
G01X-739786Y821450D02*
X-740002Y821661D01*
G01X-739570Y822085D02*
X-738922Y821450D01*
G01X-739786Y824835D02*
X-740218Y825259D01*
G01X-739354D02*
X-738922Y824835D01*
G01X-745621Y808965D02*
Y810022D01*
G01Y812350D02*
Y813408D01*
G01Y815736D02*
Y816794D01*
G01Y818487D02*
Y819545D01*
G01Y821873D02*
Y822931D01*
G01Y825259D02*
Y826317D01*
G01X-739570Y811504D02*
X-739786Y811927D01*
G01X-739570Y821026D02*
X-739786Y821450D01*
G01X-739570Y810869D02*
Y811504D01*
G01Y814255D02*
Y814678D01*
G01Y820392D02*
Y821026D01*
G01Y823778D02*
Y824201D01*
G01X-738705Y826317D02*
Y825259D01*
G01Y824201D02*
Y823354D01*
G01Y820815D02*
Y819968D01*
G01Y816794D02*
Y815736D01*
G01Y814678D02*
Y813831D01*
G01Y811292D02*
Y810446D01*
G01X-738922Y811927D02*
X-738705Y811292D01*
G01X-739570Y814678D02*
X-739786Y815313D01*
G01X-738922D02*
X-738705Y814678D01*
G01X-738922Y821450D02*
X-738705Y820815D01*
G01X-739570Y824201D02*
X-739786Y824835D01*
G01X-738922D02*
X-738705Y824201D01*
G01X-741515Y835628D02*
X-742596Y835416D01*
G01X-739786Y829068D02*
X-738489Y829279D01*
G01X-741299Y834570D02*
X-742596Y834358D01*
G01Y835416D02*
X-743244Y835205D01*
G01X-741299Y829068D02*
X-739786D01*
G01X-743244Y835205D02*
X-744108Y834781D01*
G01X-739786Y834570D02*
X-741299D01*
G01X-739570Y835628D02*
X-741515D01*
G01X-738705Y837321D02*
X-739570D01*
G01X-741299D02*
X-742163D01*
G01Y840707D02*
X-741299D01*
G01X-739570D02*
X-738705D01*
G01X-735464Y842400D02*
X-745621D01*
G01Y843669D02*
X-740867D01*
G01X-739570D02*
X-735464D01*
G01Y849594D02*
X-739570D01*
G01X-740867D02*
X-745621D01*
G01Y850864D02*
X-735464D01*
G01X-742596Y829279D02*
X-741299Y829068D01*
G01X-738489Y834358D02*
X-739786Y834570D01*
G01X-742596Y834358D02*
X-743892Y833512D01*
G01X-738489Y829279D02*
X-737193Y830126D01*
G01X-738489Y835416D02*
X-739570Y835628D01*
G01X-737841Y835205D02*
X-738489Y835416D01*
G01X-744108Y834781D02*
X-744757Y834146D01*
G01X-736976Y828856D02*
X-736328Y829491D01*
G01X-736976Y834781D02*
X-737841Y835205D01*
G01X-743892Y833512D02*
X-744324Y832877D01*
G01X-743892Y830126D02*
X-742596Y829279D01*
G01X-737193Y833512D02*
X-738489Y834358D01*
G01X-744757Y834146D02*
X-745405Y833089D01*
G01X-736328Y829491D02*
X-735680Y830549D01*
G01X-737193Y830126D02*
X-736760Y830761D01*
G01X-744757Y829491D02*
X-744108Y828856D01*
G01X-736328Y834146D02*
X-736976Y834781D01*
G01X-745621Y842400D02*
Y843669D01*
G01Y849594D02*
Y850864D01*
G01X-745405Y833089D02*
X-745621Y831819D01*
G01X-735680Y830549D02*
X-735464Y831819D01*
G01X-744324Y832877D02*
X-744541Y831819D01*
G01X-736760Y830761D02*
X-736544Y831819D01*
G01X-744324Y830761D02*
X-743892Y830126D01*
G01X-736760Y832877D02*
X-737193Y833512D01*
G01X-745405Y830549D02*
X-744757Y829491D01*
G01X-735680Y833089D02*
X-736328Y834146D01*
G01X-742163Y837321D02*
Y840707D01*
G01X-741299D02*
Y837321D01*
G01X-740867Y843669D02*
Y849594D01*
G01X-739570D02*
Y843669D01*
G01Y837321D02*
Y840707D01*
G01X-738705D02*
Y837321D01*
G01X-735464Y850864D02*
Y849594D01*
G01Y843669D02*
Y842400D01*
G01X-744541Y831819D02*
X-744324Y830761D01*
G01X-736544Y831819D02*
X-736760Y832877D01*
G01X-745621Y831819D02*
X-745405Y830549D01*
G01X-735464Y831819D02*
X-735680Y833089D01*
G01X-771840Y1098011D02*
Y904646D01*
G01X-749374Y1136288D02*
X-731193Y1099926D01*
G01D02*
X-749374Y1136288D01*
G01X-730777Y1098165D02*
G03X-731193Y1099926I-3937J0D01*
G01X-730777Y1098165D02*
G03X-731193Y1099926I-3937J0D01*
G01X-730777Y1102102D02*
Y1173504D01*
G01X-771840Y1138465D02*
Y1131674D01*
G01X-749374Y1136288D02*
G03X-752896Y1138465I-3522J-1760D01*
G01X-749374Y1136288D02*
G03X-752896Y1138465I-3522J-1760D01*
G01X-754191Y1255178D02*
X-751041D01*
G01D02*
X-449335D01*
G01X-720360Y1340060D02*
Y1321123D01*
G01X-698931Y519120D02*
X-695781D01*
G01D02*
X-588957D01*
G01X-700281Y1177835D02*
X-697131D01*
G01D02*
X-574717D01*
G01X-500691Y-837696D02*
Y-856633D01*
G01Y1340060D02*
Y1321123D01*
G01X-281021Y-837696D02*
Y-856633D01*
G01Y1340060D02*
Y1321123D01*
G01X-61352Y-837696D02*
Y-856633D01*
G01Y1340060D02*
Y1321123D01*
G01X2479Y-837696D02*
X392242D01*
G01X3691Y0D02*
X-34531D01*
G01X3937D02*
X116260D01*
G01X0Y3937D02*
G03X3937Y0I3937J0D01*
G01X0Y723480D02*
Y3937D01*
G01Y723726D02*
Y793248D01*
G01X416Y725241D02*
G03X0Y723480I3521J-1761D01*
G01X21872Y763780D02*
X-34531D01*
G01X18597Y761603D02*
X416Y725241D01*
G01X58423Y-798326D02*
Y-542421D01*
G01Y-798326D02*
X1003305D01*
G01Y-738063D02*
X58423D01*
G01Y-692937D02*
X589650D01*
G01X58423Y-602685D02*
X1003305D01*
G01X58423Y-647811D02*
X1003305D01*
G01X58423Y-542421D02*
X1003305D01*
G01X41069Y2508D02*
G03X42052Y1575I983J51D01*
G01X52436D02*
G03X53419Y2508I0J984D01*
G01D02*
X41069D01*
G01X52436Y1575D02*
X42052D01*
G01X53419Y2508D02*
X54134Y16142D01*
G01X41069Y2508D02*
X40354Y16142D01*
G01X34425Y32177D02*
X34547Y32097D01*
G01X34329Y32290D02*
X34425Y32177D01*
G01X35798Y30893D02*
X35827Y30697D01*
G01X35717Y31078D02*
X35798Y30893D01*
G01X60619Y26876D02*
X60747Y26645D01*
G01X60497Y27137D02*
X60619Y26876D01*
G01X60398Y27433D02*
X60497Y27137D01*
G01X60622Y26882D02*
X60748Y26645D01*
G01X60496Y27131D02*
X60622Y26882D01*
G01X60399Y27433D02*
X60496Y27131D01*
G01X35798Y30975D02*
X35827Y30697D01*
G01X35717Y31236D02*
X35798Y30975D01*
G01X35586Y31475D02*
X35717Y31236D01*
G01X35410Y31684D02*
X35586Y31475D01*
G01X35197Y31854D02*
X35410Y31684D01*
G01X34952Y31980D02*
X35197Y31854D01*
G01X34678Y32056D02*
X34952Y31980D01*
G01X35041Y31941D02*
X34547Y32097D01*
G01X35367Y31724D02*
X35041Y31941D01*
G01X35618Y31426D02*
X35367Y31724D01*
G01X35776Y31068D02*
X35618Y31426D01*
G01X35827Y30697D02*
X35776Y31068D01*
G01X34270Y32424D02*
X34329Y32290D01*
G01X34252Y32560D02*
X34270Y32424D01*
G01X60717Y30137D02*
X60722Y30023D01*
G01X60714Y30246D02*
X60717Y30137D01*
G01X33153Y30467D02*
X33157Y30540D01*
G01X33153Y30354D02*
Y30467D01*
G01X33157Y30212D02*
X33153Y30354D01*
G01X50059Y15313D02*
X50028Y15551D01*
G01X50157Y15077D02*
X50059Y15313D01*
G01X50327Y14860D02*
X50157Y15077D01*
G01X50539Y14702D02*
X50327Y14860D01*
G01X50772Y14606D02*
X50539Y14702D01*
G01X51056Y14567D02*
X50772Y14606D01*
G01X35583Y31250D02*
X35717Y31078D01*
G01X35406Y31398D02*
X35583Y31250D01*
G01X35187Y31520D02*
X35406Y31398D01*
G01X34942Y31607D02*
X35187Y31520D01*
G01X34678Y31658D02*
X34942Y31607D01*
G01X32700Y30922D02*
X32677Y31075D01*
G01X32770Y30781D02*
X32700Y30922D01*
G01X32878Y30669D02*
X32770Y30781D01*
G01X33014Y30594D02*
X32878Y30669D01*
G01X33163Y30564D02*
X33014Y30594D01*
G01X59811Y31843D02*
X59809Y32029D01*
G01Y31679D02*
X59811Y31843D01*
G01X61331Y30212D02*
X61325Y30053D01*
G01X61335Y30354D02*
X61331Y30212D01*
G01X60717Y30521D02*
X60722Y30534D01*
G01X60714Y30482D02*
X60717Y30521D01*
G01X60712Y30421D02*
X60714Y30482D01*
G01X61331Y30540D02*
X61325Y30564D01*
G01X61335Y30467D02*
X61331Y30540D01*
G01X61335Y30355D02*
Y30467D01*
G01X61331Y30212D02*
X61335Y30355D01*
G01X61325Y30053D02*
X61331Y30212D01*
G01X50038Y15416D02*
X50028Y15551D01*
G01X50067Y15283D02*
X50038Y15416D01*
G01X50116Y15154D02*
X50067Y15283D01*
G01X50185Y15031D02*
X50116Y15154D01*
G01X50271Y14918D02*
X50185Y15031D01*
G01X50374Y14817D02*
X50271Y14918D01*
G01X50493Y14730D02*
X50374Y14817D01*
G01X50623Y14660D02*
X50493Y14730D01*
G01X50762Y14609D02*
X50623Y14660D01*
G01X50908Y14577D02*
X50762Y14609D01*
G01X51056Y14567D02*
X50908Y14577D01*
G01X61613Y30671D02*
X61477Y30596D01*
G01X61719Y30783D02*
X61613Y30671D01*
G01X61787Y30922D02*
X61719Y30783D01*
G01X61811Y31075D02*
X61787Y30922D01*
G01X60567Y30502D02*
X60722Y30534D01*
G01X60433Y30426D02*
X60567Y30502D01*
G01X60329Y30317D02*
X60433Y30426D01*
G01X60260Y30178D02*
X60329Y30317D01*
G01X60236Y30023D02*
X60260Y30178D01*
G01X33157Y30212D02*
X33163Y30053D01*
G01X33153Y30354D02*
X33157Y30212D01*
G01X33153Y30467D02*
Y30354D01*
G01X33157Y30540D02*
X33153Y30467D01*
G01X33163Y30564D02*
X33157Y30540D01*
G01X44450Y15416D02*
X44460Y15551D01*
G01X44420Y15283D02*
X44450Y15416D01*
G01X44371Y15154D02*
X44420Y15283D01*
G01X44303Y15031D02*
X44371Y15154D01*
G01X44217Y14918D02*
X44303Y15031D01*
G01X44113Y14817D02*
X44217Y14918D01*
G01X43995Y14730D02*
X44113Y14817D01*
G01X43865Y14660D02*
X43995Y14730D01*
G01X43726Y14609D02*
X43865Y14660D01*
G01X43580Y14577D02*
X43726Y14609D01*
G01X43432Y14567D02*
X43580Y14577D01*
G01X60239Y26645D02*
X60236D01*
G01X60250D02*
X60239D01*
G01X60267D02*
X60250D01*
G01X33865Y26882D02*
X33740Y26645D01*
G01X33992Y27131D02*
X33865Y26882D01*
G01X34089Y27433D02*
X33992Y27131D01*
G01X33868Y26876D02*
X33740Y26645D01*
G01X33991Y27137D02*
X33868Y26876D01*
G01X34089Y27433D02*
X33991Y27137D01*
G01X44429Y15313D02*
X44460Y15551D01*
G01X44331Y15077D02*
X44429Y15313D01*
G01X44161Y14860D02*
X44331Y15077D01*
G01X43949Y14702D02*
X44161Y14860D01*
G01X43716Y14606D02*
X43949Y14702D01*
G01X43432Y14567D02*
X43716Y14606D01*
G01X60251Y30146D02*
X60236Y30023D01*
G01X60298Y30267D02*
X60251Y30146D01*
G01X60376Y30375D02*
X60298Y30267D01*
G01X60479Y30459D02*
X60376Y30375D01*
G01X60599Y30513D02*
X60479Y30459D01*
G01X60722Y30534D02*
X60599Y30513D01*
G01X34196Y30445D02*
X34129Y30377D01*
G01X34240Y30493D02*
X34196Y30445D01*
G01X34252Y30510D02*
X34240Y30493D01*
G01Y30492D02*
X34195Y30443D01*
G01X34252Y30509D02*
X34240Y30492D01*
G01X34237Y30490D02*
X34252Y30510D01*
G01X34178Y30427D02*
X34237Y30490D01*
G01X34029Y30277D02*
X34129Y30377D01*
G01X33915Y30166D02*
X34029Y30277D01*
G01X51933Y15062D02*
X52033Y15301D01*
G01X51773Y14857D02*
X51933Y15062D01*
G01X51562Y14698D02*
X51773Y14857D01*
G01X59066Y31005D02*
X59041Y30697D01*
G01X59139Y31295D02*
X59066Y31005D01*
G01X59258Y31555D02*
X59139Y31295D01*
G01X59415Y31773D02*
X59258Y31555D01*
G01X59603Y31937D02*
X59415Y31773D01*
G01X59809Y32038D02*
X59603Y31937D01*
G01X58711Y31064D02*
X58661Y30697D01*
G01X58868Y31423D02*
X58711Y31064D01*
G01X59121Y31724D02*
X58868Y31423D01*
G01X59451Y31943D02*
X59121Y31724D01*
G01X59809Y32056D02*
X59451Y31943D01*
G01X60722Y30534D02*
G03X60236Y30023I26J-511D01*
G01X61324Y30564D02*
G03X61811Y31075I-25J511D01*
G01X39769Y22080D02*
G03X54561I7396J88629D01*
G01X39750Y21844D02*
G03X54580I7415J88865D01*
G01X59809Y32056D02*
G03X60236Y32560I-84J504D01*
G01X32677Y31075D02*
G03X33163Y30564I512J0D01*
G01X34252Y32560D02*
G03X34678Y32056I511J0D01*
G01X59810D02*
G03X58661Y30697I229J-1359D01*
G01X35827D02*
G03X34678Y32056I-1378J0D01*
G01X50197Y19291D02*
G03X48228Y21260I-1969J0D01*
G01X46260D02*
G03X44291Y19291I0J-1969D01*
G01X39206Y22157D02*
G03X39774Y22078I1010J5179D01*
G01X54556D02*
G03X55124Y22157I-442J5258D01*
G01X54576Y21843D02*
G03X55169Y21925I-457J5493D01*
G01X39161D02*
G03X39755Y21843I1050J5411D01*
G01X45196Y22835D02*
G03X45345Y22793I1997J6799D01*
G01X48985D02*
G03X49120Y22831I-1852J6840D01*
G01X34252Y16535D02*
G03X34645Y16142I393J0D01*
G01X59842D02*
G03X60236Y16535I0J394D01*
G01X38861Y12992D02*
G03X40231Y14226I0J1377D01*
G01X37170D02*
G03X38540Y12992I1370J143D01*
G01X55790D02*
G03X57161Y14226I0J1379D01*
G01X54099D02*
G03X55469Y12992I1370J143D01*
G01X32677Y16535D02*
G03X34645Y14567I1968J0D01*
G01X59842D02*
G03X61811Y16535I0J1969D01*
G01X56356Y21567D02*
X56515Y21621D01*
G01X46251Y20864D02*
X46410Y20918D01*
G01X41437Y20864D02*
X41596Y20918D01*
G01X33534Y34728D02*
X33964Y34874D01*
G01X59719Y16220D02*
X59876Y16280D01*
G01X58333Y16220D02*
X58490Y16280D01*
G01X59561Y18017D02*
X59404Y17957D01*
G01X54491Y16220D02*
X54648Y16280D01*
G01X58175Y18017D02*
X58018Y17957D01*
G01X53105Y16220D02*
X53262Y16280D01*
G01X59561Y19035D02*
X59404Y18976D01*
G01X51719Y16220D02*
X51877Y16280D01*
G01X58175Y19035D02*
X58018Y18976D01*
G01X54333Y18017D02*
X54176Y17957D01*
G01X52947Y18017D02*
X52790Y17957D01*
G01X54333Y19035D02*
X54176Y18976D01*
G01X51530Y18017D02*
X51373Y17957D01*
G01X52947Y19035D02*
X52790Y18976D01*
G01X41861Y16520D02*
X42019Y16580D01*
G01X40476Y16220D02*
X40633Y16280D01*
G01X36885Y16220D02*
X37043Y16280D01*
G01X40318Y18017D02*
X40161Y17957D01*
G01X41704Y18736D02*
X41547Y18676D01*
G01X34145Y16280D02*
X33988Y16220D01*
G01X40318Y19035D02*
X40161Y18976D01*
G01X51319Y14601D02*
X51564Y14700D01*
G01X37540Y16001D02*
X37864Y16142D01*
G01D02*
X37288Y15891D01*
G01X54793Y16142D02*
X54217Y15891D01*
G01X53945Y15771D02*
X53953Y15774D01*
G01X53946Y15771D02*
X54473Y16003D01*
G01X37524Y15994D02*
X37017Y15771D01*
G01X53946D02*
X53950Y15773D01*
G01X37017Y15771D02*
X37021Y15773D01*
G01X51845Y16580D02*
X51719Y16520D01*
G01X51404Y17658D02*
X51530Y17718D01*
G01X42019Y16280D02*
X41893Y16220D01*
G01X37011Y16640D02*
X36885Y16580D01*
G01X34114Y16640D02*
X33988Y16580D01*
G01X36696Y19035D02*
X36570Y18976D01*
G01X57096Y19460D02*
X57308Y19568D01*
G01X54980D02*
X54769Y19460D01*
G01X34295Y16357D02*
X32891Y15642D01*
G01X56303Y21891D02*
X56091Y21783D01*
G01X53552D02*
X53764Y21891D01*
G01X49108Y19568D02*
X48896Y19460D01*
G01X46463Y20648D02*
X46674Y20756D01*
G01X47733Y21783D02*
X47944Y21891D01*
G01X55260Y26292D02*
X55577Y26454D01*
G01X38580Y19568D02*
X38369Y19460D01*
G01X34250Y33046D02*
X33964Y32900D01*
G01Y33266D02*
X34107Y33339D01*
G01X32532Y36044D02*
X32818Y36191D01*
G01X59750Y16520D02*
X59845Y16580D01*
G01X58364Y16520D02*
X58459Y16580D01*
G01X59530Y17718D02*
X59435Y17658D01*
G01X58144Y17718D02*
X58049Y17658D01*
G01X59435Y18676D02*
X59530Y18736D01*
G01X58049Y18676D02*
X58144Y18736D01*
G01X54522Y16520D02*
X54617Y16580D01*
G01X53136Y16520D02*
X53231Y16580D01*
G01X54302Y17718D02*
X54207Y17658D01*
G01X52916Y17718D02*
X52821Y17658D01*
G01X54207Y18676D02*
X54302Y18736D01*
G01X52821Y18676D02*
X52916Y18736D01*
G01X49861Y17838D02*
X49955Y17897D01*
G01X40507Y16520D02*
X40602Y16580D01*
G01X41830Y17778D02*
X42019Y17897D01*
G01X40287Y17718D02*
X40192Y17658D01*
G01Y18676D02*
X40287Y18736D01*
G01X36602Y18616D02*
X36696Y18676D01*
G01X57202Y19892D02*
X57044Y19784D01*
G01X54716D02*
X54875Y19892D01*
G01X56197Y21459D02*
X56356Y21567D01*
G01X53816D02*
X53658Y21459D01*
G01X49002Y19892D02*
X48843Y19784D01*
G01X55657Y26049D02*
X55418Y25887D01*
G01X47838Y21459D02*
X47997Y21567D01*
G01X38474Y19892D02*
X38316Y19784D01*
G01X34465Y33192D02*
X34250Y33046D01*
G01X32890Y35825D02*
X32675Y35679D01*
G01X41860Y20756D02*
X41649Y20594D01*
G01X34393Y34801D02*
X34107Y34582D01*
G01X57403Y24914D02*
X55418Y23130D01*
G01X54783D02*
X57006Y25157D01*
G01X49987Y17598D02*
X50113Y17718D01*
G01X42145Y16400D02*
X42019Y16280D01*
G01Y16580D02*
X42082Y16640D01*
G01X41389Y18856D02*
X41515Y18976D01*
G01X37043Y16280D02*
X37169Y16400D01*
G01X34271D02*
X34145Y16280D01*
G01X36570Y18976D02*
X36444Y18856D01*
G01X33765Y30023D02*
X33940Y30190D01*
G01X34075Y30323D02*
X33917Y30168D01*
G01X34075Y30323D02*
X34196Y30445D01*
G01X57308Y19568D02*
X57520Y19784D01*
G01X55192D02*
X54980Y19568D01*
G01X56091Y21783D02*
X55880Y21567D01*
G01X53340D02*
X53552Y21783D01*
G01X49320Y19784D02*
X49108Y19568D01*
G01X54942Y25968D02*
X55260Y26292D01*
G01X47521Y21567D02*
X47733Y21783D01*
G01X46410Y20918D02*
X46516Y21026D01*
G01X41596Y20918D02*
X41702Y21026D01*
G01X38792Y19784D02*
X38580Y19568D01*
G01X34107Y33339D02*
X34250Y33485D01*
G01X33964Y34874D02*
X34107Y35021D01*
G01X32245Y35752D02*
X32532Y36044D01*
G01X59876Y16280D02*
X60034Y16460D01*
G01X58490Y16280D02*
X58648Y16460D01*
G01X59404Y18976D02*
X59246Y18796D01*
G01X58018Y18976D02*
X57861Y18796D01*
G01X54648Y16280D02*
X54806Y16460D01*
G01X53262Y16280D02*
X53420Y16460D01*
G01X51877Y16280D02*
X52034Y16460D01*
G01X54176Y18976D02*
X54018Y18796D01*
G01X34196Y30445D02*
X34241Y30494D01*
G01X52790Y18976D02*
X52632Y18796D01*
G01X51373Y17957D02*
X51215Y17778D01*
G01X40633Y16280D02*
X40791Y16460D01*
G01X40161Y18976D02*
X40003Y18796D01*
G01X60080Y34289D02*
X61297Y35679D01*
G01X59578Y34289D02*
X61297Y36264D01*
G01X38291Y25887D02*
X37815Y25319D01*
G01Y25968D02*
X38291Y26535D01*
G01X59845Y16580D02*
X59939Y16700D01*
G01X59435Y17658D02*
X59341Y17538D01*
G01X58459Y16580D02*
X58553Y16700D01*
G01X59404Y17957D02*
X59215Y17718D01*
G01X59341Y18556D02*
X59435Y18676D01*
G01X58049Y17658D02*
X57955Y17538D01*
G01X58018Y17957D02*
X57829Y17718D01*
G01X57955Y18556D02*
X58049Y18676D01*
G01X54617Y16580D02*
X54711Y16700D01*
G01X54207Y17658D02*
X54113Y17538D01*
G01X53231Y16580D02*
X53325Y16700D01*
G01X54176Y17957D02*
X53987Y17718D01*
G01X54113Y18556D02*
X54207Y18676D01*
G01X52821Y17658D02*
X52727Y17538D01*
G01X51940Y16700D02*
X51845Y16580D01*
G01X52790Y17957D02*
X52601Y17718D01*
G01X52727Y18556D02*
X52821Y18676D01*
G01X42239Y16520D02*
X42145Y16400D01*
G01X40602Y16580D02*
X40696Y16700D01*
G01X41547Y18676D02*
X41452Y18556D01*
G01X40192Y17658D02*
X40098Y17538D01*
G01X40161Y17957D02*
X39972Y17718D01*
G01X40098Y18556D02*
X40192Y18676D01*
G01X37106Y16760D02*
X37011Y16640D01*
G01X36507Y18496D02*
X36602Y18616D01*
G01X34208Y16760D02*
X34114Y16640D01*
G01X32818Y27433D02*
X32740Y27334D01*
G01X42019Y20972D02*
X41860Y20756D01*
G01X46674D02*
X46833Y20972D01*
G01X51278Y17478D02*
X51404Y17658D01*
G01X42208Y17838D02*
X42082Y17658D01*
G01X57308Y20054D02*
X57202Y19892D01*
G01X57562Y25157D02*
X57403Y24914D01*
G01X53658Y21459D02*
X53552Y21297D01*
G01X55418Y25887D02*
X55260Y25643D01*
G01X49108Y20054D02*
X49002Y19892D01*
G01X47733Y21297D02*
X47838Y21459D01*
G01X38580Y20054D02*
X38474Y19892D01*
G01X34608Y33412D02*
X34465Y33192D01*
G01X34537Y35021D02*
X34393Y34801D01*
G01X32675Y35679D02*
X32532Y35459D01*
G01X57985Y27559D02*
X57303Y26378D01*
G01X40268Y27559D02*
X39586Y26378D01*
G01X59341Y17538D02*
X59278Y17418D01*
G01X57955Y17538D02*
X57892Y17418D01*
G01X33964Y32900D02*
X33677Y32827D01*
G01X38316Y19784D02*
X38104Y19730D01*
G01X47997Y21567D02*
X48209Y21621D01*
G01X54028D02*
X53816Y21567D01*
G01X41515Y18976D02*
X41735Y19035D01*
G01X32741Y27336D02*
X32693Y27249D01*
G01X54113Y17538D02*
X54050Y17418D01*
G01X52727Y17538D02*
X52664Y17418D01*
G01X49955Y17897D02*
X50018Y18017D01*
G01X42995Y17598D02*
X42775Y17179D01*
G01X42082Y16640D02*
X42145Y16760D01*
G01X42019Y17897D02*
X42082Y18017D01*
G01X41263Y18616D02*
X41389Y18856D01*
G01X40098Y17538D02*
X40035Y17418D01*
G01X37169Y16400D02*
X37295Y16640D01*
G01X36444Y18856D02*
X36318Y18616D01*
G01X34397Y16640D02*
X34271Y16400D01*
G01X42775Y17658D02*
X43468Y19035D01*
G01X43720D02*
X43153Y17897D01*
G01X57520Y19784D02*
X57625Y20000D01*
G01X57006Y25157D02*
X57165Y25481D01*
G01X53234Y21351D02*
X53340Y21567D01*
G01X49425Y20000D02*
X49320Y19784D01*
G01X47415Y21351D02*
X47521Y21567D01*
G01X38898Y20000D02*
X38792Y19784D01*
G01X34250Y33485D02*
X34322Y33631D01*
G01X34107Y35021D02*
X34250Y35313D01*
G01X32818Y36191D02*
X33319Y36264D01*
G01X57008Y22524D02*
X55124Y22158D01*
G01X55169Y21926D02*
X57008Y22283D01*
G01X33248Y35898D02*
X32890Y35825D01*
G01X33606Y33192D02*
X33964Y33266D01*
G01X56054Y26130D02*
X55657Y26049D01*
G01X47944Y21891D02*
X48209Y21945D01*
G01X41649Y20594D02*
X41384Y20540D01*
G01X38369Y19460D02*
X38104Y19406D01*
G01X53764Y21891D02*
X54028Y21945D01*
G01X48896Y19460D02*
X48632Y19406D01*
G01X54769Y19460D02*
X54504Y19406D01*
G01X56832D02*
X57096Y19460D01*
G01X48324Y22672D02*
X48924Y22795D01*
G01X61477Y30596D02*
X61325Y30564D01*
G01X56515Y21945D02*
X56303Y21891D01*
G01X48843Y19784D02*
X48632Y19730D01*
G01X54504D02*
X54716Y19784D01*
G01X57044D02*
X56832Y19730D01*
G01X60034Y16460D02*
X60128Y16700D01*
G01X58648Y16460D02*
X58742Y16700D01*
G01X59246Y18796D02*
X59152Y18556D01*
G01X57861Y18796D02*
X57766Y18556D01*
G01X54806Y16460D02*
X54900Y16700D01*
G01X53420Y16460D02*
X53514Y16700D01*
G01X54018Y18796D02*
X53924Y18556D01*
G01X52034Y16460D02*
X52129Y16700D01*
G01X52632Y18796D02*
X52538Y18556D01*
G01X50113Y17718D02*
X50207Y17957D01*
G01X40791Y16460D02*
X40885Y16700D01*
G01X40003Y18796D02*
X39909Y18556D01*
G01X50708Y22598D02*
X50590Y22283D01*
G01X59939Y16700D02*
X60002Y16879D01*
G01X59278Y18377D02*
X59341Y18556D01*
G01X58553Y16700D02*
X58616Y16879D01*
G01X57892Y18377D02*
X57955Y18556D01*
G01X54711Y16700D02*
X54774Y16879D01*
G01X54050Y18377D02*
X54113Y18556D01*
G01X53325Y16700D02*
X53388Y16879D01*
G01X52664Y18377D02*
X52727Y18556D01*
G01X52003Y16879D02*
X51940Y16700D01*
G01X34248Y26645D02*
X34252D01*
G01X47740Y22602D02*
X48350Y22677D01*
G01X51322Y14601D02*
X51056Y14567D01*
G01X55577Y26454D02*
X56133Y26535D01*
G01X42302Y16700D02*
X42239Y16520D01*
G01X42271Y18017D02*
X42208Y17838D01*
G01X41452Y18556D02*
X41389Y18377D01*
G01X40696Y16700D02*
X40759Y16879D01*
G01X40035Y18377D02*
X40098Y18556D01*
G01X37169Y16939D02*
X37106Y16760D01*
G01X34271Y16939D02*
X34208Y16760D01*
G01X56144Y21297D02*
X56197Y21459D01*
G01X54875Y19892D02*
X54927Y20054D01*
G01X46833Y20972D02*
X46886Y21134D01*
G01X46516Y21026D02*
X46569Y21188D01*
G01X42072Y21134D02*
X42019Y20972D01*
G01X41702Y21026D02*
X41754Y21188D01*
G01X34680Y33631D02*
X34608Y33412D01*
G01X48822Y18317D02*
X48412Y16819D01*
G01X48318Y16939D02*
X48727Y18437D01*
G01X42145Y16760D02*
X42176Y16879D01*
G01X42082Y18017D02*
X42145Y18257D01*
G01X57420Y18736D02*
X56790Y16220D01*
G01X56601D02*
X57231Y18736D01*
G01X57641Y25481D02*
X57562Y25157D01*
G01X55880Y21567D02*
X55827Y21351D01*
G01X54863Y25643D02*
X54942Y25968D01*
G01X53552Y21297D02*
X53499Y21080D01*
G01X49161Y20270D02*
X49108Y20054D01*
G01X34220Y26645D02*
X34238D01*
G01X81496Y45669D02*
X77756D01*
G01X81496Y42913D02*
X77756D01*
G01X32677Y40354D02*
X34252D01*
G01X61811D02*
X60236D01*
G01X34252Y40149D02*
X32677D01*
G01X61811D02*
X60236D01*
G01X32677Y39173D02*
X34252D01*
G01X61811D02*
X60236D01*
G01X32677Y38968D02*
X34252D01*
G01X61811D02*
X60236D01*
G01X61297Y36264D02*
X61727D01*
G01X33319D02*
X33463D01*
G01X33534Y35898D02*
X33248D01*
G01X34252Y35622D02*
X32677D01*
G01X61811D02*
X60236D01*
G01X32532Y35459D02*
X32174D01*
G01X60236Y35004D02*
X61811D01*
G01X34252D02*
X32677D01*
G01X33248Y34728D02*
X33534D01*
G01Y34436D02*
X33248D01*
G01X61727Y34289D02*
X62443D01*
G01X61297D02*
X60080D01*
G01X34252Y34244D02*
X32677D01*
G01X61811D02*
X60236D01*
G01X61297Y33851D02*
X59578D01*
G01X62443D02*
X61727D01*
G01X32102Y33631D02*
X32460D01*
G01X60236Y33483D02*
X61811D01*
G01X32677D02*
X34252D01*
G01X33176Y33192D02*
X33606D01*
G01X60236Y32866D02*
X61811D01*
G01X34252D02*
X32677D01*
G01X33677Y32827D02*
X33105D01*
G01X61727D02*
X61297D01*
G01X34252Y30697D02*
X35827D01*
G01X60236D02*
X58661D01*
G01X32677Y30307D02*
X34252D01*
G01X61811D02*
X60236D01*
G01X61325Y30053D02*
X61811D01*
G01X33163D02*
X32677D01*
G01X60722Y30023D02*
X60236D01*
G01Y29740D02*
X61811D01*
G01X32677D02*
X34252D01*
G01X35748Y29134D02*
X43228D01*
G01X58582D02*
X51102D01*
G01Y28346D02*
X43228D01*
G01X40472Y28150D02*
X35748D01*
G01X58582D02*
X53858D01*
G01X50414Y28071D02*
X43916D01*
G01X32677Y27748D02*
X34252D01*
G01X61811D02*
X60236D01*
G01X59370Y27559D02*
X34960D01*
G01Y27433D02*
X32818D01*
G01X61670D02*
X59370D01*
G01X34220Y26645D02*
X33740D01*
G01D02*
X34220D01*
G01X60748D02*
X61811D01*
G01X33740D02*
X32677D01*
G01X34252D02*
X33740D01*
G01X60748D02*
X60236D01*
G01X60747D02*
X60267D01*
G01X56133Y26535D02*
X56451D01*
G01X38291D02*
X38767D01*
G01X39586Y26378D02*
X37027D01*
G01X57303D02*
X54744D01*
G01X56371Y26130D02*
X56054D01*
G01X54744Y26032D02*
X57303D01*
G01X39586D02*
X37027D01*
G01X55260Y25643D02*
X54863D01*
G01X49921Y25276D02*
X44409D01*
G01X39586Y25197D02*
X37027D01*
G01X57303D02*
X54744D01*
G01Y25191D02*
X57303D01*
G01X39586D02*
X37027D01*
G01X54744Y24355D02*
X57303D01*
G01X39586D02*
X37027D01*
G01X54744Y24010D02*
X57303D01*
G01X39586D02*
X37027D01*
G01X41653Y23543D02*
X36535D01*
G01X57795D02*
X52677D01*
G01X60236Y23496D02*
X61811D01*
G01X34252D02*
X32677D01*
G01X55418Y23130D02*
X57641D01*
G01X52283Y22835D02*
X42047D01*
G01X45338Y22795D02*
X48992D01*
G01X38767Y22724D02*
X38291D01*
G01X57641D02*
X54783D01*
G01X55756Y22598D02*
X38574D01*
G01X53959Y22524D02*
X52733D01*
G01X49921D02*
X57008D01*
G01X46378D02*
X37323D01*
G01X49921D02*
X47953D01*
G01X49921Y22520D02*
X44409D01*
G01X50590Y22283D02*
X57008D01*
G01X43740D02*
X37323D01*
G01X50590D02*
X43740D01*
G01X55124Y22158D02*
X39206D01*
G01X39775Y22079D02*
X54556D01*
G01X54028Y21945D02*
X54504D01*
G01X52441D02*
X52758D01*
G01X51700D02*
X52018D01*
G01X49902D02*
X50378D01*
G01X48209D02*
X48632D01*
G01X42495D02*
X44505D01*
G01X40114D02*
X41384D01*
G01X39374D02*
X39691D01*
G01X36834D02*
X38104D01*
G01X46198D02*
X44929D01*
G01X56779D02*
X56515D01*
G01X55169Y21926D02*
X39161D01*
G01X39755Y21844D02*
X54575D01*
G01X41437Y21675D02*
X40432D01*
G01X44505D02*
X43659D01*
G01X43342D02*
X42495D01*
G01X46251D02*
X45246D01*
G01X56515Y21621D02*
X56832D01*
G01X48209D02*
X48632D01*
G01X37152D02*
X38104D01*
G01X54504D02*
X54028D01*
G01X57149Y21351D02*
X57467D01*
G01X55245Y21297D02*
X54927D01*
G01X48228Y21260D02*
X46260D01*
G01X45246Y20864D02*
X46251D01*
G01X40432D02*
X41437D01*
G01X56832D02*
X56515D01*
G01Y20540D02*
X56832D01*
G01X45246D02*
X46145D01*
G01X41384D02*
X40432D01*
G01X55985Y20108D02*
X55668D01*
G01X54927Y20054D02*
X55245D01*
G01X54028Y19730D02*
X54504D01*
G01X38104D02*
X37152D01*
G01X48632D02*
X48209D01*
G01X56832D02*
X56409D01*
G01Y19406D02*
X56832D01*
G01X44929D02*
X45246D01*
G01X46569D02*
X46939D01*
G01X38104D02*
X36834D01*
G01X40432D02*
X40114D01*
G01X39691D02*
X39374D01*
G01X43659D02*
X43342D01*
G01X50219D02*
X49902D01*
G01X48632D02*
X48209D01*
G01X52758D02*
X52441D01*
G01X52018D02*
X51542D01*
G01X54504D02*
X54028D01*
G01X44291Y19291D02*
X50197D01*
G01X60443Y19035D02*
X60569D01*
G01X56286D02*
X57420D01*
G01X55215D02*
X55341D01*
G01X46869D02*
X48066D01*
G01X44664D02*
X44853D01*
G01X45735D02*
X45924D01*
G01X42586D02*
X42775D01*
G01X43468D02*
X43720D01*
G01X41735D02*
X41798D01*
G01X38114D02*
X38366D01*
G01X34744D02*
X35941D01*
G01X33232D02*
X33988D01*
G01X36854D02*
X36696D01*
G01X40444D02*
X40318D01*
G01X50806D02*
X50680D01*
G01X49829D02*
X49074D01*
G01X53073D02*
X52947D01*
G01X52129D02*
X51058D01*
G01X56034D02*
X55908D01*
G01X54459D02*
X54333D01*
G01X59687D02*
X59561D01*
G01X58301D02*
X58175D01*
G01X59530Y18736D02*
X59719D01*
G01X58144D02*
X58333D01*
G01X54302D02*
X54491D01*
G01X52916D02*
X53105D01*
G01X51215D02*
X52129D01*
G01X40287D02*
X40476D01*
G01X35941D02*
X35437D01*
G01X35248D02*
X34744D01*
G01X41830D02*
X41704D01*
G01X47373D02*
X46869D01*
G01X49861D02*
X49263D01*
G01X48066D02*
X47562D01*
G01X57231D02*
X56286D01*
G01X36696Y18676D02*
X36885D01*
G01X33421D02*
X33988D01*
G01X57185Y18504D02*
X37765D01*
G01X59971Y18377D02*
X60128D01*
G01X58585D02*
X58742D01*
G01X54743D02*
X54900D01*
G01X53357D02*
X53514D01*
G01X40728D02*
X40885D01*
G01X37074D02*
X37263D01*
G01X41389D02*
X41232D01*
G01X32677Y18082D02*
X34252D01*
G01X61811D02*
X60236D01*
G01X40476Y18017D02*
X40318D01*
G01X53105D02*
X52947D01*
G01X51719D02*
X51530D01*
G01X54491D02*
X54333D01*
G01X59719D02*
X59561D01*
G01X58333D02*
X58175D01*
G01X49263Y17838D02*
X49861D01*
G01X36885D02*
X36696D01*
G01X41704Y17778D02*
X41830D01*
G01X51530Y17718D02*
X51719D01*
G01X40507D02*
X40287D01*
G01X53136D02*
X52916D01*
G01X54522D02*
X54302D01*
G01X59750D02*
X59530D01*
G01X58364D02*
X58144D01*
G01X46176Y17538D02*
X46617D01*
G01X43972D02*
X44412D01*
G01X39121D02*
X39562D01*
G01X41830D02*
X41704D01*
G01X51058Y17478D02*
X51278D01*
G01X49263D02*
X49798D01*
G01X36696D02*
X36885D01*
G01X39562Y17239D02*
X39121D01*
G01X44412D02*
X43972D01*
G01X46617D02*
X46176D01*
G01X38523Y17179D02*
X37956D01*
G01X36381Y16999D02*
X36192D01*
G01X38555Y16939D02*
X37925D01*
G01X51247D02*
X51058D01*
G01X41200Y16879D02*
X41358D01*
G01X33988Y16580D02*
X33421D01*
G01X36885D02*
X36633D01*
G01X32677Y16535D02*
X34252D01*
G01X61811D02*
X60236D01*
G01X59530Y16520D02*
X59750D01*
G01X58144D02*
X58364D01*
G01X54302D02*
X54522D01*
G01X52916D02*
X53136D01*
G01X41672D02*
X41861D01*
G01X40287D02*
X40507D01*
G01X51719D02*
X51530D01*
G01X59561Y16220D02*
X59719D01*
G01X58175D02*
X58333D01*
G01X54333D02*
X54491D01*
G01X52947D02*
X53105D01*
G01X51530D02*
X51719D01*
G01X49074D02*
X49263D01*
G01X50050D02*
X50270D01*
G01X40318D02*
X40476D01*
G01X36633D02*
X36885D01*
G01X33988D02*
X33232D01*
G01X35437D02*
X35248D01*
G01X38869D02*
X38681D01*
G01X37799D02*
X37610D01*
G01X42775D02*
X42586D01*
G01X43720D02*
X43468D01*
G01X41893D02*
X41641D01*
G01X47562D02*
X47373D01*
G01X45420D02*
X45168D01*
G01X56790D02*
X56601D01*
G01X34645Y16142D02*
X36535D01*
G01X59842D02*
X57795D01*
G01D02*
X36535D01*
G01X55908Y15861D02*
X56034D01*
G01X50680D02*
X50806D01*
G01X55341D02*
X55215D01*
G01X60569D02*
X60443D01*
G01X46260Y15551D02*
X42422D01*
G01X52066D02*
X48228D01*
G01X43432Y14567D02*
X34645D01*
G01X48228D02*
X46260D01*
G01D02*
X43432D01*
G01X59842D02*
X51056D01*
G01D02*
X48228D01*
G01X54099Y14226D02*
X57161D01*
G01X37170D02*
X40231D01*
G01X55469Y12992D02*
X55790D01*
G01X38540D02*
X38861D01*
G01X51374Y22524D02*
X49921Y22522D01*
G01X34248Y26645D02*
X34238D01*
G01X47152Y22580D02*
X47767Y22604D01*
G01X61325Y30564D02*
X60722Y30534D01*
G01X61325Y30053D02*
X60722Y30023D01*
G01X37295Y16640D02*
X37358Y16879D01*
G01X34460D02*
X34397Y16640D01*
G01X47680Y21080D02*
X47733Y21297D01*
G01X38633Y20270D02*
X38580Y20054D01*
G01X34608Y35313D02*
X34537Y35021D01*
G01X32174Y35459D02*
X32245Y35752D01*
G01X32693Y27250D02*
X32677Y27177D01*
G01X60632Y16161D02*
X60569Y15861D01*
G01X60443D02*
X60506Y16161D01*
G01X60128Y16700D02*
X60191Y16999D01*
G01X59152Y18556D02*
X59089Y18257D01*
G01X58742Y16700D02*
X58805Y16999D01*
G01X57766Y18556D02*
X57703Y18257D01*
G01X55971Y18736D02*
X56034Y19035D01*
G01X55404Y16161D02*
X55341Y15861D01*
G01X55908Y19035D02*
X55845Y18736D01*
G01X55215Y15861D02*
X55278Y16161D01*
G01X54900Y16700D02*
X54963Y16999D01*
G01X53924Y18556D02*
X53861Y18257D01*
G01X53514Y16700D02*
X53577Y16999D01*
G01X52538Y18556D02*
X52475Y18257D01*
G01X52129Y16700D02*
X52192Y16999D01*
G01X50743Y18736D02*
X50806Y19035D01*
G01X50680D02*
X50617Y18736D01*
G01X40885Y16700D02*
X40948Y16999D01*
G01X39909Y18556D02*
X39846Y18257D01*
G01X55245Y20054D02*
X55192Y19784D01*
G01X53182Y21080D02*
X53234Y21351D01*
G01X49478Y20270D02*
X49425Y20000D01*
G01X47362Y21080D02*
X47415Y21351D01*
G01X38951Y20270D02*
X38898Y20000D01*
G01X45294Y16580D02*
X45735Y19035D01*
G01X45924D02*
X45420Y16220D01*
G01X37610D02*
X38114Y19035D01*
G01X50462Y28346D02*
X49921Y25276D01*
G01X60002Y16879D02*
X60034Y17059D01*
G01X59278Y17418D02*
X59246Y17239D01*
G01Y18197D02*
X59278Y18377D01*
G01X58616Y16879D02*
X58648Y17059D01*
G01X57892Y17418D02*
X57861Y17239D01*
G01Y18197D02*
X57892Y18377D01*
G01X54774Y16879D02*
X54806Y17059D01*
G01X54050Y17418D02*
X54018Y17239D01*
G01Y18197D02*
X54050Y18377D01*
G01X53388Y16879D02*
X53420Y17059D01*
G01X52664Y17418D02*
X52632Y17239D01*
G01Y18197D02*
X52664Y18377D01*
G01X52034Y17059D02*
X52003Y16879D01*
G01X50207Y17957D02*
X50239Y18137D01*
G01X50018Y18017D02*
X50050Y18197D01*
G01X42334Y16879D02*
X42302Y16700D01*
G01X40759Y16879D02*
X40791Y17059D01*
G01X40035Y17418D02*
X40003Y17239D01*
G01Y18197D02*
X40035Y18377D01*
G01X37925Y16939D02*
X37799Y16220D01*
G01X37956Y17179D02*
X38240Y18796D01*
G01X60695Y16700D02*
X60632Y16161D01*
G01X60506D02*
X60569Y16700D01*
G01X33463Y36264D02*
X33964Y36191D01*
G01X45980Y22677D02*
X46590Y22602D01*
G01X34252Y30510D02*
X33163Y30564D01*
G01X33765Y30023D02*
X33163Y30053D01*
G01X46564Y22604D02*
X47178Y22580D01*
G01X36476Y18317D02*
X36507Y18496D01*
G01X52066Y15551D02*
X52032Y15299D01*
G01X42302Y18257D02*
X42271Y18017D01*
G01X41232Y18377D02*
X41263Y18616D01*
G01X36318D02*
X36287Y18377D01*
G01X34303Y17179D02*
X34271Y16939D01*
G01X55908Y18197D02*
X55971Y18736D01*
G01X55845D02*
X55782Y18197D01*
G01X55467Y16700D02*
X55404Y16161D01*
G01X55278D02*
X55341Y16700D01*
G01X50680Y18197D02*
X50743Y18736D01*
G01X50617D02*
X50554Y18197D01*
G01X34492Y17179D02*
X34460Y16879D01*
G01X57161Y14226D02*
X57362Y16142D01*
G01X40231Y14226D02*
X40433Y16142D01*
G01X59215Y17838D02*
X59246Y18197D01*
G01X57829Y17838D02*
X57861Y18197D01*
G01X53987Y17838D02*
X54018Y18197D01*
G01X52601Y17838D02*
X52632Y18197D01*
G01X39972Y17838D02*
X40003Y18197D01*
G01X59089Y18257D02*
X59057Y17838D01*
G01X57703Y18257D02*
X57672Y17838D01*
G01X53861Y18257D02*
X53829Y17838D01*
G01X52475Y18257D02*
X52444Y17838D01*
G01X39846Y18257D02*
X39814Y17838D01*
G01X60727Y17239D02*
X60695Y16700D01*
G01X60569D02*
X60601Y17239D01*
G01X55876Y17658D02*
X55908Y18197D01*
G01X55782D02*
X55750Y17658D01*
G01X55498Y17239D02*
X55467Y16700D01*
G01X55341D02*
X55372Y17239D01*
G01X50648Y17658D02*
X50680Y18197D01*
G01X50554D02*
X50522Y17658D01*
G01X77915Y45669D02*
Y42913D01*
G01X77891D02*
Y45669D01*
G01X77755D02*
Y42913D01*
G01X33105Y32827D02*
X32818Y32900D01*
G01X54716Y21567D02*
X54504Y21621D01*
G01X56832Y20540D02*
X57044Y20486D01*
G01X46007Y22672D02*
X45406Y22795D01*
G01X33892Y35825D02*
X33534Y35898D01*
G01X32818Y33266D02*
X33176Y33192D01*
G01X56768Y26049D02*
X56371Y26130D01*
G01X57044Y21891D02*
X56779Y21945D01*
G01X54504D02*
X54769Y21891D01*
G01X57096Y20810D02*
X56832Y20864D01*
G01X48632Y21945D02*
X48896Y21891D01*
G01X46463D02*
X46198Y21945D01*
G01X56144Y19460D02*
X56409Y19406D01*
G01X54028D02*
X53764Y19460D01*
G01X41384Y21945D02*
X41649Y21891D01*
G01X38104Y21945D02*
X38369Y21891D01*
G01X48209Y19406D02*
X47944Y19460D01*
G01X39206Y22158D02*
X37323Y22524D01*
G01X39161Y21926D02*
X37323Y22283D01*
G01X33964Y34362D02*
X33534Y34436D01*
G01X56451Y26535D02*
X56927Y26454D01*
G01X43166Y14601D02*
X43432Y14567D01*
G01X38574Y22598D02*
X38378Y16142D01*
G01X59809Y32056D02*
Y32029D01*
G01X59810Y31947D02*
X59809Y31818D01*
G01X59811Y31428D02*
X59809Y30916D01*
G01X60712Y30423D02*
Y30340D01*
G01X62443Y34289D02*
Y33851D01*
G01X61811Y31075D02*
Y38968D01*
G01Y16535D02*
Y30053D01*
G01Y40354D02*
Y38968D01*
G01Y30053D02*
Y31075D01*
G01X61727Y36264D02*
Y34289D01*
G01Y33851D02*
Y32827D01*
G01X61325Y27433D02*
Y30053D01*
G01X61297Y32827D02*
Y33851D01*
G01Y35679D02*
Y34289D01*
G01X60727Y17658D02*
Y17239D01*
G01X60722Y30023D02*
Y27433D01*
G01X60601Y17239D02*
Y17658D01*
G01X60236Y16535D02*
Y38968D01*
G01Y40354D02*
Y38968D01*
G01X60191Y16999D02*
Y17299D01*
G01X60034Y17059D02*
Y17239D01*
G01X59809Y30916D02*
Y32056D01*
G01Y27433D02*
Y30697D01*
G01Y32038D02*
Y30697D01*
G01X59578Y33851D02*
Y34289D01*
G01X59370Y27559D02*
Y16142D01*
G01X59246Y17239D02*
Y17059D01*
G01X59215Y17718D02*
Y17838D01*
G01X59057D02*
Y17418D01*
G01X58858Y16142D02*
Y14567D01*
G01X58805Y16999D02*
Y17299D01*
G01X58661Y30697D02*
Y27559D01*
G01X58648Y17059D02*
Y17239D01*
G01X58582Y29134D02*
Y27559D01*
G01X57861Y17239D02*
Y17059D01*
G01X57829Y17718D02*
Y17838D01*
G01X57795Y23543D02*
Y16142D01*
G01Y27230D02*
Y23543D01*
G01X57672Y17838D02*
Y17418D01*
G01X57641Y23130D02*
Y22724D01*
G01Y25643D02*
Y25481D01*
G01X57625Y20000D02*
Y20270D01*
G01X57480Y16142D02*
Y14567D01*
G01X57420Y19035D02*
Y18736D01*
G01X57308Y20216D02*
Y20054D01*
G01X57303Y24010D02*
Y26378D01*
G01X57185Y16142D02*
Y18504D01*
G01X57165Y25481D02*
Y25643D01*
G01X57008Y22524D02*
Y22283D01*
G01X56286Y18736D02*
Y19035D01*
G01X56144Y21188D02*
Y21297D01*
G01X55876Y17239D02*
Y17658D01*
G01X55827Y21351D02*
Y21134D01*
G01X55756Y23543D02*
Y22598D01*
G01X55750Y17658D02*
Y17239D01*
G01X55498Y17658D02*
Y17239D01*
G01X55372D02*
Y17658D01*
G01X54963Y16999D02*
Y17299D01*
G01X54806Y17059D02*
Y17239D01*
G01X54783Y22724D02*
Y23130D01*
G01X54744Y26378D02*
Y24010D01*
G01X54527Y14567D02*
Y16142D01*
G01X54018Y17239D02*
Y17059D01*
G01X53987Y17718D02*
Y17838D01*
G01X53937Y15772D02*
Y14567D01*
G01X53858Y29134D02*
Y28150D01*
G01X53829Y17838D02*
Y17418D01*
G01X53577Y16999D02*
Y17299D01*
G01X53499Y21080D02*
Y20270D01*
G01X53420Y17059D02*
Y17239D01*
G01X53182Y20270D02*
Y21080D01*
G01X53149Y16142D02*
Y14567D01*
G01X53071Y29134D02*
Y27559D01*
G01X52991Y16142D02*
Y14567D01*
G01X52758Y21945D02*
Y19406D01*
G01X52677Y23543D02*
Y22598D01*
G01X52632Y17239D02*
Y17059D01*
G01X52601Y17718D02*
Y17838D01*
G01X52444D02*
Y17418D01*
G01X52441Y19406D02*
Y21945D01*
G01X52283Y22835D02*
Y16142D01*
G01X52192Y16999D02*
Y17239D01*
G01X52165Y18504D02*
Y16142D01*
G01X52129Y18736D02*
Y19035D01*
G01X52066Y18504D02*
Y15551D01*
G01X52034Y17179D02*
Y17059D01*
G01X52018Y21945D02*
Y19406D01*
G01X51700Y19784D02*
Y21945D01*
G01X51215Y17778D02*
Y18736D01*
G01X51102Y29134D02*
Y28346D01*
G01X51058Y19035D02*
Y17478D01*
G01X50648Y17239D02*
Y17658D01*
G01X50522D02*
Y17239D01*
G01X50239Y18137D02*
Y18377D01*
G01X50219Y21621D02*
Y19406D01*
G01X50197Y14567D02*
Y16142D01*
G01Y19291D02*
Y18504D01*
G01X50050Y18197D02*
Y18377D01*
G01X50028Y18504D02*
Y15551D01*
G01X49921Y22283D02*
Y22524D01*
G01X49902Y19406D02*
Y21945D01*
G01X49862Y14567D02*
Y16142D01*
G01X49478Y21080D02*
Y20270D01*
G01X49263Y16220D02*
Y17478D01*
G01Y18736D02*
Y17838D01*
G01X49161Y21080D02*
Y20270D01*
G01X49074Y19035D02*
Y16220D01*
G01X48228Y18504D02*
Y14567D01*
G01X48066Y19035D02*
Y18736D01*
G01X47953Y22524D02*
Y22283D01*
G01X47680Y20270D02*
Y21080D01*
G01X47562Y18736D02*
Y16220D01*
G01X47373D02*
Y18736D01*
G01X47362Y20270D02*
Y21080D01*
G01X47165Y21926D02*
Y21844D01*
G01X46886Y21134D02*
Y21351D01*
G01X46869Y18736D02*
Y19035D01*
G01X46617Y17538D02*
Y17239D01*
G01X46569Y21188D02*
Y21351D01*
G01X46378Y22283D02*
Y22524D01*
G01X46260Y18504D02*
Y14567D01*
G01X46176Y17239D02*
Y17538D01*
G01X45246Y19406D02*
Y20540D01*
G01Y21675D02*
Y20864D01*
G01X44929Y21945D02*
Y19406D01*
G01X44626Y14567D02*
Y16142D01*
G01X44622Y14567D02*
Y16142D01*
G01X44505Y21945D02*
Y21675D01*
G01X44460Y18504D02*
Y15551D01*
G01X44412Y17538D02*
Y17239D01*
G01X44409Y22524D02*
Y22283D01*
G01X44291Y14567D02*
Y16142D01*
G01Y19291D02*
Y18504D01*
G01X43972Y17239D02*
Y17538D01*
G01X43659Y21675D02*
Y19406D01*
G01X43342D02*
Y21675D01*
G01X43228Y28346D02*
Y29134D01*
G01X42775Y19035D02*
Y17658D01*
G01Y17179D02*
Y16220D01*
G01X42586D02*
Y19035D01*
G01X42495Y21675D02*
Y21945D01*
G01X42422Y18504D02*
Y15551D01*
G01X42334Y17119D02*
Y16879D01*
G01X42323Y16142D02*
Y18504D01*
G01X42302Y18377D02*
Y18257D01*
G01X42176Y16879D02*
Y17119D01*
G01X42145Y18257D02*
Y18377D01*
G01X42072Y21351D02*
Y21134D01*
G01X42047Y22835D02*
Y16142D01*
G01X41754Y21188D02*
Y21351D01*
G01X41704Y17538D02*
Y17778D01*
G01X41653Y23543D02*
Y22598D01*
G01X41497Y16142D02*
Y14567D01*
G01X41338Y16142D02*
Y14567D01*
G01X41260Y29134D02*
Y27559D01*
G01X40948Y16999D02*
Y17299D01*
G01X40791Y17059D02*
Y17239D01*
G01X40551Y16142D02*
Y14567D01*
G01X40472Y29134D02*
Y28150D01*
G01X40432Y21675D02*
Y20864D01*
G01Y20540D02*
Y19406D01*
G01X40114D02*
Y21945D01*
G01X40003Y17239D02*
Y17059D01*
G01X39972Y17718D02*
Y17838D01*
G01X39960Y14567D02*
Y16142D01*
G01X39814Y17838D02*
Y17418D01*
G01X39691Y21945D02*
Y19406D01*
G01X39586Y24010D02*
Y26378D01*
G01X39562Y17538D02*
Y17239D01*
G01X39374Y19406D02*
Y21945D01*
G01X39121Y17239D02*
Y17538D01*
G01X38951Y21080D02*
Y20270D01*
G01X38767Y26535D02*
Y22724D01*
G01X38633Y21080D02*
Y20270D01*
G01X38582Y16142D02*
Y18504D01*
G01X38574Y23543D02*
Y22598D01*
G01X38291Y22724D02*
Y25887D01*
G01X37815Y25319D02*
Y25968D01*
G01X37765Y16142D02*
Y18504D01*
G01X37358Y16879D02*
Y17179D01*
G01X37323Y22524D02*
Y22283D01*
G01X37169Y17119D02*
Y16939D01*
G01X37152Y19730D02*
Y21621D01*
G01X37027Y26378D02*
Y24010D01*
G01X37008Y15772D02*
Y14567D01*
G01X36834Y19406D02*
Y21945D01*
G01X36535Y23543D02*
Y16142D01*
G01Y27230D02*
Y23543D01*
G01X36476Y18197D02*
Y18317D01*
G01X36287Y18377D02*
Y18137D01*
G01X35941Y19035D02*
Y18736D01*
G01X35827Y30697D02*
Y28150D01*
G01X35748Y29134D02*
Y27559D01*
G01X35630Y16142D02*
Y14567D01*
G01X35437Y18736D02*
Y16220D01*
G01X35248D02*
Y18736D01*
G01X34960Y27559D02*
Y16142D01*
G01X34744Y18736D02*
Y19035D01*
G01X34680Y33924D02*
Y33631D01*
G01X34678Y31658D02*
Y27433D01*
G01Y31658D02*
Y32056D01*
G01D02*
Y31658D01*
G01X34608Y35459D02*
Y35313D01*
G01X34492Y18077D02*
Y17179D01*
G01X34322Y33631D02*
Y33924D01*
G01X34303Y18077D02*
Y17179D01*
G01X34252Y16535D02*
Y38968D01*
G01Y40354D02*
Y38968D01*
G01X34250Y35313D02*
Y35459D01*
G01X33765Y30023D02*
Y27433D01*
G01X33421Y16580D02*
Y18676D01*
G01X33248Y34436D02*
Y34728D01*
G01X33232Y16220D02*
Y19035D01*
G01X33163Y30053D02*
Y27433D01*
G01X32677Y31075D02*
Y38968D01*
G01Y16535D02*
Y30053D01*
G01Y31075D02*
Y30053D01*
G01Y40354D02*
Y38968D01*
G01X59809Y31636D02*
X59811Y31428D01*
G01Y31965D02*
X59809Y32038D01*
G01X60712Y30342D02*
X60714Y30244D01*
G01X55756Y22598D02*
X55952Y16142D01*
G01X60722Y30023D02*
X60717Y30136D01*
G01X60695Y18197D02*
X60727Y17658D01*
G01X60601D02*
X60569Y18197D01*
G01X55908Y16700D02*
X55876Y17239D01*
G01X55750D02*
X55782Y16700D01*
G01X55467Y18197D02*
X55498Y17658D01*
G01X55372D02*
X55341Y18197D01*
G01X50680Y16700D02*
X50648Y17239D01*
G01X50522D02*
X50554Y16700D01*
G01X59057Y17418D02*
X59089Y16999D01*
G01X57672Y17418D02*
X57703Y16999D01*
G01X53829Y17418D02*
X53861Y16999D01*
G01X52444Y17418D02*
X52475Y16999D01*
G01X60632Y18736D02*
X60695Y18197D01*
G01X60569D02*
X60506Y18736D01*
G01X55971Y16161D02*
X55908Y16700D01*
G01X55782D02*
X55845Y16161D01*
G01X55404Y18736D02*
X55467Y18197D01*
G01X55341D02*
X55278Y18736D01*
G01X50743Y16161D02*
X50680Y16700D01*
G01X50554D02*
X50617Y16161D01*
G01X42271Y18616D02*
X42302Y18377D01*
G01Y17358D02*
X42334Y17119D01*
G01X36287Y18137D02*
X36318Y17897D01*
G01X36192Y16999D02*
X36224Y16760D01*
G01X34271Y18317D02*
X34303Y18077D01*
G01X42422Y15551D02*
X42456Y15299D01*
G01X41502Y23450D02*
X41486Y23543D01*
G01X60128Y18377D02*
X60097Y18556D01*
G01X60034Y17239D02*
X60002Y17418D01*
G01X59246Y17059D02*
X59278Y16879D01*
G01X58742Y18377D02*
X58711Y18556D01*
G01X58648Y17239D02*
X58616Y17418D01*
G01X57861Y17059D02*
X57892Y16879D01*
G01X54900Y18377D02*
X54869Y18556D01*
G01X54806Y17239D02*
X54774Y17418D01*
G01X54018Y17059D02*
X54050Y16879D01*
G01X53514Y18377D02*
X53483Y18556D01*
G01X53420Y17239D02*
X53388Y17418D01*
G01X52632Y17059D02*
X52664Y16879D01*
G01X52003Y17358D02*
X52034Y17179D01*
G01X50239Y18377D02*
X50207Y18556D01*
G01X50050Y18377D02*
X50018Y18556D01*
G01X41232Y16700D02*
X41200Y16879D01*
G01X40885Y18377D02*
X40854Y18556D01*
G01X40791Y17239D02*
X40759Y17418D01*
G01X40003Y17059D02*
X40035Y16879D01*
G01X38240Y18796D02*
X38523Y17179D01*
G01X38681Y16220D02*
X38555Y16939D01*
G01X37263Y18377D02*
X37232Y18556D01*
G01X43868Y28346D02*
X44409Y25276D01*
G01X45168Y16220D02*
X44664Y19035D01*
G01X38366D02*
X38869Y16220D01*
G01X44853Y19035D02*
X45294Y16580D01*
G01X55192Y21567D02*
X55245Y21297D01*
G01X53234Y20000D02*
X53182Y20270D01*
G01X49425Y21351D02*
X49478Y21080D01*
G01X47415Y20000D02*
X47362Y20270D01*
G01X49798Y17478D02*
X50050Y16220D01*
G01X50270D02*
X49987Y17598D01*
G01X60569Y19035D02*
X60632Y18736D01*
G01X60506D02*
X60443Y19035D01*
G01X60191Y17299D02*
X60128Y17598D01*
G01X59089Y16999D02*
X59152Y16700D01*
G01X58805Y17299D02*
X58742Y17598D01*
G01X57703Y16999D02*
X57766Y16700D01*
G01X56034Y15861D02*
X55971Y16161D01*
G01X55341Y19035D02*
X55404Y18736D01*
G01X55845Y16161D02*
X55908Y15861D01*
G01X55278Y18736D02*
X55215Y19035D01*
G01X54963Y17299D02*
X54900Y17598D01*
G01X53861Y16999D02*
X53924Y16700D01*
G01X53577Y17299D02*
X53514Y17598D01*
G01X52475Y16999D02*
X52538Y16700D01*
G01X52192Y17239D02*
X52129Y17538D01*
G01X50806Y15861D02*
X50743Y16161D01*
G01X50617D02*
X50680Y15861D01*
G01X61795Y27250D02*
X61811Y27177D01*
G01X57562Y25968D02*
X57641Y25643D01*
G01X55827Y21134D02*
X55880Y20918D01*
G01X55668Y20108D02*
X55721Y19892D01*
G01X34107Y34582D02*
X34465Y34436D01*
G01X59845Y18976D02*
X59687Y19035D01*
G01X58459Y18976D02*
X58301Y19035D01*
G01X59876Y17957D02*
X59719Y18017D01*
G01X58490Y17957D02*
X58333Y18017D01*
G01X54617Y18976D02*
X54459Y19035D01*
G01X53231Y18976D02*
X53073Y19035D01*
G01X59404Y16280D02*
X59561Y16220D01*
G01X54648Y17957D02*
X54491Y18017D01*
G01X58018Y16280D02*
X58175Y16220D01*
G01X53262Y17957D02*
X53105Y18017D01*
G01X49987Y18976D02*
X49829Y19035D01*
G01X51877Y17957D02*
X51719Y18017D01*
G01X54176Y16280D02*
X54333Y16220D01*
G01X52790Y16280D02*
X52947Y16220D01*
G01X51373Y16280D02*
X51530Y16220D01*
G01X41987Y18676D02*
X41830Y18736D01*
G01X40602Y18976D02*
X40444Y19035D01*
G01X40633Y17957D02*
X40476Y18017D01*
G01X37011Y18976D02*
X36854Y19035D01*
G01X56832Y21621D02*
X56991Y21567D01*
G01X56515Y20864D02*
X56356Y20918D01*
G01X46410Y21621D02*
X46251Y21675D01*
G01X41596Y21621D02*
X41437Y21675D01*
G01X42019Y17478D02*
X41830Y17538D01*
G01X41798Y19035D02*
X42019Y18976D01*
G01X56303Y20594D02*
X56515Y20540D01*
G01X56409Y19730D02*
X56197Y19784D01*
G01X48632Y21621D02*
X48843Y21567D01*
G01X53816Y19784D02*
X54028Y19730D01*
G01X48209D02*
X47997Y19784D01*
G01X38104Y21621D02*
X38316Y21567D01*
G01X39814Y17418D02*
X39846Y16999D01*
G01X54099Y14226D02*
X53936Y15772D01*
G01X37170Y14226D02*
X37007Y15772D01*
G01X34460Y18377D02*
X34492Y18077D01*
G01X36507Y18017D02*
X36476Y18197D01*
G01X36413Y16819D02*
X36381Y16999D01*
G01X38898Y21351D02*
X38951Y21080D01*
G01X40948Y17299D02*
X40885Y17598D01*
G01X39846Y16999D02*
X39909Y16700D01*
G01X41501Y23455D02*
X41523Y23360D01*
G01X53499Y20270D02*
X53552Y20054D01*
G01X49108Y21297D02*
X49161Y21080D01*
G01X47733Y20054D02*
X47680Y20270D01*
G01X38580Y21297D02*
X38633Y21080D01*
G01X34537Y35752D02*
X34608Y35459D01*
G01Y34216D02*
X34680Y33924D01*
G01X51310Y16700D02*
X51247Y16939D01*
G01X51058D02*
X51121Y16700D01*
G01X42176Y17119D02*
X42113Y17358D01*
G01X41358Y16879D02*
X41389Y16760D01*
G01X37043Y18496D02*
X37074Y18377D01*
G01X37358Y17179D02*
X37295Y17418D01*
G01X34397Y18616D02*
X34460Y18377D01*
G01X41522Y23365D02*
X41548Y23276D01*
G01X36224Y16760D02*
X36318Y16460D01*
G01X57467Y21351D02*
X57414Y21513D01*
G01X56197Y21026D02*
X56144Y21188D01*
G01X56038Y19946D02*
X55985Y20108D01*
G01X54927Y21297D02*
X54875Y21459D01*
G01X46886Y21351D02*
X46833Y21513D01*
G01X46569Y21351D02*
X46516Y21513D01*
G01X42019D02*
X42072Y21351D01*
G01X41754D02*
X41702Y21513D01*
G01X32174Y33412D02*
X32102Y33631D01*
G01X43153Y17897D02*
X43720Y16220D01*
G01X43468D02*
X42995Y17598D01*
G01X59908Y18556D02*
X59971Y18377D01*
G01X59278Y16879D02*
X59341Y16700D01*
G01X58522Y18556D02*
X58585Y18377D01*
G01X57892Y16879D02*
X57955Y16700D01*
G01X54680Y18556D02*
X54743Y18377D01*
G01X54050Y16879D02*
X54113Y16700D01*
G01X53294Y18556D02*
X53357Y18377D01*
G01X52664Y16879D02*
X52727Y16700D01*
G01X51940Y17538D02*
X52003Y17358D01*
G01X42145Y18377D02*
X42082Y18556D01*
G01X42239Y17538D02*
X42302Y17358D01*
G01X40665Y18556D02*
X40728Y18377D01*
G01X41295Y16520D02*
X41232Y16700D01*
G01X40035Y16879D02*
X40098Y16700D01*
G01X37106Y17299D02*
X37169Y17119D01*
G01X41548Y23278D02*
X41579Y23192D01*
G01X46145Y20540D02*
X46569Y19406D01*
G01X43622Y22598D02*
X43740Y22283D01*
G01X46939Y19406D02*
X46463Y20648D01*
G01X60097Y18556D02*
X60002Y18796D01*
G01X58711Y18556D02*
X58616Y18796D01*
G01X59152Y16700D02*
X59246Y16460D01*
G01X57766Y16700D02*
X57861Y16460D01*
G01X54869Y18556D02*
X54774Y18796D01*
G01X53483Y18556D02*
X53388Y18796D01*
G01X53924Y16700D02*
X54018Y16460D01*
G01X52538Y16700D02*
X52632Y16460D01*
G01X52129Y17538D02*
X52034Y17778D01*
G01X51121Y16700D02*
X51215Y16460D01*
G01X50207Y18556D02*
X50113Y18796D01*
G01X57096Y21459D02*
X57149Y21351D01*
G01X57625Y20270D02*
X57520Y20486D01*
G01X60128Y17598D02*
X60034Y17778D01*
G01X61746Y27336D02*
X61795Y27249D01*
G01X57006Y25887D02*
X56768Y26049D01*
G01X57044Y20486D02*
X57202Y20378D01*
G01X56356Y20918D02*
X56197Y21026D01*
G01X34107Y35679D02*
X33892Y35825D01*
G01X54875Y21459D02*
X54716Y21567D01*
G01X34179Y34216D02*
X33964Y34362D01*
G01X53658Y19892D02*
X53816Y19784D01*
G01X59719Y18736D02*
X59813Y18676D01*
G01X58333Y18736D02*
X58427Y18676D01*
G01X59845Y17658D02*
X59750Y17718D01*
G01X58459Y17658D02*
X58364Y17718D01*
G01X59435Y16580D02*
X59530Y16520D01*
G01X58049Y16580D02*
X58144Y16520D01*
G01X54491Y18736D02*
X54585Y18676D01*
G01X53105Y18736D02*
X53199Y18676D01*
G01X54617Y17658D02*
X54522Y17718D01*
G01X53231Y17658D02*
X53136Y17718D01*
G01X54207Y16580D02*
X54302Y16520D01*
G01X49955Y18676D02*
X49861Y18736D01*
G01X52821Y16580D02*
X52916Y16520D01*
G01X55880Y19622D02*
X56144Y19460D01*
G01X56927Y26454D02*
X57244Y26292D01*
G01X33964Y36191D02*
X34250Y36044D01*
G01X32675Y33339D02*
X32818Y33266D01*
G01X57308Y20702D02*
X57096Y20810D01*
G01X54769Y21891D02*
X54980Y21783D01*
G01X32818Y32900D02*
X32532Y33046D01*
G01X56091Y20702D02*
X56303Y20594D01*
G01X53764Y19460D02*
X53552Y19568D01*
G01X48896Y21891D02*
X49108Y21783D01*
G01X47944Y19460D02*
X47733Y19568D01*
G01X38369Y21891D02*
X38580Y21783D01*
G01X60193Y16357D02*
X61596Y15642D01*
G01X51719Y17718D02*
X51845Y17658D01*
G01X51530Y16520D02*
X51404Y16580D01*
G01X41641Y16220D02*
X41515Y16280D01*
G01X36885Y17478D02*
X37011Y17418D01*
G01X36570Y17538D02*
X36696Y17478D01*
G01X33988Y18676D02*
X34114Y18616D01*
G01X36633Y16580D02*
X36507Y16640D01*
G01X42924Y14700D02*
X43169Y14601D01*
G01X41515Y16580D02*
X41672Y16520D01*
G01X33988Y19035D02*
X34145Y18976D01*
G01X37043Y17778D02*
X36885Y17838D01*
G01X40161Y16280D02*
X40318Y16220D01*
G01X36476Y16280D02*
X36633Y16220D01*
G01X34208Y18496D02*
X34271Y18317D01*
G01X40854Y18556D02*
X40759Y18796D01*
G01X39909Y16700D02*
X40003Y16460D01*
G01X37232Y18556D02*
X37137Y18796D01*
G01X42555Y15061D02*
X42455Y15301D01*
G01X41577Y23197D02*
X41615Y23112D01*
G01X53340Y19784D02*
X53234Y20000D01*
G01X49320Y21567D02*
X49425Y21351D01*
G01X47521Y19784D02*
X47415Y20000D01*
G01X34322Y33924D02*
X34179Y34216D01*
G01X38792Y21567D02*
X38898Y21351D01*
G01X32460Y33631D02*
X32532Y33485D01*
G01X41613Y23117D02*
X41653Y23039D01*
G01X58616Y17418D02*
X58553Y17538D01*
G01X53388Y17418D02*
X53325Y17538D01*
G01X42145Y18856D02*
X42271Y18616D01*
G01X41389Y16760D02*
X41452Y16640D01*
G01X40759Y17418D02*
X40696Y17538D01*
G01X36980Y18616D02*
X37043Y18496D01*
G01X60002Y17418D02*
X59939Y17538D01*
G01X58742Y17598D02*
X58648Y17778D01*
G01X54900Y17598D02*
X54806Y17778D01*
G01X54774Y17418D02*
X54711Y17538D01*
G01X53514Y17598D02*
X53420Y17778D01*
G01X50018Y18556D02*
X49955Y18676D01*
G01X40885Y17598D02*
X40791Y17778D01*
G01X37295Y17418D02*
X37169Y17658D01*
G01X36318Y17897D02*
X36444Y17658D01*
G01X36507Y16640D02*
X36413Y16819D01*
G01X34271Y18856D02*
X34397Y18616D01*
G01X54062Y27559D02*
X54744Y26378D01*
G01X36345Y27559D02*
X37027Y26378D01*
G01X55721Y19892D02*
X55880Y19622D01*
G01X51542Y19406D02*
X50219Y21621D01*
G01X50378Y21945D02*
X51700Y19784D01*
G01X57165Y25643D02*
X57006Y25887D01*
G01X57202Y20378D02*
X57308Y20216D01*
G01X53552Y20054D02*
X53658Y19892D01*
G01X49002Y21459D02*
X49108Y21297D01*
G01X47838Y19892D02*
X47733Y20054D01*
G01X34250Y35459D02*
X34107Y35679D01*
G01X34465Y34436D02*
X34608Y34216D01*
G01X32317Y33192D02*
X32174Y33412D01*
G01X38474Y21459D02*
X38580Y21297D01*
G01X50113Y18796D02*
X49987Y18976D01*
G01X37137Y18796D02*
X37011Y18976D01*
G01X57414Y21513D02*
X57255Y21729D01*
G01X46833Y21513D02*
X46674Y21729D01*
G01X41860D02*
X42019Y21513D01*
G01X42555Y15061D02*
X42714Y14858D01*
G01X61670Y27433D02*
X61748Y27334D01*
G01X59813Y18676D02*
X59908Y18556D01*
G01X59939Y17538D02*
X59845Y17658D01*
G01X58427Y18676D02*
X58522Y18556D01*
G01X59341Y16700D02*
X59435Y16580D01*
G01X58553Y17538D02*
X58459Y17658D01*
G01X57955Y16700D02*
X58049Y16580D01*
G01X54585Y18676D02*
X54680Y18556D01*
G01X54711Y17538D02*
X54617Y17658D01*
G01X53199Y18676D02*
X53294Y18556D01*
G01X54113Y16700D02*
X54207Y16580D01*
G01X53325Y17538D02*
X53231Y17658D01*
G01X52727Y16700D02*
X52821Y16580D01*
G01X51845Y17658D02*
X51940Y17538D01*
G01X51404Y16580D02*
X51310Y16700D01*
G01X48727Y18437D02*
X48822Y18317D01*
G01X48412Y16819D02*
X48318Y16939D01*
G01X42082Y18556D02*
X41987Y18676D01*
G01X42113Y17358D02*
X42019Y17478D01*
G01X40570Y18676D02*
X40665Y18556D01*
G01X40696Y17538D02*
X40602Y17658D01*
G01X41389Y16400D02*
X41295Y16520D01*
G01X40098Y16700D02*
X40192Y16580D01*
G01X37011Y17418D02*
X37106Y17299D01*
G01X36602Y17897D02*
X36507Y18017D01*
G01X34114Y18616D02*
X34208Y18496D01*
G01X60002Y18796D02*
X59845Y18976D01*
G01X60034Y17778D02*
X59876Y17957D01*
G01X58616Y18796D02*
X58459Y18976D01*
G01X58648Y17778D02*
X58490Y17957D01*
G01X59246Y16460D02*
X59404Y16280D01*
G01X57861Y16460D02*
X58018Y16280D01*
G01X54774Y18796D02*
X54617Y18976D01*
G01X54806Y17778D02*
X54648Y17957D01*
G01X53388Y18796D02*
X53231Y18976D01*
G01X53420Y17778D02*
X53262Y17957D01*
G01X54018Y16460D02*
X54176Y16280D01*
G01X52034Y17778D02*
X51877Y17957D01*
G01X52632Y16460D02*
X52790Y16280D01*
G01X51215Y16460D02*
X51373Y16280D01*
G01X40759Y18796D02*
X40602Y18976D01*
G01X40791Y17778D02*
X40633Y17957D01*
G01X40003Y16460D02*
X40161Y16280D01*
G01X36318Y16460D02*
X36476Y16280D01*
G01X57244Y26292D02*
X57562Y25968D01*
G01X56991Y21567D02*
X57096Y21459D01*
G01X57520Y20486D02*
X57308Y20702D01*
G01X55880Y20918D02*
X56091Y20702D01*
G01X54980Y21783D02*
X55192Y21567D01*
G01X56197Y19784D02*
X56038Y19946D01*
G01X53552Y19568D02*
X53340Y19784D01*
G01X49108Y21783D02*
X49320Y21567D01*
G01X34250Y36044D02*
X34537Y35752D01*
G01X46516Y21513D02*
X46410Y21621D01*
G01X47733Y19568D02*
X47521Y19784D01*
G01X32532Y33485D02*
X32675Y33339D01*
G01X41702Y21513D02*
X41596Y21621D01*
G01X38580Y21783D02*
X38792Y21567D01*
G01X59041Y31647D02*
X59809Y30916D01*
G01X42019Y18976D02*
X42145Y18856D01*
G01X41452Y16640D02*
X41515Y16580D01*
G01Y16280D02*
X41389Y16400D01*
G01X37169Y17658D02*
X37043Y17778D01*
G01X36444Y17658D02*
X36570Y17538D01*
G01X34145Y18976D02*
X34271Y18856D01*
G01X57255Y21729D02*
X57044Y21891D01*
G01X46674Y21729D02*
X46463Y21891D01*
G01X41649D02*
X41860Y21729D01*
G01X42082Y17658D02*
X42239Y17538D01*
G01X42926Y14698D02*
X42714Y14857D01*
G01X32532Y33046D02*
X32317Y33192D01*
G01X48843Y21567D02*
X49002Y21459D01*
G01X47997Y19784D02*
X47838Y19892D01*
G01X38316Y21567D02*
X38474Y21459D01*
G01X40476Y18736D02*
X40570Y18676D01*
G01X40602Y17658D02*
X40507Y17718D01*
G01X40192Y16580D02*
X40287Y16520D01*
G01X36885Y18676D02*
X36980Y18616D01*
G01X36696Y17838D02*
X36602Y17897D01*
G01X77756Y98425D02*
G03X63976I-6890J0D01*
G01D02*
G03X77756I6890J0D01*
G01X83071Y245079D02*
G03Y231693I0J-6693D01*
G01X77756Y472441D02*
G03X63976I-6890J0D01*
G01D02*
G03X77756I6890J0D01*
G01X57087Y740157D02*
G03X41339I-7874J0D01*
G01D02*
G03X57087I7874J0D01*
G01X22118Y763780D02*
G03X18597Y761603I1J-3937D01*
G01X386149Y763780D02*
X22118D01*
G01X128071Y3937D02*
G03X132008Y0I3937J0D01*
G01X116260D02*
G03X120197Y3937I0J3937D01*
G01X132008Y0D02*
X275709D01*
G01X99477Y1575D02*
G03X100459Y2489I0J985D01*
G01X88517D02*
G03X89499Y1575I982J71D01*
G01X100459Y2489D02*
X101378Y15354D01*
G01X100459Y2489D02*
X88517D01*
G01X99477Y1575D02*
X89499D01*
G01X88517Y2489D02*
X87598Y15354D01*
G01X120197Y3937D02*
Y429331D01*
G01X128071Y59055D02*
Y3937D01*
G01Y59055D02*
G03X120197I-3937J0D01*
G01X128071D02*
G03X120197I-3937J0D01*
G01X79960Y44458D02*
X79967Y44291D01*
G01X79942Y44617D02*
X79960Y44458D01*
G01X79913Y44761D02*
X79942Y44617D01*
G01X79874Y44881D02*
X79913Y44761D01*
G01X79827Y44974D02*
X79874Y44881D01*
G01X79776Y45034D02*
X79827Y44974D01*
G01X109015Y44125D02*
X109009Y44291D01*
G01X109034Y43965D02*
X109015Y44125D01*
G01X109063Y43821D02*
X109034Y43965D01*
G01X109101Y43702D02*
X109063Y43821D01*
G01X109148Y43609D02*
X109101Y43702D01*
G01X109200Y43549D02*
X109148Y43609D01*
G01X81312Y44973D02*
X81259Y45034D01*
G01X81359Y44880D02*
X81312Y44973D01*
G01X81398Y44758D02*
X81359Y44880D01*
G01X81426Y44616D02*
X81398Y44758D01*
G01X81444Y44456D02*
X81426Y44616D01*
G01X81450Y44291D02*
X81444Y44456D01*
G01X107664Y43609D02*
X107717Y43549D01*
G01X107617Y43703D02*
X107664Y43609D01*
G01X107578Y43825D02*
X107617Y43703D01*
G01X107550Y43967D02*
X107578Y43825D01*
G01X107532Y44126D02*
X107550Y43967D01*
G01X107526Y44291D02*
X107532Y44126D01*
G01X79828Y43609D02*
X79776Y43549D01*
G01X79875Y43703D02*
X79828Y43609D01*
G01X79914Y43825D02*
X79875Y43703D01*
G01X79943Y43967D02*
X79914Y43825D01*
G01X79961Y44126D02*
X79943Y43967D01*
G01X79967Y44291D02*
X79961Y44126D01*
G01X109148Y44973D02*
X109200Y45034D01*
G01X109101Y44880D02*
X109148Y44973D01*
G01X109062Y44758D02*
X109101Y44880D01*
G01X109033Y44616D02*
X109062Y44758D01*
G01X109015Y44456D02*
X109033Y44616D01*
G01X109009Y44291D02*
X109015Y44456D01*
G01X81444Y44125D02*
X81450Y44291D01*
G01X81426Y43965D02*
X81444Y44125D01*
G01X81397Y43821D02*
X81426Y43965D01*
G01X81358Y43702D02*
X81397Y43821D01*
G01X81311Y43609D02*
X81358Y43702D01*
G01X81259Y43549D02*
X81311Y43609D01*
G01X107532Y44458D02*
X107526Y44291D01*
G01X107550Y44617D02*
X107532Y44458D01*
G01X107579Y44761D02*
X107550Y44617D01*
G01X107618Y44881D02*
X107579Y44761D01*
G01X107665Y44974D02*
X107618Y44881D01*
G01X107717Y45034D02*
X107665Y44974D01*
G01X107833Y39784D02*
G03X107500Y39252I258J-532D01*
G01X107147Y41201D02*
G03X107480Y41733I-258J532D01*
G01X106693Y25984D02*
G03X107480Y26772I0J787D01*
G01X107833Y39784D02*
G03X109055Y41733I-943J1949D01*
G01X107147Y41201D02*
G03X105925Y39252I943J-1949D01*
G01X106693Y24409D02*
G03X109055Y26772I0J2362D01*
G01X81476Y39252D02*
G03X81143Y39784I-591J0D01*
G01X81496Y41733D02*
G03X81829Y41201I591J0D01*
G01X81496Y26772D02*
G03X82283Y25984I788J0D01*
G01X79921Y41733D02*
G03X81143Y39784I2165J0D01*
G01X83051Y39252D02*
G03X81829Y41201I-2165J0D01*
G01X79921Y26772D02*
G03X82283Y24409I2363J0D01*
G01X85518Y34613D02*
X85656Y34660D01*
G01X85886Y34519D02*
X85702Y34378D01*
G01X109200Y45034D02*
X109999Y45669D01*
G01X108515D02*
X107717Y45034D01*
G01X80461Y42913D02*
X81259Y43549D01*
G01X79776D02*
X78977Y42913D01*
G01X85656Y34660D02*
X85748Y34754D01*
G01X86712Y35176D02*
X86437Y34848D01*
G01Y35223D02*
X86712Y35551D01*
G01X86023Y34707D02*
X85886Y34519D01*
G01X85702Y34378D02*
X85472Y34332D01*
G01X86069Y34848D02*
X86023Y34707D01*
G01X85748Y34754D02*
X85794Y34894D01*
G01X81496Y50197D02*
X79921D01*
G01X109055D02*
X107480D01*
G01X81496Y49016D02*
X79921D01*
G01X109055D02*
X107480D01*
G01X111220Y45669D02*
X107480D01*
G01Y45472D02*
X109055D01*
G01X79921D02*
X81496D01*
G01X79776Y45034D02*
X81259D01*
G01X109200D02*
X107717D01*
G01X81496Y44291D02*
X79921D01*
G01X109055D02*
X107480D01*
G01X79776Y43549D02*
X81259D01*
G01X109200D02*
X107717D01*
G01X111220Y42913D02*
X107480D01*
G01Y41732D02*
X109055D01*
G01X79921D02*
X81496D01*
G01X107480Y40389D02*
X109055D01*
G01X79921D02*
X81496D01*
G01X107480Y39764D02*
X109055D01*
G01X79921D02*
X81496D01*
G01X90551Y38976D02*
X83071D01*
G01X105905D02*
X98425D01*
G01Y38189D02*
X90551D01*
G01X87795Y37992D02*
X83071D01*
G01X105905D02*
X101181D01*
G01X107480Y37795D02*
X109055D01*
G01X79921D02*
X81496D01*
G01X107500Y37402D02*
X81476D01*
G01X79921Y36693D02*
X81496D01*
G01X109055D02*
X107480D01*
G01X87008Y36220D02*
X84252D01*
G01X104724D02*
X101968D01*
G01X87008Y35954D02*
X84252D01*
G01X104724D02*
X101968D01*
G01X86712Y35551D02*
X86988D01*
G01X84370D02*
X85472D01*
G01X85518Y35317D02*
X84645D01*
G01X87008Y35106D02*
X84252D01*
G01X104724D02*
X101968D01*
G01X87008Y35039D02*
X84252D01*
G01X104724D02*
X101968D01*
G01X87008Y34973D02*
X84252D01*
G01X104724D02*
X101968D01*
G01X84645Y34613D02*
X85518D01*
G01X85472Y34332D02*
X84645D01*
G01X87008Y34124D02*
X84252D01*
G01X104724D02*
X101968D01*
G01X87008Y33858D02*
X84252D01*
G01X104724D02*
X101968D01*
G01X81496Y33543D02*
X79921D01*
G01X109055D02*
X107480D01*
G01X86988Y33346D02*
X86712D01*
G01X84645D02*
X84370D01*
G01X107480Y29311D02*
X109055D01*
G01X79921D02*
X81496D01*
G01Y28130D02*
X79921D01*
G01X109055D02*
X107480D01*
G01Y26161D02*
X109055D01*
G01X79921D02*
X81496D01*
G01X106693Y25984D02*
X82283D01*
G01X106693Y24409D02*
X82283D01*
G01X88386Y22835D02*
X83661D01*
G01X105315D02*
X100590D01*
G01X101378Y15354D02*
X87598D01*
G01X111220Y45669D02*
Y42913D01*
G01X111085Y45669D02*
Y42913D01*
G01X111061D02*
Y45669D01*
G01X109646D02*
Y42913D01*
G01X109587Y45669D02*
Y42913D01*
G01X109577D02*
Y45669D01*
G01X109057D02*
Y42913D01*
G01X109055Y50197D02*
Y26161D01*
G01X107560Y45669D02*
Y42913D01*
G01X107500Y39252D02*
Y37402D01*
G01X107480Y26161D02*
Y50197D01*
G01X106693Y37402D02*
Y25984D01*
G01X106102D02*
Y24409D01*
G01X105925Y39252D02*
Y37402D01*
G01X105905D02*
Y38976D01*
G01X105512Y37402D02*
Y25984D01*
G01X105315Y22835D02*
Y24409D01*
G01X104724Y33858D02*
Y36220D01*
G01X104527Y25984D02*
Y24409D01*
G01X104134Y35039D02*
Y33858D01*
G01X102559D02*
Y35039D01*
G01X101968Y36220D02*
Y33858D01*
G01X101771Y25984D02*
Y24409D01*
G01X101378Y15354D02*
Y25984D01*
G01X101181Y37992D02*
Y38976D01*
G01X100984Y25984D02*
Y24409D01*
G01X100590Y22835D02*
Y24409D01*
G01X100393Y37402D02*
Y38976D01*
G01Y25984D02*
Y24409D01*
G01X98425Y38976D02*
Y38189D01*
G01X97441Y25984D02*
Y24409D01*
G01X91535Y25984D02*
Y24409D01*
G01X90551Y38976D02*
Y38189D01*
G01X88582Y25984D02*
Y24409D01*
G01Y38976D02*
Y37402D01*
G01X88386Y22835D02*
Y24409D01*
G01X87992Y25984D02*
Y24409D01*
G01X87795Y37992D02*
Y38976D01*
G01X87598Y15354D02*
Y25984D01*
G01X87204D02*
Y24409D01*
G01X87008Y33858D02*
Y36220D01*
G01X86988Y35551D02*
Y33346D01*
G01X86712D02*
Y35176D01*
G01X86437Y34848D02*
Y35223D01*
G01X86417Y35039D02*
Y33858D01*
G01X86069Y35035D02*
Y34848D01*
G01X85794Y34894D02*
Y35035D01*
G01X84842Y35039D02*
Y33858D01*
G01X84645Y35317D02*
Y34613D01*
G01Y34332D02*
Y33346D01*
G01X84449Y25984D02*
Y24409D01*
G01X84370Y33346D02*
Y35551D01*
G01X84252Y33858D02*
Y36220D01*
G01X83661Y22835D02*
Y24409D01*
G01X83464Y37402D02*
Y25984D01*
G01X83071Y37402D02*
Y38976D01*
G01X83051Y39252D02*
Y37402D01*
G01X82874Y25984D02*
Y24409D01*
G01X82283Y37402D02*
Y25984D01*
G01X81496Y26161D02*
Y50197D01*
G01X81476Y39252D02*
Y37402D01*
G01X81416Y42913D02*
Y45669D01*
G01X79921Y26161D02*
Y50197D01*
G01X79919Y42913D02*
Y45669D01*
G01X79398D02*
Y42913D01*
G01X79388D02*
Y45669D01*
G01X79330D02*
Y42913D01*
G01X85656Y35270D02*
X85518Y35317D01*
G01X85472Y35551D02*
X85702Y35504D01*
G01X86023Y35176D02*
X86069Y35035D01*
G01X85794D02*
X85748Y35176D01*
G01X109999Y42913D02*
X109200Y43549D01*
G01X107717D02*
X108515Y42913D01*
G01X85886Y35364D02*
X86023Y35176D01*
G01X85748D02*
X85656Y35270D01*
G01X81259Y45034D02*
X80461Y45669D01*
G01X78977D02*
X79776Y45034D01*
G01X85702Y35504D02*
X85886Y35364D01*
G01X128071Y98425D02*
Y421457D01*
G01X120197Y98425D02*
G03X128071I3937J0D01*
G01X120197D02*
G03X128071I3937J0D01*
G01X96457Y231693D02*
G03Y245079I0J6693D01*
G01X83071D02*
X96457D01*
G01Y231693D02*
X83071D01*
G01X96654Y413583D02*
G03X83661I-6496J0D01*
G01D02*
G03X96654I6496J0D01*
G01X132008Y425394D02*
G03X128071Y421457I0J-3937D01*
G01X124134Y433268D02*
X283583D01*
G01X124134D02*
G03X120197Y429331I0J-3937D01*
G01X184173Y425394D02*
X132008D01*
G01X158317Y-837696D02*
Y-856633D01*
G01X213480Y37075D02*
G03I-4291J0D01*
G01Y383483D02*
G03I-4291J0D01*
G01X184173Y425394D02*
G03Y433268I0J3937D01*
G01Y425394D02*
G03Y433268I0J3937D01*
G01X150393Y533465D02*
X225197D01*
G01X150393Y608268D02*
Y533465D01*
G01X225197Y608268D02*
X150393D01*
G01X171457Y669291D02*
G03X154921I-8268J0D01*
G01D02*
G03X171457I8268J0D01*
G01X195197Y684856D02*
X195181Y684670D01*
G01X195253Y685044D02*
X195197Y684856D01*
G01X195350Y685228D02*
X195253Y685044D01*
G01X195491Y685394D02*
X195350Y685228D01*
G01X206253Y682536D02*
X206168Y682507D01*
G01X206334Y682569D02*
X206253Y682536D01*
G01X206412Y682607D02*
X206334Y682569D01*
G01X206488Y682649D02*
X206412Y682607D01*
G01X206561Y682696D02*
X206488Y682649D01*
G01X206628Y682745D02*
X206561Y682696D01*
G01X203449Y677307D02*
X203533Y677335D01*
G01X203368Y677274D02*
X203449Y677307D01*
G01X203289Y677236D02*
X203368Y677274D01*
G01X203213Y677193D02*
X203289Y677236D01*
G01X203140Y677146D02*
X203213Y677193D01*
G01X203073Y677098D02*
X203140Y677146D01*
G01X207131Y685510D02*
X207149Y685513D01*
G01X207111Y685500D02*
X207131Y685510D01*
G01X207089Y685483D02*
X207111Y685500D01*
G01X204854Y686044D02*
X205013Y686063D01*
G01X204704Y685987D02*
X204854Y686044D01*
G01X204571Y685895D02*
X204704Y685987D01*
G01X208794Y686044D02*
X208953Y686063D01*
G01X208644Y685987D02*
X208794Y686044D01*
G01X208511Y685895D02*
X208644Y685987D01*
G01X204983Y685510D02*
X205013Y685513D01*
G01X204953Y685500D02*
X204983Y685510D01*
G01X204927Y685483D02*
X204953Y685500D01*
G01X208923Y685510D02*
X208953Y685513D01*
G01X208893Y685500D02*
X208923Y685510D01*
G01X208867Y685483D02*
X208893Y685500D01*
G01X207389Y677307D02*
X207473Y677335D01*
G01X207308Y677274D02*
X207389Y677307D01*
G01X207229Y677236D02*
X207308Y677274D01*
G01X207153Y677193D02*
X207229Y677236D01*
G01X207080Y677146D02*
X207153Y677193D01*
G01X207013Y677098D02*
X207080Y677146D01*
G01X202570Y674333D02*
X202552Y674329D01*
G01X202590Y674343D02*
X202570Y674333D01*
G01X202613Y674359D02*
X202590Y674343D01*
G01X206510Y674333D02*
X206492Y674329D01*
G01X206530Y674343D02*
X206510Y674333D01*
G01X206553Y674359D02*
X206530Y674343D01*
G01X204847Y673799D02*
X204688Y673779D01*
G01X204997Y673856D02*
X204847Y673799D01*
G01X205130Y673947D02*
X204997Y673856D01*
G01X208787Y673799D02*
X208628Y673779D01*
G01X208937Y673856D02*
X208787Y673799D01*
G01X209070Y673947D02*
X208937Y673856D01*
G01X204718Y674333D02*
X204688Y674329D01*
G01X204748Y674343D02*
X204718Y674333D01*
G01X204774Y674359D02*
X204748Y674343D01*
G01X208658Y674333D02*
X208628Y674329D01*
G01X208688Y674343D02*
X208658Y674333D01*
G01X208714Y674359D02*
X208688Y674343D01*
G01X206253Y682255D02*
X206168Y682231D01*
G01X206334Y682282D02*
X206253Y682255D01*
G01X206412Y682313D02*
X206334Y682282D01*
G01X206488Y682347D02*
X206412Y682313D01*
G01X206561Y682386D02*
X206488Y682347D01*
G01X206628Y682426D02*
X206561Y682386D01*
G01X203449Y677588D02*
X203533Y677611D01*
G01X203368Y677561D02*
X203449Y677588D01*
G01X203289Y677530D02*
X203368Y677561D01*
G01X203213Y677495D02*
X203289Y677530D01*
G01X203140Y677456D02*
X203213Y677495D01*
G01X203073Y677417D02*
X203140Y677456D01*
G01X207389Y677588D02*
X207473Y677611D01*
G01X207308Y677561D02*
X207389Y677588D01*
G01X207229Y677530D02*
X207308Y677561D01*
G01X207153Y677495D02*
X207229Y677530D01*
G01X207080Y677456D02*
X207153Y677495D01*
G01X207013Y677417D02*
X207080Y677456D01*
G01X206556Y682242D02*
X206628Y682294D01*
G01X206483Y682195D02*
X206556Y682242D01*
G01X206406Y682153D02*
X206483Y682195D01*
G01X206327Y682115D02*
X206406Y682153D01*
G01X206246Y682083D02*
X206327Y682115D01*
G01X206168Y682056D02*
X206246Y682083D01*
G01X203145Y677601D02*
X203073Y677549D01*
G01X203219Y677648D02*
X203145Y677601D01*
G01X203295Y677690D02*
X203219Y677648D01*
G01X203374Y677727D02*
X203295Y677690D01*
G01X203455Y677760D02*
X203374Y677727D01*
G01X203533Y677786D02*
X203455Y677760D01*
G01X207085Y677601D02*
X207013Y677549D01*
G01X207159Y677648D02*
X207085Y677601D01*
G01X207235Y677690D02*
X207159Y677648D01*
G01X207314Y677727D02*
X207235Y677690D01*
G01X207395Y677760D02*
X207314Y677727D01*
G01X207473Y677786D02*
X207395Y677760D01*
G01X202565Y674296D02*
X202595Y674339D01*
G01X202554Y674265D02*
X202565Y674296D01*
G01X202552Y674254D02*
X202554Y674265D01*
G01X207136Y685547D02*
X207106Y685504D01*
G01X207147Y685578D02*
X207136Y685547D01*
G01X207149Y685589D02*
X207147Y685578D01*
G01X206505Y674296D02*
X206535Y674339D01*
G01X206494Y674265D02*
X206505Y674296D01*
G01X206492Y674254D02*
X206494Y674265D01*
G01X204695Y673780D02*
X204699Y673779D01*
G01X204692Y673780D02*
X204695D01*
G01X204690D02*
X204692D01*
G01X204689Y673781D02*
X204690Y673780D01*
G01X204688Y673782D02*
X204689Y673781D01*
G01X204688Y673783D02*
Y673782D01*
G01X205006Y686063D02*
X205002D01*
G01X205009D02*
X205006D01*
G01X205011Y686062D02*
X205009Y686063D01*
G01X205012Y686061D02*
X205011Y686062D01*
G01X205013Y686060D02*
X205012Y686061D01*
G01X205013Y686059D02*
Y686060D01*
G01X208635Y673780D02*
X208639Y673779D01*
G01X208632Y673780D02*
X208635D01*
G01X208630D02*
X208632D01*
G01X208629Y673781D02*
X208630Y673780D01*
G01X208628Y673782D02*
X208629Y673781D01*
G01X208628Y673783D02*
Y673782D01*
G01X208946Y686063D02*
X208942D01*
G01X208949D02*
X208946D01*
G01X208951Y686062D02*
X208949Y686063D01*
G01X208952Y686061D02*
X208951Y686062D01*
G01X208953Y686060D02*
X208952Y686061D01*
G01X208953Y686059D02*
Y686060D01*
G01X205207Y674265D02*
X205209Y674254D01*
G01X205196Y674296D02*
X205207Y674265D01*
G01X205166Y674339D02*
X205196Y674296D01*
G01X209147Y674265D02*
X209149Y674254D01*
G01X209136Y674296D02*
X209147Y674265D01*
G01X209106Y674339D02*
X209136Y674296D01*
G01X204494Y685578D02*
X204492Y685589D01*
G01X204505Y685547D02*
X204494Y685578D01*
G01X204535Y685504D02*
X204505Y685547D01*
G01X195197Y674988D02*
X195181Y675172D01*
G01X195252Y674799D02*
X195197Y674988D01*
G01X195350Y674615D02*
X195252Y674799D01*
G01X195491Y674448D02*
X195350Y674615D01*
G01X208434Y685578D02*
X208432Y685589D01*
G01X208445Y685547D02*
X208434Y685578D01*
G01X208475Y685504D02*
X208445Y685547D01*
G01X204692Y674330D02*
X204699Y674329D01*
G01X204689Y674331D02*
X204692Y674330D01*
G01X204688Y674332D02*
X204689Y674331D01*
G01X208632Y674330D02*
X208639Y674329D01*
G01X208629Y674331D02*
X208632Y674330D01*
G01X208628Y674332D02*
X208629Y674331D01*
G01X205009Y685513D02*
X205002D01*
G01X205012Y685512D02*
X205009Y685513D01*
G01X205013Y685511D02*
X205012Y685512D01*
G01X208949Y685513D02*
X208942D01*
G01X208952Y685512D02*
X208949Y685513D01*
G01X208953Y685511D02*
X208952Y685512D01*
G01X204323Y677759D02*
X204242Y677786D01*
G01X204400Y677728D02*
X204323Y677759D01*
G01X204479Y677691D02*
X204400Y677728D01*
G01X204551Y677651D02*
X204479Y677691D01*
G01X204621Y677607D02*
X204551Y677651D01*
G01X204688Y677559D02*
X204621Y677607D01*
G01X208263Y677759D02*
X208182Y677786D01*
G01X208340Y677728D02*
X208263Y677759D01*
G01X208419Y677691D02*
X208340Y677728D01*
G01X208491Y677651D02*
X208419Y677691D01*
G01X208561Y677607D02*
X208491Y677651D01*
G01X208628Y677559D02*
X208561Y677607D01*
G01X205378Y682084D02*
X205459Y682056D01*
G01X205301Y682115D02*
X205378Y682084D01*
G01X205222Y682152D02*
X205301Y682115D01*
G01X205150Y682192D02*
X205222Y682152D01*
G01X205080Y682235D02*
X205150Y682192D01*
G01X205013Y682283D02*
X205080Y682235D01*
G01X209241Y682115D02*
X209318Y682084D01*
G01X209162Y682152D02*
X209241Y682115D01*
G01X209090Y682192D02*
X209162Y682152D01*
G01X209020Y682235D02*
X209090Y682192D01*
G01X208953Y682283D02*
X209020Y682235D01*
G01X195809Y673932D02*
X195954Y673921D01*
G01X195679Y673942D02*
X195809Y673932D01*
G01X195578Y673952D02*
X195679Y673942D01*
G01X195513Y673962D02*
X195578Y673952D01*
G01X195491Y673973D02*
X195513Y673962D01*
G01X204323Y674834D02*
X204242Y674857D01*
G01X204400Y674809D02*
X204323Y674834D01*
G01X204479Y674779D02*
X204400Y674809D01*
G01X204551Y674746D02*
X204479Y674779D01*
G01X204621Y674710D02*
X204551Y674746D01*
G01X204688Y674671D02*
X204621Y674710D01*
G01X208263Y674834D02*
X208182Y674857D01*
G01X208340Y674809D02*
X208263Y674834D01*
G01X208419Y674779D02*
X208340Y674809D01*
G01X208491Y674746D02*
X208419Y674779D01*
G01X208561Y674710D02*
X208491Y674746D01*
G01X208628Y674671D02*
X208561Y674710D01*
G01X205378Y685008D02*
X205459Y684986D01*
G01X205301Y685033D02*
X205378Y685008D01*
G01X205222Y685064D02*
X205301Y685033D01*
G01X205150Y685096D02*
X205222Y685064D01*
G01X205080Y685132D02*
X205150Y685096D01*
G01X205013Y685171D02*
X205080Y685132D01*
G01X209241Y685033D02*
X209318Y685008D01*
G01X209162Y685064D02*
X209241Y685033D01*
G01X209090Y685096D02*
X209162Y685064D01*
G01X209020Y685132D02*
X209090Y685096D01*
G01X208953Y685171D02*
X209020Y685132D01*
G01X195422Y673938D02*
X195914Y673921D01*
G01X195221Y673947D02*
X195422Y673938D01*
G01X195069Y673956D02*
X195221Y673947D01*
G01X194973Y673964D02*
X195069Y673956D01*
G01X194941Y673973D02*
X194973Y673964D01*
G01X204618Y677466D02*
X204688Y677426D01*
G01X204548Y677502D02*
X204618Y677466D01*
G01X204472Y677536D02*
X204548Y677502D01*
G01X204397Y677565D02*
X204472Y677536D01*
G01X204320Y677590D02*
X204397Y677565D01*
G01X204242Y677611D02*
X204320Y677590D01*
G01X208558Y677466D02*
X208628Y677426D01*
G01X208488Y677502D02*
X208558Y677466D01*
G01X208412Y677536D02*
X208488Y677502D01*
G01X208337Y677565D02*
X208412Y677536D01*
G01X208260Y677590D02*
X208337Y677565D01*
G01X208182Y677611D02*
X208260Y677590D01*
G01X205083Y682376D02*
X205013Y682417D01*
G01X205153Y682341D02*
X205083Y682376D01*
G01X205229Y682306D02*
X205153Y682341D01*
G01X205304Y682278D02*
X205229Y682306D01*
G01X205381Y682253D02*
X205304Y682278D01*
G01X205459Y682231D02*
X205381Y682253D01*
G01X209023Y682376D02*
X208953Y682417D01*
G01X209093Y682341D02*
X209023Y682376D01*
G01X209169Y682306D02*
X209093Y682341D01*
G01X209244Y682278D02*
X209169Y682306D01*
G01X209321Y682253D02*
X209244Y682278D01*
G01X204618Y677158D02*
X204688Y677108D01*
G01X204548Y677202D02*
X204618Y677158D01*
G01X204472Y677243D02*
X204548Y677202D01*
G01X204397Y677278D02*
X204472Y677243D01*
G01X204320Y677309D02*
X204397Y677278D01*
G01X204242Y677335D02*
X204320Y677309D01*
G01X208558Y677158D02*
X208628Y677108D01*
G01X208488Y677202D02*
X208558Y677158D01*
G01X208412Y677243D02*
X208488Y677202D01*
G01X208337Y677278D02*
X208412Y677243D01*
G01X208260Y677309D02*
X208337Y677278D01*
G01X208182Y677335D02*
X208260Y677309D01*
G01X205083Y682685D02*
X205013Y682734D01*
G01X205153Y682641D02*
X205083Y682685D01*
G01X205229Y682599D02*
X205153Y682641D01*
G01X205304Y682564D02*
X205229Y682599D01*
G01X205381Y682533D02*
X205304Y682564D01*
G01X205459Y682507D02*
X205381Y682533D01*
G01X209023Y682685D02*
X208953Y682734D01*
G01X209093Y682641D02*
X209023Y682685D01*
G01X209169Y682599D02*
X209093Y682641D01*
G01X209244Y682564D02*
X209169Y682599D01*
G01X209321Y682533D02*
X209244Y682564D01*
G01X203013Y674343D02*
X202987Y674359D01*
G01X203043Y674333D02*
X203013Y674343D01*
G01X203073Y674329D02*
X203043Y674333D01*
G01X206953Y674343D02*
X206927Y674359D01*
G01X206983Y674333D02*
X206953Y674343D01*
G01X207013Y674329D02*
X206983Y674333D01*
G01X206688Y685500D02*
X206714Y685483D01*
G01X206658Y685510D02*
X206688Y685500D01*
G01X206628Y685513D02*
X206658Y685510D01*
G01X202764Y673856D02*
X202631Y673947D01*
G01X202914Y673799D02*
X202764Y673856D01*
G01X203073Y673779D02*
X202914Y673799D01*
G01X206704Y673856D02*
X206571Y673947D01*
G01X206854Y673799D02*
X206704Y673856D01*
G01X207013Y673779D02*
X206854Y673799D01*
G01X206938Y685987D02*
X207070Y685895D01*
G01X206787Y686044D02*
X206938Y685987D01*
G01X206628Y686063D02*
X206787Y686044D01*
G01X205171Y674343D02*
X205149Y674359D01*
G01X205191Y674333D02*
X205171Y674343D01*
G01X205209Y674329D02*
X205191Y674333D01*
G01X209111Y674343D02*
X209089Y674359D01*
G01X209131Y674333D02*
X209111Y674343D01*
G01X209149Y674329D02*
X209131Y674333D01*
G01X204530Y685500D02*
X204553Y685483D01*
G01X204510Y685510D02*
X204530Y685500D01*
G01X204492Y685513D02*
X204510Y685510D01*
G01X208470Y685500D02*
X208493Y685483D01*
G01X208450Y685510D02*
X208470Y685500D01*
G01X208432Y685513D02*
X208450Y685510D01*
G01X207012Y674331D02*
X207013Y674332D01*
G01X207009Y674330D02*
X207012Y674331D01*
G01X207002Y674329D02*
X207009Y674330D01*
G01X203072Y674331D02*
X203073Y674332D01*
G01X203069Y674330D02*
X203072Y674331D01*
G01X203062Y674329D02*
X203069Y674330D01*
G01X206629Y685512D02*
X206628Y685511D01*
G01X206632Y685513D02*
X206629Y685512D01*
G01X206639Y685513D02*
X206632D01*
G01X194973Y685878D02*
X194941Y685870D01*
G01X195069Y685887D02*
X194973Y685878D01*
G01X195221Y685896D02*
X195069Y685887D01*
G01X195422Y685904D02*
X195221Y685896D01*
G01X207013Y673782D02*
Y673783D01*
G01X207012Y673781D02*
X207013Y673782D01*
G01X207011Y673780D02*
X207012Y673781D01*
G01X207008Y673780D02*
X207011D01*
G01X207006D02*
X207008D01*
G01X207002Y673779D02*
X207006Y673780D01*
G01X203073Y673782D02*
Y673783D01*
G01X203072Y673781D02*
X203073Y673782D01*
G01X203071Y673780D02*
X203072Y673781D01*
G01X203068Y673780D02*
X203071D01*
G01X203066D02*
X203068D01*
G01X203062Y673779D02*
X203066Y673780D01*
G01X206628Y686061D02*
Y686059D01*
G01X206629Y686061D02*
X206628D01*
G01X206630Y686062D02*
X206629Y686061D01*
G01X206633Y686063D02*
X206630Y686062D01*
G01X206635Y686063D02*
X206633D01*
G01X206639D02*
X206635D01*
G01X195977Y673918D02*
X195991Y673917D01*
G01X195965Y673919D02*
X195977Y673918D01*
G01X195951Y673920D02*
X195965Y673919D01*
G01X195938Y673921D02*
X195951Y673920D01*
G01X195926Y673921D02*
X195938D01*
G01X195914D02*
X195926D01*
G01X195984Y673918D02*
X195991Y673917D01*
G01X195978Y673919D02*
X195984Y673918D01*
G01X195972Y673920D02*
X195978Y673919D01*
G01X195966Y673921D02*
X195972Y673920D01*
G01X195960Y673921D02*
X195966D01*
G01X195954D02*
X195960D01*
G01X207085Y674705D02*
X207013Y674662D01*
G01X207159Y674743D02*
X207085Y674705D01*
G01X207235Y674778D02*
X207159Y674743D01*
G01X207314Y674809D02*
X207235Y674778D01*
G01X207395Y674835D02*
X207314Y674809D01*
G01X207473Y674857D02*
X207395Y674835D01*
G01X203145Y674705D02*
X203073Y674662D01*
G01X203219Y674743D02*
X203145Y674705D01*
G01X203295Y674778D02*
X203219Y674743D01*
G01X203374Y674809D02*
X203295Y674778D01*
G01X203455Y674835D02*
X203374Y674809D01*
G01X203533Y674857D02*
X203455Y674835D01*
G01X195960Y685921D02*
X195954D01*
G01X195966Y685922D02*
X195960Y685921D01*
G01X195973Y685922D02*
X195966D01*
G01X195979Y685923D02*
X195973Y685922D01*
G01X195985Y685924D02*
X195979Y685923D01*
G01X195991Y685925D02*
X195985Y685924D01*
G01X195927Y685921D02*
X195914D01*
G01X195940Y685922D02*
X195927Y685921D01*
G01X195954Y685922D02*
X195940D01*
G01X195966Y685923D02*
X195954Y685922D01*
G01X195978Y685924D02*
X195966Y685923D01*
G01X195991Y685925D02*
X195978Y685924D01*
G01X195513Y685880D02*
X195491Y685870D01*
G01X195578Y685890D02*
X195513Y685880D01*
G01X195679Y685901D02*
X195578Y685890D01*
G01X195808Y685911D02*
X195679Y685901D01*
G01X195954Y685921D02*
X195808Y685911D01*
G01X206556Y685137D02*
X206628Y685180D01*
G01X206483Y685099D02*
X206556Y685137D01*
G01X206406Y685065D02*
X206483Y685099D01*
G01X206327Y685034D02*
X206406Y685065D01*
G01X206246Y685007D02*
X206327Y685034D01*
G01X206168Y684986D02*
X206246Y685007D01*
G01X206173Y682005D02*
G03X206638Y682254I-425J1352D01*
G01X205003Y682243D02*
G03X205454Y682005I876J1114D01*
G01X208943Y682243D02*
G03X209394Y682005I876J1114D01*
G01X208626Y671071D02*
G03X208114Y671583I-512J0D01*
G01X207614D02*
G03X207102Y671071I0J-512D01*
G01X204702D02*
G03X204191Y671583I-512J0D01*
G01X207468Y677838D02*
G03X207003Y677588I427J-1351D01*
G01X208638Y677600D02*
G03X208187Y677838I-876J-1114D01*
G01X195993Y685911D02*
G03X195941Y686536I-52J310D01*
G01X193526Y685241D02*
G03X194017Y684980I315J0D01*
G01X203141Y684251D02*
G03I-1250J0D01*
G01X195941Y673306D02*
G03X195993Y673932I0J315D01*
G01X194017Y674862D02*
G03X193526Y674601I-176J-261D01*
G01X203691Y671583D02*
G03X203179Y671071I0J-512D01*
G01X199338Y678016D02*
G03X200000Y677264I252J-445D01*
G01X203528Y677838D02*
G03X203063Y677588I427J-1351D01*
G01X204698Y677600D02*
G03X204247Y677838I-876J-1114D01*
G01X169094Y669291D02*
G03I-5905J0D01*
G01X169606D02*
G03I-6417J0D01*
G01X169685D02*
G03I-6496J0D01*
G01X170551D02*
G03I-7362J0D01*
G01X171063D02*
G03I-7874J0D01*
G01D02*
G03I-7874J0D01*
G01X171456D02*
G03I-8267J0D01*
G01X172519D02*
G03I-9330J0D01*
G01X173031D02*
G03I-9842J0D01*
G01X207171Y686062D02*
X207149Y686063D01*
G01X206471Y673780D02*
X206492Y673779D01*
G01X202531Y673780D02*
X202552Y673779D01*
G01X206628Y691113D02*
X205013D01*
G01X210568D02*
X208953D01*
G01X199441Y690421D02*
X195941D01*
G01X214751Y689771D02*
X193541D01*
G01X214751Y688171D02*
X193541D01*
G01X214751Y687018D02*
X203791D01*
G01X206628Y686963D02*
X205013D01*
G01X210568D02*
X208953D01*
G01X207171Y686821D02*
X204471D01*
G01X211111D02*
X208411D01*
G01X206628Y686613D02*
X205013D01*
G01X210568D02*
X208953D01*
G01X203791Y686271D02*
X214751D01*
G01X206628Y686111D02*
X205013D01*
G01X210568D02*
X208953D01*
G01X203791Y686071D02*
X214751D01*
G01X207149Y686063D02*
X204492D01*
G01X211089D02*
X208432D01*
G01X195914Y685921D02*
X195954D01*
G01X207070Y685895D02*
X207171D01*
G01X208411D02*
X208511D01*
G01X204471D02*
X204571D01*
G01X195491Y685870D02*
X194941D01*
G01Y685669D02*
X195491D01*
G01X207149Y685513D02*
X204492D01*
G01X211089D02*
X208432D01*
G01X206714Y685483D02*
X207089D01*
G01X208493D02*
X208867D01*
G01X204553D02*
X204927D01*
G01X206628Y685420D02*
X205013D01*
G01X210568D02*
X208953D01*
G01X206771Y685371D02*
X208811D01*
G01X203791D02*
X204871D01*
G01Y685157D02*
X203791D01*
G01X208811D02*
X206771D01*
G01X205459Y684986D02*
X206168D01*
G01X195181Y684670D02*
X194941D01*
G01X206628Y683646D02*
X205013D01*
G01X210568D02*
X208953D01*
G01X204871Y683571D02*
X201369D01*
G01X208811D02*
X206771D01*
G01X206628Y683116D02*
X205013D01*
G01X210568D02*
X208953D01*
G01X206628Y682666D02*
X205013D01*
G01X210568D02*
X208953D01*
G01Y682587D02*
X210568D01*
G01X205013D02*
X206628D01*
G01X204871Y682571D02*
X201005D01*
G01X206628D02*
X205013D01*
G01X210568D02*
X208953D01*
G01X208811D02*
X206771D01*
G01X208953Y682507D02*
X209399D01*
G01X206168D02*
X206628D01*
G01X205013D02*
X205459D01*
G01X196441Y682421D02*
X194941D01*
G01X206168Y682231D02*
X205459D01*
G01X194491Y682171D02*
X194941D01*
G01X195491D02*
X194941D01*
G01X205459Y682056D02*
X206168D01*
G01Y682021D02*
X205459D01*
G01X203791Y681971D02*
X199991D01*
G01X206771Y681121D02*
X204871D01*
G01X210711D02*
X208811D01*
G01X204831Y678721D02*
X202931D01*
G01X208771D02*
X206871D01*
G01X207473Y677821D02*
X208182D01*
G01X203533D02*
X204242D01*
G01Y677786D02*
X203533D01*
G01X208182D02*
X207473D01*
G01X194941Y677671D02*
X194491D01*
G01X195491D02*
X194941D01*
G01X207473Y677611D02*
X208182D01*
G01X203533D02*
X204242D01*
G01X196441Y677421D02*
X194941D01*
G01X203533Y677335D02*
X203073D01*
G01X204688D02*
X204242D01*
G01X207473D02*
X207013D01*
G01X208628D02*
X208182D01*
G01X207013Y677271D02*
X208628D01*
G01X203073D02*
X204688D01*
G01X202931D02*
X199991D01*
G01X206871D02*
X204831D01*
G01X210811D02*
X208771D01*
G01X204688Y677256D02*
X203073D01*
G01X208628D02*
X207013D01*
G01Y677177D02*
X208628D01*
G01X203073D02*
X204688D01*
G01X207013Y676727D02*
X208628D01*
G01X203073D02*
X204688D01*
G01X208771Y676271D02*
X210811D01*
G01X204831D02*
X206871D01*
G01X198712D02*
X202931D01*
G01X207013Y676196D02*
X208628D01*
G01X203073D02*
X204688D01*
G01X194941Y675172D02*
X195181D01*
G01X204242Y674857D02*
X203533D01*
G01X208182D02*
X207473D01*
G01X208771Y674686D02*
X210811D01*
G01X204831D02*
X206871D01*
G01X199991D02*
X202931D01*
G01Y674471D02*
X199991D01*
G01X206871D02*
X204831D01*
G01X210811D02*
X208771D01*
G01X207013Y674422D02*
X208628D01*
G01X203073D02*
X204688D01*
G01X202987Y674359D02*
X202613D01*
G01X205149D02*
X204774D01*
G01X209089D02*
X208714D01*
G01X206927D02*
X206553D01*
G01X205209Y674329D02*
X202552D01*
G01X209149D02*
X206492D01*
G01X195491Y674174D02*
X194941D01*
G01Y673973D02*
X195491D01*
G01X202631Y673947D02*
X202531D01*
G01X205231D02*
X205130D01*
G01X209171D02*
X209070D01*
G01X206571D02*
X206471D01*
G01X195954Y673921D02*
X195914D01*
G01X205209Y673779D02*
X202552D01*
G01X209149D02*
X206492D01*
G01X199991Y673771D02*
X214751D01*
G01X207013Y673732D02*
X208628D01*
G01X203073D02*
X204688D01*
G01X214751Y673571D02*
X199991D01*
G01X207013Y673229D02*
X208628D01*
G01X203073D02*
X204688D01*
G01X206471Y673021D02*
X209171D01*
G01X202531D02*
X205231D01*
G01X207013Y672879D02*
X208628D01*
G01X203073D02*
X204688D01*
G01X199991Y672825D02*
X214751D01*
G01X193541Y671671D02*
X214751D01*
G01X204191Y671571D02*
X203691D01*
G01X208114D02*
X207614D01*
G01X203191Y670071D02*
X193541D01*
G01X207114D02*
X204691D01*
G01X211038D02*
X208614D01*
G01X199441Y669421D02*
X195941D01*
G01X204688Y668729D02*
X203073D01*
G01X208628D02*
X207013D01*
G01X204492Y686063D02*
X204471Y686062D01*
G01X208432Y686063D02*
X208411Y686062D01*
G01X205209Y673779D02*
X205231Y673780D01*
G01X209149Y673779D02*
X209171Y673780D01*
G01X195914Y685921D02*
X195422Y685904D01*
G01X194008Y674850D02*
X195491Y673850D01*
G01X207171Y685810D02*
X207070Y685895D01*
G01X206714Y685483D02*
X206845Y685371D01*
G01X206927Y674359D02*
X206796Y674471D01*
G01X206471Y674033D02*
X206571Y673947D01*
G01X202987Y674359D02*
X202856Y674471D01*
G01X202531Y674033D02*
X202631Y673947D01*
G01X208511Y685895D02*
X208867Y685483D01*
G01X208493D02*
X208411Y685578D01*
G01X204571Y685895D02*
X204927Y685483D01*
G01X204553D02*
X204471Y685578D01*
G01X209089Y674359D02*
X209171Y674264D01*
G01X209070Y673947D02*
X208714Y674359D01*
G01X205149D02*
X205231Y674264D01*
G01X205130Y673947D02*
X204774Y674359D01*
G01X207089Y685483D02*
X207106Y685371D01*
G01X206553Y674359D02*
X206535Y674471D01*
G01X202613Y674359D02*
X202595Y674471D01*
G01X209171D02*
Y673021D01*
G01X209149Y673779D02*
Y674329D01*
G01X209021Y673779D02*
Y674329D01*
G01X208953Y682257D02*
Y691113D01*
G01X208942Y686063D02*
Y685513D01*
G01X208913Y686063D02*
Y685513D01*
G01X208876Y674329D02*
Y673779D01*
G01X208811Y685371D02*
Y681121D01*
G01X208771Y678721D02*
Y674471D01*
G01X208705Y685513D02*
Y686063D01*
G01X208668Y673779D02*
Y674329D01*
G01X208639Y673779D02*
Y674329D01*
G01X208628Y677586D02*
Y668729D01*
G01X208614Y670071D02*
Y671071D01*
G01X208561Y686063D02*
Y685513D01*
G01X208432Y686063D02*
Y685513D01*
G01X208411Y686821D02*
Y685371D01*
G01X208182Y677820D02*
Y674857D01*
G01X207473D02*
Y677820D01*
G01X207171Y685371D02*
Y686821D01*
G01X207149Y685513D02*
Y686063D01*
G01X207114Y671071D02*
Y670071D01*
G01X207021Y685513D02*
Y686063D01*
G01X207013Y668729D02*
Y677574D01*
G01X207002Y674329D02*
Y673779D01*
G01X206973Y674329D02*
Y673779D01*
G01X206876Y686063D02*
Y685513D01*
G01X206871Y678721D02*
Y674471D01*
G01X206771Y685371D02*
Y681121D01*
G01X206765Y673779D02*
Y674329D01*
G01X206668Y685513D02*
Y686063D01*
G01X206639Y685513D02*
Y686063D01*
G01X206628Y682268D02*
Y691113D01*
G01X206621Y674329D02*
Y673779D01*
G01X206492Y674329D02*
Y673779D01*
G01X206471Y674471D02*
Y673021D01*
G01X206168Y684986D02*
Y682022D01*
G01X205459D02*
Y684986D01*
G01X205231Y674471D02*
Y673021D01*
G01X205209Y673779D02*
Y674329D01*
G01X205081Y673779D02*
Y674329D01*
G01X205013Y682257D02*
Y691113D01*
G01X205002Y686063D02*
Y685513D01*
G01X204973Y686063D02*
Y685513D01*
G01X204936Y674329D02*
Y673779D01*
G01X204871Y685371D02*
Y681121D01*
G01X204831Y678721D02*
Y674471D01*
G01X204765Y685513D02*
Y686063D01*
G01X204728Y673779D02*
Y674329D01*
G01X204699Y673779D02*
Y674329D01*
G01X204691Y670071D02*
Y671071D01*
G01X204688Y677586D02*
Y668729D01*
G01X204621Y686063D02*
Y685513D01*
G01X204492Y686063D02*
Y685513D01*
G01X204471Y686821D02*
Y685371D01*
G01X204242Y677820D02*
Y674857D01*
G01X203791Y688171D02*
Y686271D01*
G01Y686071D02*
Y681971D01*
G01X203533Y674857D02*
Y677820D01*
G01X203191Y671071D02*
Y670071D01*
G01X203073Y668729D02*
Y677574D01*
G01X203062Y674329D02*
Y673779D01*
G01X203033Y674329D02*
Y673779D01*
G01X202931Y678721D02*
Y674471D01*
G01X202825Y673779D02*
Y674329D01*
G01X202681D02*
Y673779D01*
G01X202552Y674329D02*
Y673779D01*
G01X202531Y674471D02*
Y673021D01*
G01X199991Y688171D02*
Y671671D01*
G01X199441Y669421D02*
Y690421D01*
G01X196501Y688171D02*
Y671671D01*
G01X196441Y682421D02*
Y677421D01*
G01X196201Y670071D02*
Y689771D01*
G01X195991Y682421D02*
Y685925D01*
G01Y673917D02*
Y677421D01*
G01X195941Y673321D02*
Y669421D01*
G01Y690421D02*
Y686521D01*
G01X195491Y685992D02*
Y673850D01*
G01X195343Y677671D02*
Y682171D01*
G01X195181Y677671D02*
Y675172D01*
G01Y684670D02*
Y682171D01*
G01X195122Y677671D02*
Y682171D01*
G01X194941Y685870D02*
Y673973D01*
G01X194867Y677671D02*
Y682171D01*
G01X194698Y677671D02*
Y682171D01*
G01X194491Y677671D02*
Y682171D01*
G01X193541Y674601D02*
Y670071D01*
G01Y689771D02*
Y685241D01*
G01X209106Y674471D02*
X209089Y674359D01*
G01X208475Y685371D02*
X208493Y685483D01*
G01X205166Y674471D02*
X205149Y674359D01*
G01X204535Y685371D02*
X204553Y685483D01*
G01X199122Y677397D02*
X198712Y676271D01*
G01X201369Y683571D02*
X199343Y678006D01*
G01X209070Y673947D02*
X209171Y674033D01*
G01X208714Y674359D02*
X208845Y674471D01*
G01X205130Y673947D02*
X205231Y674033D01*
G01X204774Y674359D02*
X204905Y674471D01*
G01X206927Y674359D02*
X206571Y673947D01*
G01X206471Y674264D02*
X206553Y674359D01*
G01X202987D02*
X202631Y673947D01*
G01X202531Y674264D02*
X202613Y674359D01*
G01X207171Y685578D02*
X207089Y685483D01*
G01X195491Y685992D02*
X194008Y684992D01*
G01X208867Y685483D02*
X208736Y685371D01*
G01X208511Y685895D02*
X208411Y685810D01*
G01X204927Y685483D02*
X204796Y685371D01*
G01X204571Y685895D02*
X204471Y685810D01*
G01X206714Y685483D02*
X207070Y685895D01*
G01X158317Y1340060D02*
Y1321123D01*
G01X204093D02*
X711967D01*
G01X247399Y-738063D02*
Y-542541D01*
G01X223543Y425394D02*
X275709D01*
G01X223543Y433268D02*
G03Y425394I0J-3937D01*
G01Y433268D02*
G03Y425394I0J-3937D01*
G01X225197Y533465D02*
Y608268D01*
G01X224728Y608907D02*
X224811Y608924D01*
G01Y608842D02*
X224728Y608825D01*
G01X224409Y610236D02*
X225197D01*
G01X225113Y610138D02*
X224862D01*
G01X224761D02*
X224409D01*
G01X224962Y609728D02*
X225012D01*
G01Y609629D02*
X224945D01*
G01X225113Y609498D02*
X225197D01*
G01X224409D02*
X224945D01*
G01X225197Y609416D02*
X225113D01*
G01X224945D02*
X224409D01*
G01Y609285D02*
X224945D01*
G01Y609203D02*
X224862D01*
G01X224795D02*
X224409D01*
G01Y608907D02*
X224728D01*
G01Y608825D02*
X224409D01*
G01X224945Y608694D02*
X225079D01*
G01X224409Y608596D02*
X225063D01*
G01X225197Y608497D02*
X224409D01*
G01X224912Y609744D02*
X224962Y609728D01*
G01X224945Y609629D02*
X224895Y609646D01*
G01D02*
X224828Y609695D01*
G01X225079Y608694D02*
X225197Y608596D01*
G01X225063D02*
X224945Y608694D01*
G01X224878Y609777D02*
X224912Y609744D01*
G01X224862Y609203D02*
X224895Y609170D01*
G01X224828D02*
X224795Y609203D01*
G01X224895Y609170D02*
X224929Y609121D01*
G01X224862D02*
X224828Y609170D01*
G01Y609695D02*
X224778Y609760D01*
G01X224862Y609826D02*
X224878Y609777D01*
G01X224778Y609760D02*
X224761Y609843D01*
G01X224929Y609121D02*
X224945Y609055D01*
G01X224878D02*
X224862Y609121D01*
G01X225197Y608596D02*
Y608497D01*
G01Y609498D02*
Y609416D01*
G01Y610236D02*
Y609843D01*
G01X225113Y609826D02*
Y610138D01*
G01Y609416D02*
Y609498D01*
G01X224945Y609285D02*
Y609203D01*
G01Y609055D02*
Y608990D01*
G01Y609498D02*
Y609416D01*
G01X224862Y610138D02*
Y609826D01*
G01X224761Y609843D02*
Y610138D01*
G01X224409D02*
Y610236D01*
G01Y608497D02*
Y608596D01*
G01Y609203D02*
Y609285D01*
G01Y608825D02*
Y608907D01*
G01Y609416D02*
Y609498D01*
G01X224862Y608858D02*
X224811Y608842D01*
G01X225063Y609646D02*
X225012Y609629D01*
G01Y609728D02*
X225063Y609744D01*
G01X224945Y608990D02*
X224929Y608940D01*
G01X225096Y609777D02*
X225113Y609826D01*
G01X224862Y608990D02*
X224878Y609055D01*
G01X225197Y609843D02*
X225180Y609760D01*
G01X225130Y609695D02*
X225063Y609646D01*
G01X224895Y608891D02*
X224862Y608858D01*
G01X224811Y608924D02*
X224845Y608957D01*
G01X225063Y609744D02*
X225096Y609777D01*
G01X225180Y609760D02*
X225130Y609695D01*
G01X224929Y608940D02*
X224895Y608891D01*
G01X224845Y608957D02*
X224862Y608990D01*
G01X210193Y682536D02*
X210108Y682507D01*
G01X210274Y682569D02*
X210193Y682536D01*
G01X210352Y682607D02*
X210274Y682569D01*
G01X210428Y682649D02*
X210352Y682607D01*
G01X210501Y682696D02*
X210428Y682649D01*
G01X210568Y682745D02*
X210501Y682696D01*
G01X211071Y685510D02*
X211089Y685513D01*
G01X211051Y685500D02*
X211071Y685510D01*
G01X211029Y685483D02*
X211051Y685500D01*
G01X215011Y685510D02*
X215029Y685513D01*
G01X214991Y685500D02*
X215011Y685510D01*
G01X214969Y685483D02*
X214991Y685500D01*
G01X212734Y686044D02*
X212893Y686063D01*
G01X212584Y685987D02*
X212734Y686044D01*
G01X212451Y685895D02*
X212584Y685987D01*
G01X232324Y674987D02*
X232341Y675172D01*
G01X232268Y674799D02*
X232324Y674987D01*
G01X232171Y674615D02*
X232268Y674799D01*
G01X232031Y674448D02*
X232171Y674615D01*
G01X214133Y682536D02*
X214048Y682507D01*
G01X214214Y682569D02*
X214133Y682536D01*
G01X214292Y682607D02*
X214214Y682569D01*
G01X214368Y682649D02*
X214292Y682607D01*
G01X214441Y682696D02*
X214368Y682649D01*
G01X214508Y682745D02*
X214441Y682696D01*
G01X218073Y682536D02*
X217988Y682507D01*
G01X218154Y682569D02*
X218073Y682536D01*
G01X218232Y682607D02*
X218154Y682569D01*
G01X218308Y682649D02*
X218232Y682607D01*
G01X218381Y682696D02*
X218308Y682649D01*
G01X218448Y682745D02*
X218381Y682696D01*
G01X211329Y677307D02*
X211413Y677335D01*
G01X211248Y677274D02*
X211329Y677307D01*
G01X211169Y677236D02*
X211248Y677274D01*
G01X211093Y677193D02*
X211169Y677236D01*
G01X211020Y677146D02*
X211093Y677193D01*
G01X210953Y677098D02*
X211020Y677146D01*
G01X222013Y682536D02*
X221928Y682507D01*
G01X222094Y682569D02*
X222013Y682536D01*
G01X222172Y682607D02*
X222094Y682569D01*
G01X222248Y682649D02*
X222172Y682607D01*
G01X222321Y682696D02*
X222248Y682649D01*
G01X222388Y682745D02*
X222321Y682696D01*
G01X215269Y677307D02*
X215353Y677335D01*
G01X215188Y677274D02*
X215269Y677307D01*
G01X215109Y677236D02*
X215188Y677274D01*
G01X215033Y677193D02*
X215109Y677236D01*
G01X214960Y677146D02*
X215033Y677193D01*
G01X214893Y677098D02*
X214960Y677146D01*
G01X219209Y677307D02*
X219293Y677335D01*
G01X219128Y677274D02*
X219209Y677307D01*
G01X219049Y677236D02*
X219128Y677274D01*
G01X218973Y677193D02*
X219049Y677236D01*
G01X218900Y677146D02*
X218973Y677193D01*
G01X218833Y677098D02*
X218900Y677146D01*
G01X223149Y677307D02*
X223233Y677335D01*
G01X223068Y677274D02*
X223149Y677307D01*
G01X222989Y677236D02*
X223068Y677274D01*
G01X222913Y677193D02*
X222989Y677236D01*
G01X222840Y677146D02*
X222913Y677193D01*
G01X222773Y677098D02*
X222840Y677146D01*
G01X218951Y685510D02*
X218969Y685513D01*
G01X218931Y685500D02*
X218951Y685510D01*
G01X218909Y685483D02*
X218931Y685500D01*
G01X222891Y685510D02*
X222909Y685513D01*
G01X222871Y685500D02*
X222891Y685510D01*
G01X222849Y685483D02*
X222871Y685500D01*
G01X210450Y674333D02*
X210432Y674329D01*
G01X210470Y674343D02*
X210450Y674333D01*
G01X210493Y674359D02*
X210470Y674343D01*
G01X214390Y674333D02*
X214372Y674329D01*
G01X214410Y674343D02*
X214390Y674333D01*
G01X214433Y674359D02*
X214410Y674343D01*
G01X218330Y674333D02*
X218312Y674329D01*
G01X218350Y674343D02*
X218330Y674333D01*
G01X218373Y674359D02*
X218350Y674343D01*
G01X222270Y674333D02*
X222252Y674329D01*
G01X222290Y674343D02*
X222270Y674333D01*
G01X222313Y674359D02*
X222290Y674343D01*
G01X216674Y686044D02*
X216833Y686063D01*
G01X216524Y685987D02*
X216674Y686044D01*
G01X216391Y685895D02*
X216524Y685987D01*
G01X220614Y686044D02*
X220773Y686063D01*
G01X220464Y685987D02*
X220614Y686044D01*
G01X220331Y685895D02*
X220464Y685987D01*
G01X212727Y673799D02*
X212568Y673779D01*
G01X212877Y673856D02*
X212727Y673799D01*
G01X213010Y673947D02*
X212877Y673856D01*
G01X216667Y673799D02*
X216508Y673779D01*
G01X216817Y673856D02*
X216667Y673799D01*
G01X216950Y673947D02*
X216817Y673856D01*
G01X220607Y673799D02*
X220448Y673779D01*
G01X220757Y673856D02*
X220607Y673799D01*
G01X220890Y673947D02*
X220757Y673856D01*
G01X224547Y673799D02*
X224388Y673779D01*
G01X224697Y673856D02*
X224547Y673799D01*
G01X224830Y673947D02*
X224697Y673856D01*
G01X212863Y685510D02*
X212893Y685513D01*
G01X212833Y685500D02*
X212863Y685510D01*
G01X212807Y685483D02*
X212833Y685500D01*
G01X216803Y685510D02*
X216833Y685513D01*
G01X216773Y685500D02*
X216803Y685510D01*
G01X216747Y685483D02*
X216773Y685500D01*
G01X220743Y685510D02*
X220773Y685513D01*
G01X220713Y685500D02*
X220743Y685510D01*
G01X220687Y685483D02*
X220713Y685500D01*
G01X212598Y674333D02*
X212568Y674329D01*
G01X212628Y674343D02*
X212598Y674333D01*
G01X212654Y674359D02*
X212628Y674343D01*
G01X216538Y674333D02*
X216508Y674329D01*
G01X216568Y674343D02*
X216538Y674333D01*
G01X216594Y674359D02*
X216568Y674343D01*
G01X220478Y674333D02*
X220448Y674329D01*
G01X220508Y674343D02*
X220478Y674333D01*
G01X220534Y674359D02*
X220508Y674343D01*
G01X224418Y674333D02*
X224388Y674329D01*
G01X224448Y674343D02*
X224418Y674333D01*
G01X224474Y674359D02*
X224448Y674343D01*
G01X210193Y682255D02*
X210108Y682231D01*
G01X210274Y682282D02*
X210193Y682255D01*
G01X210352Y682313D02*
X210274Y682282D01*
G01X210428Y682347D02*
X210352Y682313D01*
G01X210501Y682386D02*
X210428Y682347D01*
G01X210568Y682426D02*
X210501Y682386D01*
G01X214133Y682255D02*
X214048Y682231D01*
G01X214214Y682282D02*
X214133Y682255D01*
G01X214292Y682313D02*
X214214Y682282D01*
G01X214368Y682347D02*
X214292Y682313D01*
G01X214441Y682386D02*
X214368Y682347D01*
G01X214508Y682426D02*
X214441Y682386D01*
G01X218073Y682255D02*
X217988Y682231D01*
G01X218154Y682282D02*
X218073Y682255D01*
G01X218232Y682313D02*
X218154Y682282D01*
G01X218308Y682347D02*
X218232Y682313D01*
G01X218381Y682386D02*
X218308Y682347D01*
G01X218448Y682426D02*
X218381Y682386D01*
G01X211329Y677588D02*
X211413Y677611D01*
G01X211248Y677561D02*
X211329Y677588D01*
G01X211169Y677530D02*
X211248Y677561D01*
G01X211093Y677495D02*
X211169Y677530D01*
G01X211020Y677456D02*
X211093Y677495D01*
G01X210953Y677417D02*
X211020Y677456D01*
G01X222013Y682255D02*
X221928Y682231D01*
G01X222094Y682282D02*
X222013Y682255D01*
G01X222172Y682313D02*
X222094Y682282D01*
G01X222248Y682347D02*
X222172Y682313D01*
G01X222321Y682386D02*
X222248Y682347D01*
G01X222388Y682426D02*
X222321Y682386D01*
G01X215269Y677588D02*
X215353Y677611D01*
G01X215188Y677561D02*
X215269Y677588D01*
G01X215109Y677530D02*
X215188Y677561D01*
G01X215033Y677495D02*
X215109Y677530D01*
G01X214960Y677456D02*
X215033Y677495D01*
G01X214893Y677417D02*
X214960Y677456D01*
G01X219209Y677588D02*
X219293Y677611D01*
G01X219128Y677561D02*
X219209Y677588D01*
G01X219049Y677530D02*
X219128Y677561D01*
G01X218973Y677495D02*
X219049Y677530D01*
G01X218900Y677456D02*
X218973Y677495D01*
G01X218833Y677417D02*
X218900Y677456D01*
G01X223149Y677588D02*
X223233Y677611D01*
G01X223068Y677561D02*
X223149Y677588D01*
G01X222989Y677530D02*
X223068Y677561D01*
G01X222913Y677495D02*
X222989Y677530D01*
G01X222840Y677456D02*
X222913Y677495D01*
G01X222773Y677417D02*
X222840Y677456D01*
G01X210496Y682242D02*
X210568Y682294D01*
G01X210423Y682195D02*
X210496Y682242D01*
G01X210346Y682153D02*
X210423Y682195D01*
G01X210267Y682115D02*
X210346Y682153D01*
G01X210186Y682083D02*
X210267Y682115D01*
G01X210108Y682056D02*
X210186Y682083D01*
G01X214436Y682242D02*
X214508Y682294D01*
G01X214363Y682195D02*
X214436Y682242D01*
G01X214286Y682153D02*
X214363Y682195D01*
G01X214207Y682115D02*
X214286Y682153D01*
G01X214126Y682083D02*
X214207Y682115D01*
G01X214048Y682056D02*
X214126Y682083D01*
G01X218376Y682242D02*
X218448Y682294D01*
G01X218303Y682195D02*
X218376Y682242D01*
G01X218226Y682153D02*
X218303Y682195D01*
G01X218147Y682115D02*
X218226Y682153D01*
G01X218066Y682083D02*
X218147Y682115D01*
G01X217988Y682056D02*
X218066Y682083D01*
G01X222316Y682242D02*
X222388Y682294D01*
G01X222243Y682195D02*
X222316Y682242D01*
G01X222166Y682153D02*
X222243Y682195D01*
G01X222087Y682115D02*
X222166Y682153D01*
G01X222006Y682083D02*
X222087Y682115D01*
G01X221928Y682056D02*
X222006Y682083D01*
G01X211025Y677601D02*
X210953Y677549D01*
G01X211099Y677648D02*
X211025Y677601D01*
G01X211175Y677690D02*
X211099Y677648D01*
G01X211254Y677727D02*
X211175Y677690D01*
G01X211335Y677760D02*
X211254Y677727D01*
G01X211413Y677786D02*
X211335Y677760D01*
G01X214965Y677601D02*
X214893Y677549D01*
G01X215039Y677648D02*
X214965Y677601D01*
G01X215115Y677690D02*
X215039Y677648D01*
G01X215194Y677727D02*
X215115Y677690D01*
G01X215275Y677760D02*
X215194Y677727D01*
G01X215353Y677786D02*
X215275Y677760D01*
G01X218905Y677601D02*
X218833Y677549D01*
G01X218979Y677648D02*
X218905Y677601D01*
G01X219055Y677690D02*
X218979Y677648D01*
G01X219134Y677727D02*
X219055Y677690D01*
G01X219215Y677760D02*
X219134Y677727D01*
G01X219293Y677786D02*
X219215Y677760D01*
G01X222845Y677601D02*
X222773Y677549D01*
G01X222919Y677648D02*
X222845Y677601D01*
G01X222995Y677690D02*
X222919Y677648D01*
G01X223074Y677727D02*
X222995Y677690D01*
G01X223155Y677760D02*
X223074Y677727D01*
G01X223233Y677786D02*
X223155Y677760D01*
G01X211076Y685547D02*
X211046Y685504D01*
G01X211087Y685578D02*
X211076Y685547D01*
G01X211089Y685589D02*
X211087Y685578D01*
G01X210445Y674296D02*
X210475Y674339D01*
G01X210434Y674265D02*
X210445Y674296D01*
G01X210432Y674254D02*
X210434Y674265D01*
G01X215016Y685547D02*
X214986Y685504D01*
G01X215027Y685578D02*
X215016Y685547D01*
G01X215029Y685589D02*
X215027Y685578D01*
G01X214385Y674296D02*
X214415Y674339D01*
G01X214374Y674265D02*
X214385Y674296D01*
G01X214372Y674254D02*
X214374Y674265D01*
G01X218956Y685547D02*
X218926Y685504D01*
G01X218967Y685578D02*
X218956Y685547D01*
G01X218969Y685589D02*
X218967Y685578D01*
G01X218325Y674296D02*
X218355Y674339D01*
G01X218314Y674265D02*
X218325Y674296D01*
G01X218312Y674254D02*
X218314Y674265D01*
G01X222896Y685547D02*
X222866Y685504D01*
G01X222907Y685578D02*
X222896Y685547D01*
G01X222909Y685589D02*
X222907Y685578D01*
G01X222265Y674296D02*
X222295Y674339D01*
G01X222254Y674265D02*
X222265Y674296D01*
G01X222252Y674254D02*
X222254Y674265D01*
G01X212575Y673780D02*
X212579Y673779D01*
G01X212572Y673780D02*
X212575D01*
G01X212570D02*
X212572D01*
G01X212569Y673781D02*
X212570Y673780D01*
G01X212568Y673782D02*
X212569Y673781D01*
G01X212568Y673783D02*
Y673782D01*
G01X212886Y686063D02*
X212882D01*
G01X212889D02*
X212886D01*
G01X212891Y686062D02*
X212889Y686063D01*
G01X212892Y686061D02*
X212891Y686062D01*
G01X212893Y686060D02*
X212892Y686061D01*
G01X212893Y686059D02*
Y686060D01*
G01X216515Y673780D02*
X216519Y673779D01*
G01X216512Y673780D02*
X216515D01*
G01X216510D02*
X216512D01*
G01X216509Y673781D02*
X216510Y673780D01*
G01X216508Y673782D02*
X216509Y673781D01*
G01X216508Y673783D02*
Y673782D01*
G01X216826Y686063D02*
X216822D01*
G01X216829D02*
X216826D01*
G01X216831Y686062D02*
X216829Y686063D01*
G01X216832Y686061D02*
X216831Y686062D01*
G01X216833Y686060D02*
X216832Y686061D01*
G01X216833Y686059D02*
Y686060D01*
G01X220455Y673780D02*
X220459Y673779D01*
G01X220452Y673780D02*
X220455D01*
G01X220450D02*
X220452D01*
G01X220449Y673781D02*
X220450Y673780D01*
G01X220448Y673782D02*
X220449Y673781D01*
G01X220448Y673783D02*
Y673782D01*
G01X220766Y686063D02*
X220762D01*
G01X220769D02*
X220766D01*
G01X220771Y686062D02*
X220769Y686063D01*
G01X220772Y686061D02*
X220771Y686062D01*
G01X220773Y686060D02*
X220772Y686061D01*
G01X220773Y686059D02*
Y686060D01*
G01X224395Y673780D02*
X224399Y673779D01*
G01X224392Y673780D02*
X224395D01*
G01X224390D02*
X224392D01*
G01X224389Y673781D02*
X224390Y673780D01*
G01X224388Y673782D02*
X224389Y673781D01*
G01X224388Y673783D02*
Y673782D01*
G01X213087Y674265D02*
X213089Y674254D01*
G01X213076Y674296D02*
X213087Y674265D01*
G01X213046Y674339D02*
X213076Y674296D01*
G01X217027Y674265D02*
X217029Y674254D01*
G01X217016Y674296D02*
X217027Y674265D01*
G01X216986Y674339D02*
X217016Y674296D01*
G01X212374Y685578D02*
X212372Y685589D01*
G01X212385Y685547D02*
X212374Y685578D01*
G01X212415Y685504D02*
X212385Y685547D01*
G01X220967Y674265D02*
X220969Y674254D01*
G01X220956Y674296D02*
X220967Y674265D01*
G01X220926Y674339D02*
X220956Y674296D01*
G01X216314Y685578D02*
X216312Y685589D01*
G01X216325Y685547D02*
X216314Y685578D01*
G01X216355Y685504D02*
X216325Y685547D01*
G01X224907Y674265D02*
X224909Y674254D01*
G01X224896Y674296D02*
X224907Y674265D01*
G01X224866Y674339D02*
X224896Y674296D01*
G01X220254Y685578D02*
X220252Y685589D01*
G01X220265Y685547D02*
X220254Y685578D01*
G01X220295Y685504D02*
X220265Y685547D01*
G01X218201Y673799D02*
X218312Y673779D01*
G01X218100Y673856D02*
X218201Y673799D01*
G01X218016Y673947D02*
X218100Y673856D01*
G01X222141Y673799D02*
X222252Y673779D01*
G01X222040Y673856D02*
X222141Y673799D01*
G01X221956Y673947D02*
X222040Y673856D01*
G01X215140Y686044D02*
X215029Y686063D01*
G01X215241Y685987D02*
X215140Y686044D01*
G01X215325Y685895D02*
X215241Y685987D01*
G01X219080Y686044D02*
X218969Y686063D01*
G01X219181Y685987D02*
X219080Y686044D01*
G01X219265Y685895D02*
X219181Y685987D01*
G01X223020Y686044D02*
X222909Y686063D01*
G01X223121Y685987D02*
X223020Y686044D01*
G01X223205Y685895D02*
X223121Y685987D01*
G01X212572Y674330D02*
X212579Y674329D01*
G01X212569Y674331D02*
X212572Y674330D01*
G01X212568Y674332D02*
X212569Y674331D01*
G01X216512Y674330D02*
X216519Y674329D01*
G01X216509Y674331D02*
X216512Y674330D01*
G01X216508Y674332D02*
X216509Y674331D01*
G01X220452Y674330D02*
X220459Y674329D01*
G01X220449Y674331D02*
X220452Y674330D01*
G01X220448Y674332D02*
X220449Y674331D01*
G01X212889Y685513D02*
X212882D01*
G01X212892Y685512D02*
X212889Y685513D01*
G01X212893Y685511D02*
X212892Y685512D01*
G01X224392Y674330D02*
X224399Y674329D01*
G01X224389Y674331D02*
X224392Y674330D01*
G01X224388Y674332D02*
X224389Y674331D01*
G01X216829Y685513D02*
X216822D01*
G01X216832Y685512D02*
X216829Y685513D01*
G01X216833Y685511D02*
X216832Y685512D01*
G01X220769Y685513D02*
X220762D01*
G01X220772Y685512D02*
X220769Y685513D01*
G01X220773Y685511D02*
X220772Y685512D01*
G01X232324Y684855D02*
X232341Y684670D01*
G01X232269Y685043D02*
X232324Y684855D01*
G01X232171Y685227D02*
X232269Y685043D01*
G01X232031Y685394D02*
X232171Y685227D01*
G01X212203Y677759D02*
X212122Y677786D01*
G01X212280Y677728D02*
X212203Y677759D01*
G01X212359Y677691D02*
X212280Y677728D01*
G01X212431Y677651D02*
X212359Y677691D01*
G01X212501Y677607D02*
X212431Y677651D01*
G01X212568Y677559D02*
X212501Y677607D01*
G01X209318Y682084D02*
X209399Y682056D01*
G01X216143Y677759D02*
X216062Y677786D01*
G01X216220Y677728D02*
X216143Y677759D01*
G01X216299Y677691D02*
X216220Y677728D01*
G01X216371Y677651D02*
X216299Y677691D01*
G01X216441Y677607D02*
X216371Y677651D01*
G01X216508Y677559D02*
X216441Y677607D01*
G01X213258Y682084D02*
X213339Y682056D01*
G01X213181Y682115D02*
X213258Y682084D01*
G01X213102Y682152D02*
X213181Y682115D01*
G01X213030Y682192D02*
X213102Y682152D01*
G01X212960Y682235D02*
X213030Y682192D01*
G01X212893Y682283D02*
X212960Y682235D01*
G01X220083Y677759D02*
X220002Y677786D01*
G01X220160Y677728D02*
X220083Y677759D01*
G01X220239Y677691D02*
X220160Y677728D01*
G01X220311Y677651D02*
X220239Y677691D01*
G01X220381Y677607D02*
X220311Y677651D01*
G01X220448Y677559D02*
X220381Y677607D01*
G01X217198Y682084D02*
X217279Y682056D01*
G01X217121Y682115D02*
X217198Y682084D01*
G01X217042Y682152D02*
X217121Y682115D01*
G01X216970Y682192D02*
X217042Y682152D01*
G01X216900Y682235D02*
X216970Y682192D01*
G01X216833Y682283D02*
X216900Y682235D01*
G01X224023Y677759D02*
X223942Y677786D01*
G01X224100Y677728D02*
X224023Y677759D01*
G01X224179Y677691D02*
X224100Y677728D01*
G01X224251Y677651D02*
X224179Y677691D01*
G01X224321Y677607D02*
X224251Y677651D01*
G01X224388Y677559D02*
X224321Y677607D01*
G01X221138Y682084D02*
X221219Y682056D01*
G01X221061Y682115D02*
X221138Y682084D01*
G01X220982Y682152D02*
X221061Y682115D01*
G01X220910Y682192D02*
X220982Y682152D01*
G01X220840Y682235D02*
X220910Y682192D01*
G01X220773Y682283D02*
X220840Y682235D01*
G01X212203Y674834D02*
X212122Y674857D01*
G01X212280Y674809D02*
X212203Y674834D01*
G01X212359Y674779D02*
X212280Y674809D01*
G01X212431Y674746D02*
X212359Y674779D01*
G01X212501Y674710D02*
X212431Y674746D01*
G01X212568Y674671D02*
X212501Y674710D01*
G01X216143Y674834D02*
X216062Y674857D01*
G01X216220Y674809D02*
X216143Y674834D01*
G01X216299Y674779D02*
X216220Y674809D01*
G01X216371Y674746D02*
X216299Y674779D01*
G01X216441Y674710D02*
X216371Y674746D01*
G01X216508Y674671D02*
X216441Y674710D01*
G01X220083Y674834D02*
X220002Y674857D01*
G01X220160Y674809D02*
X220083Y674834D01*
G01X220239Y674779D02*
X220160Y674809D01*
G01X220311Y674746D02*
X220239Y674779D01*
G01X220381Y674710D02*
X220311Y674746D01*
G01X220448Y674671D02*
X220381Y674710D01*
G01X224023Y674834D02*
X223942Y674857D01*
G01X224100Y674809D02*
X224023Y674834D01*
G01X224179Y674779D02*
X224100Y674809D01*
G01X224251Y674746D02*
X224179Y674779D01*
G01X224321Y674710D02*
X224251Y674746D01*
G01X224388Y674671D02*
X224321Y674710D01*
G01X209318Y685008D02*
X209399Y684986D01*
G01X213258Y685008D02*
X213339Y684986D01*
G01X213181Y685033D02*
X213258Y685008D01*
G01X213102Y685064D02*
X213181Y685033D01*
G01X213030Y685096D02*
X213102Y685064D01*
G01X212960Y685132D02*
X213030Y685096D01*
G01X212893Y685171D02*
X212960Y685132D01*
G01X217198Y685008D02*
X217279Y684986D01*
G01X217121Y685033D02*
X217198Y685008D01*
G01X217042Y685064D02*
X217121Y685033D01*
G01X216970Y685096D02*
X217042Y685064D01*
G01X216900Y685132D02*
X216970Y685096D01*
G01X216833Y685171D02*
X216900Y685132D01*
G01X221138Y685008D02*
X221219Y684986D01*
G01X221061Y685033D02*
X221138Y685008D01*
G01X220982Y685064D02*
X221061Y685033D01*
G01X220910Y685096D02*
X220982Y685064D01*
G01X220840Y685132D02*
X220910Y685096D01*
G01X220773Y685171D02*
X220840Y685132D01*
G01X231713Y685911D02*
X231567Y685921D01*
G01X231842Y685901D02*
X231713Y685911D01*
G01X231943Y685890D02*
X231842Y685901D01*
G01X232008Y685880D02*
X231943Y685890D01*
G01X232031Y685870D02*
X232008Y685880D01*
G01X232099Y685904D02*
X231607Y685921D01*
G01X232300Y685896D02*
X232099Y685904D01*
G01X232452Y685887D02*
X232300Y685896D01*
G01X232548Y685878D02*
X232452Y685887D01*
G01X232581Y685870D02*
X232548Y685878D01*
G01X212498Y677466D02*
X212568Y677426D01*
G01X212428Y677502D02*
X212498Y677466D01*
G01X212352Y677536D02*
X212428Y677502D01*
G01X212277Y677565D02*
X212352Y677536D01*
G01X212200Y677590D02*
X212277Y677565D01*
G01X212122Y677611D02*
X212200Y677590D01*
G01X216438Y677466D02*
X216508Y677426D01*
G01X216368Y677502D02*
X216438Y677466D01*
G01X216292Y677536D02*
X216368Y677502D01*
G01X216217Y677565D02*
X216292Y677536D01*
G01X216140Y677590D02*
X216217Y677565D01*
G01X216062Y677611D02*
X216140Y677590D01*
G01X220378Y677466D02*
X220448Y677426D01*
G01X220308Y677502D02*
X220378Y677466D01*
G01X220232Y677536D02*
X220308Y677502D01*
G01X220157Y677565D02*
X220232Y677536D01*
G01X220080Y677590D02*
X220157Y677565D01*
G01X220002Y677611D02*
X220080Y677590D01*
G01X224318Y677466D02*
X224388Y677426D01*
G01X224248Y677502D02*
X224318Y677466D01*
G01X224172Y677536D02*
X224248Y677502D01*
G01X224097Y677565D02*
X224172Y677536D01*
G01X224020Y677590D02*
X224097Y677565D01*
G01X223942Y677611D02*
X224020Y677590D01*
G01X209399Y682231D02*
X209321Y682253D01*
G01X212963Y682376D02*
X212893Y682417D01*
G01X213033Y682341D02*
X212963Y682376D01*
G01X213109Y682306D02*
X213033Y682341D01*
G01X213184Y682278D02*
X213109Y682306D01*
G01X213261Y682253D02*
X213184Y682278D01*
G01X213339Y682231D02*
X213261Y682253D01*
G01X216903Y682376D02*
X216833Y682417D01*
G01X216973Y682341D02*
X216903Y682376D01*
G01X217049Y682306D02*
X216973Y682341D01*
G01X217124Y682278D02*
X217049Y682306D01*
G01X217201Y682253D02*
X217124Y682278D01*
G01X217279Y682231D02*
X217201Y682253D01*
G01X220843Y682376D02*
X220773Y682417D01*
G01X220913Y682341D02*
X220843Y682376D01*
G01X220989Y682306D02*
X220913Y682341D01*
G01X221064Y682278D02*
X220989Y682306D01*
G01X221141Y682253D02*
X221064Y682278D01*
G01X221219Y682231D02*
X221141Y682253D01*
G01X212498Y677158D02*
X212568Y677108D01*
G01X212428Y677202D02*
X212498Y677158D01*
G01X212352Y677243D02*
X212428Y677202D01*
G01X212277Y677278D02*
X212352Y677243D01*
G01X212200Y677309D02*
X212277Y677278D01*
G01X212122Y677335D02*
X212200Y677309D01*
G01X216438Y677158D02*
X216508Y677108D01*
G01X216368Y677202D02*
X216438Y677158D01*
G01X216292Y677243D02*
X216368Y677202D01*
G01X216217Y677278D02*
X216292Y677243D01*
G01X216140Y677309D02*
X216217Y677278D01*
G01X216062Y677335D02*
X216140Y677309D01*
G01X220378Y677158D02*
X220448Y677108D01*
G01X220308Y677202D02*
X220378Y677158D01*
G01X220232Y677243D02*
X220308Y677202D01*
G01X220157Y677278D02*
X220232Y677243D01*
G01X220080Y677309D02*
X220157Y677278D01*
G01X220002Y677335D02*
X220080Y677309D01*
G01X224318Y677158D02*
X224388Y677108D01*
G01X224248Y677202D02*
X224318Y677158D01*
G01X224172Y677243D02*
X224248Y677202D01*
G01X224097Y677278D02*
X224172Y677243D01*
G01X224020Y677309D02*
X224097Y677278D01*
G01X223942Y677335D02*
X224020Y677309D01*
G01X209399Y682507D02*
X209321Y682533D01*
G01X212963Y682685D02*
X212893Y682734D01*
G01X213033Y682641D02*
X212963Y682685D01*
G01X213109Y682599D02*
X213033Y682641D01*
G01X213184Y682564D02*
X213109Y682599D01*
G01X213261Y682533D02*
X213184Y682564D01*
G01X213339Y682507D02*
X213261Y682533D01*
G01X216903Y682685D02*
X216833Y682734D01*
G01X216973Y682641D02*
X216903Y682685D01*
G01X217049Y682599D02*
X216973Y682641D01*
G01X217124Y682564D02*
X217049Y682599D01*
G01X217201Y682533D02*
X217124Y682564D01*
G01X217279Y682507D02*
X217201Y682533D01*
G01X220843Y682685D02*
X220773Y682734D01*
G01X220913Y682641D02*
X220843Y682685D01*
G01X220989Y682599D02*
X220913Y682641D01*
G01X221064Y682564D02*
X220989Y682599D01*
G01X221141Y682533D02*
X221064Y682564D01*
G01X221219Y682507D02*
X221141Y682533D01*
G01X210893Y674343D02*
X210867Y674359D01*
G01X210923Y674333D02*
X210893Y674343D01*
G01X210953Y674329D02*
X210923Y674333D01*
G01X214833Y674343D02*
X214807Y674359D01*
G01X214863Y674333D02*
X214833Y674343D01*
G01X214893Y674329D02*
X214863Y674333D01*
G01X218773Y674343D02*
X218747Y674359D01*
G01X218803Y674333D02*
X218773Y674343D01*
G01X218833Y674329D02*
X218803Y674333D01*
G01X222713Y674343D02*
X222687Y674359D01*
G01X222743Y674333D02*
X222713Y674343D01*
G01X222773Y674329D02*
X222743Y674333D01*
G01X210628Y685500D02*
X210654Y685483D01*
G01X210598Y685510D02*
X210628Y685500D01*
G01X210568Y685513D02*
X210598Y685510D01*
G01X214568Y685500D02*
X214594Y685483D01*
G01X214538Y685510D02*
X214568Y685500D01*
G01X214508Y685513D02*
X214538Y685510D01*
G01X218508Y685500D02*
X218534Y685483D01*
G01X218478Y685510D02*
X218508Y685500D01*
G01X218448Y685513D02*
X218478Y685510D01*
G01X222448Y685500D02*
X222474Y685483D01*
G01X222418Y685510D02*
X222448Y685500D01*
G01X222388Y685513D02*
X222418Y685510D01*
G01X210644Y673856D02*
X210511Y673947D01*
G01X210794Y673799D02*
X210644Y673856D01*
G01X210953Y673779D02*
X210794Y673799D01*
G01X214584Y673856D02*
X214451Y673947D01*
G01X214734Y673799D02*
X214584Y673856D01*
G01X214893Y673779D02*
X214734Y673799D01*
G01X218524Y673856D02*
X218391Y673947D01*
G01X218674Y673799D02*
X218524Y673856D01*
G01X218833Y673779D02*
X218674Y673799D01*
G01X222464Y673856D02*
X222331Y673947D01*
G01X222614Y673799D02*
X222464Y673856D01*
G01X222773Y673779D02*
X222614Y673799D01*
G01X210878Y685987D02*
X211010Y685895D01*
G01X210727Y686044D02*
X210878Y685987D01*
G01X210568Y686063D02*
X210727Y686044D01*
G01X214818Y685987D02*
X214950Y685895D01*
G01X214667Y686044D02*
X214818Y685987D01*
G01X214508Y686063D02*
X214667Y686044D01*
G01X218758Y685987D02*
X218890Y685895D01*
G01X218607Y686044D02*
X218758Y685987D01*
G01X218448Y686063D02*
X218607Y686044D01*
G01X222698Y685987D02*
X222830Y685895D01*
G01X222547Y686044D02*
X222698Y685987D01*
G01X222388Y686063D02*
X222547Y686044D01*
G01X213051Y674343D02*
X213029Y674359D01*
G01X213071Y674333D02*
X213051Y674343D01*
G01X213089Y674329D02*
X213071Y674333D01*
G01X216991Y674343D02*
X216969Y674359D01*
G01X217011Y674333D02*
X216991Y674343D01*
G01X217029Y674329D02*
X217011Y674333D01*
G01X220931Y674343D02*
X220909Y674359D01*
G01X220951Y674333D02*
X220931Y674343D01*
G01X220969Y674329D02*
X220951Y674333D01*
G01X224871Y674343D02*
X224849Y674359D01*
G01X224891Y674333D02*
X224871Y674343D01*
G01X224909Y674329D02*
X224891Y674333D01*
G01X212410Y685500D02*
X212433Y685483D01*
G01X212390Y685510D02*
X212410Y685500D01*
G01X212372Y685513D02*
X212390Y685510D01*
G01X216350Y685500D02*
X216373Y685483D01*
G01X216330Y685510D02*
X216350Y685500D01*
G01X216312Y685513D02*
X216330Y685510D01*
G01X220290Y685500D02*
X220313Y685483D01*
G01X220270Y685510D02*
X220290Y685500D01*
G01X220252Y685513D02*
X220270Y685510D01*
G01X231594Y673921D02*
X231607D01*
G01X231582D02*
X231594D01*
G01X231567Y673920D02*
X231582Y673921D01*
G01X231555Y673919D02*
X231567Y673920D01*
G01X231543Y673918D02*
X231555Y673919D01*
G01X231531Y673917D02*
X231543Y673918D01*
G01X232008Y673962D02*
X232031Y673973D01*
G01X231944Y673952D02*
X232008Y673962D01*
G01X231842Y673942D02*
X231944Y673952D01*
G01X231713Y673932D02*
X231842Y673942D01*
G01X231567Y673921D02*
X231713Y673932D01*
G01X232548Y673964D02*
X232581Y673973D01*
G01X232452Y673956D02*
X232548Y673964D01*
G01X232300Y673947D02*
X232452Y673956D01*
G01X232099Y673938D02*
X232300Y673947D01*
G01X222772Y674331D02*
X222773Y674332D01*
G01X222769Y674330D02*
X222772Y674331D01*
G01X222762Y674329D02*
X222769Y674330D01*
G01X218832Y674331D02*
X218833Y674332D01*
G01X218829Y674330D02*
X218832Y674331D01*
G01X218822Y674329D02*
X218829Y674330D01*
G01X214892Y674331D02*
X214893Y674332D01*
G01X214889Y674330D02*
X214892Y674331D01*
G01X214882Y674329D02*
X214889Y674330D01*
G01X210952Y674331D02*
X210953Y674332D01*
G01X210949Y674330D02*
X210952Y674331D01*
G01X210942Y674329D02*
X210949Y674330D01*
G01X222389Y685512D02*
X222388Y685511D01*
G01X222392Y685513D02*
X222389Y685512D01*
G01X222399Y685513D02*
X222392D01*
G01X218449Y685512D02*
X218448Y685511D01*
G01X218452Y685513D02*
X218449Y685512D01*
G01X218459Y685513D02*
X218452D01*
G01X214509Y685512D02*
X214508Y685511D01*
G01X214512Y685513D02*
X214509Y685512D01*
G01X214519Y685513D02*
X214512D01*
G01X210569Y685512D02*
X210568Y685511D01*
G01X210572Y685513D02*
X210569Y685512D01*
G01X210579Y685513D02*
X210572D01*
G01X222773Y673782D02*
Y673783D01*
G01X222772Y673781D02*
X222773Y673782D01*
G01X222771Y673780D02*
X222772Y673781D01*
G01X222768Y673780D02*
X222771D01*
G01X222766D02*
X222768D01*
G01X222762Y673779D02*
X222766Y673780D01*
G01X218833Y673782D02*
Y673783D01*
G01X218832Y673781D02*
X218833Y673782D01*
G01X218831Y673780D02*
X218832Y673781D01*
G01X218828Y673780D02*
X218831D01*
G01X218826D02*
X218828D01*
G01X218822Y673779D02*
X218826Y673780D01*
G01X214893Y673782D02*
Y673783D01*
G01X214892Y673781D02*
X214893Y673782D01*
G01X214891Y673780D02*
X214892Y673781D01*
G01X214888Y673780D02*
X214891D01*
G01X214886D02*
X214888D01*
G01X214882Y673779D02*
X214886Y673780D01*
G01X210953Y673782D02*
Y673783D01*
G01X210952Y673781D02*
X210953Y673782D01*
G01X210951Y673780D02*
X210952Y673781D01*
G01X210948Y673780D02*
X210951D01*
G01X210946D02*
X210948D01*
G01X210942Y673779D02*
X210946Y673780D01*
G01X222388Y686061D02*
Y686059D01*
G01X222389Y686061D02*
X222388D01*
G01X222390Y686062D02*
X222389Y686061D01*
G01X222393Y686063D02*
X222390Y686062D01*
G01X222395Y686063D02*
X222393D01*
G01X222399D02*
X222395D01*
G01X218448Y686061D02*
Y686059D01*
G01X218449Y686061D02*
X218448D01*
G01X218450Y686062D02*
X218449Y686061D01*
G01X218453Y686063D02*
X218450Y686062D01*
G01X218455Y686063D02*
X218453D01*
G01X218459D02*
X218455D01*
G01X214508Y686061D02*
Y686059D01*
G01X214509Y686061D02*
X214508D01*
G01X214510Y686062D02*
X214509Y686061D01*
G01X214513Y686063D02*
X214510Y686062D01*
G01X214515Y686063D02*
X214513D01*
G01X214519D02*
X214515D01*
G01X210568Y686061D02*
Y686059D01*
G01X210569Y686061D02*
X210568D01*
G01X210570Y686062D02*
X210569Y686061D01*
G01X210573Y686063D02*
X210570Y686062D01*
G01X210575Y686063D02*
X210573D01*
G01X210579D02*
X210575D01*
G01X231544Y685924D02*
X231531Y685925D01*
G01X231556Y685923D02*
X231544Y685924D01*
G01X231571Y685922D02*
X231556Y685923D01*
G01X231583Y685922D02*
X231571D01*
G01X231595Y685921D02*
X231583Y685922D01*
G01X231607Y685921D02*
X231595D01*
G01X231537Y685924D02*
X231531Y685925D01*
G01X231543Y685923D02*
X231537Y685924D01*
G01X231549Y685922D02*
X231543Y685923D01*
G01X231555Y685922D02*
X231549D01*
G01X231561Y685921D02*
X231555Y685922D01*
G01X231567Y685921D02*
X231561D01*
G01X222845Y674705D02*
X222773Y674662D01*
G01X222919Y674743D02*
X222845Y674705D01*
G01X222995Y674778D02*
X222919Y674743D01*
G01X223074Y674809D02*
X222995Y674778D01*
G01X223155Y674835D02*
X223074Y674809D01*
G01X223233Y674857D02*
X223155Y674835D01*
G01X218905Y674705D02*
X218833Y674662D01*
G01X218979Y674743D02*
X218905Y674705D01*
G01X219055Y674778D02*
X218979Y674743D01*
G01X219134Y674809D02*
X219055Y674778D01*
G01X219215Y674835D02*
X219134Y674809D01*
G01X219293Y674857D02*
X219215Y674835D01*
G01X214965Y674705D02*
X214893Y674662D01*
G01X215039Y674743D02*
X214965Y674705D01*
G01X215115Y674778D02*
X215039Y674743D01*
G01X215194Y674809D02*
X215115Y674778D01*
G01X215275Y674835D02*
X215194Y674809D01*
G01X215353Y674857D02*
X215275Y674835D01*
G01X211025Y674705D02*
X210953Y674662D01*
G01X211099Y674743D02*
X211025Y674705D01*
G01X211175Y674778D02*
X211099Y674743D01*
G01X211254Y674809D02*
X211175Y674778D01*
G01X211335Y674835D02*
X211254Y674809D01*
G01X211413Y674857D02*
X211335Y674835D01*
G01X222316Y685137D02*
X222388Y685180D01*
G01X222243Y685099D02*
X222316Y685137D01*
G01X222166Y685065D02*
X222243Y685099D01*
G01X222087Y685034D02*
X222166Y685065D01*
G01X222006Y685007D02*
X222087Y685034D01*
G01X221928Y684986D02*
X222006Y685007D01*
G01X218376Y685137D02*
X218448Y685180D01*
G01X218303Y685099D02*
X218376Y685137D01*
G01X218226Y685065D02*
X218303Y685099D01*
G01X218147Y685034D02*
X218226Y685065D01*
G01X218066Y685007D02*
X218147Y685034D01*
G01X217988Y684986D02*
X218066Y685007D01*
G01X214436Y685137D02*
X214508Y685180D01*
G01X214363Y685099D02*
X214436Y685137D01*
G01X214286Y685065D02*
X214363Y685099D01*
G01X214207Y685034D02*
X214286Y685065D01*
G01X214126Y685007D02*
X214207Y685034D01*
G01X214048Y684986D02*
X214126Y685007D01*
G01X231561Y673921D02*
X231567D01*
G01X231555D02*
X231561D01*
G01X231548Y673920D02*
X231555Y673921D01*
G01X231542Y673919D02*
X231548Y673920D01*
G01X231536Y673918D02*
X231542Y673919D01*
G01X231531Y673917D02*
X231536Y673918D01*
G01X225121Y673856D02*
X225205Y673947D01*
G01X225020Y673799D02*
X225121Y673856D01*
G01X224909Y673779D02*
X225020Y673799D01*
G01X221181Y673856D02*
X221265Y673947D01*
G01X221080Y673799D02*
X221181Y673856D01*
G01X220969Y673779D02*
X221080Y673799D01*
G01X217241Y673856D02*
X217325Y673947D01*
G01X217140Y673799D02*
X217241Y673856D01*
G01X217029Y673779D02*
X217140Y673799D01*
G01X220040Y685987D02*
X219956Y685895D01*
G01X220141Y686044D02*
X220040Y685987D01*
G01X220252Y686063D02*
X220141Y686044D01*
G01X216100Y685987D02*
X216016Y685895D01*
G01X216201Y686044D02*
X216100Y685987D01*
G01X216312Y686063D02*
X216201Y686044D01*
G01X210496Y685137D02*
X210568Y685180D01*
G01X210423Y685099D02*
X210496Y685137D01*
G01X210346Y685065D02*
X210423Y685099D01*
G01X210267Y685034D02*
X210346Y685065D01*
G01X210186Y685007D02*
X210267Y685034D01*
G01X210108Y684986D02*
X210186Y685007D01*
G01X233504Y684980D02*
G03X233995Y685241I176J261D01*
G01X231581Y686536D02*
G03X231528Y685911I0J-315D01*
G01X226881Y684251D02*
G03I-1250J0D01*
G01X221933Y682005D02*
G03X222398Y682254I-425J1352D01*
G01X220763Y682243D02*
G03X221214Y682005I876J1114D01*
G01X233995Y674601D02*
G03X233504Y674862I-315J0D01*
G01X231528Y673932D02*
G03X231581Y673306I53J-311D01*
G01X227521Y677264D02*
G03X228183Y678016I410J306D01*
G01X219288Y677838D02*
G03X218823Y677588I427J-1351D01*
G01X220458Y677600D02*
G03X220007Y677838I-876J-1114D01*
G01X223228D02*
G03X222763Y677588I427J-1351D01*
G01X224398Y677600D02*
G03X223947Y677838I-876J-1114D01*
G01X217993Y682005D02*
G03X218458Y682254I-425J1352D01*
G01X216823Y682243D02*
G03X217274Y682005I876J1114D01*
G01X210113D02*
G03X210578Y682254I-425J1352D01*
G01X214053Y682005D02*
G03X214518Y682254I-425J1352D01*
G01X212883Y682243D02*
G03X213334Y682005I876J1114D01*
G01X212550Y671071D02*
G03X212038Y671583I-512J0D01*
G01X211538D02*
G03X211026Y671071I0J-512D01*
G01X211408Y677838D02*
G03X210943Y677588I427J-1351D01*
G01X212578Y677600D02*
G03X212127Y677838I-876J-1114D01*
G01X215348D02*
G03X214883Y677588I427J-1351D01*
G01X216518Y677600D02*
G03X216067Y677838I-876J-1114D01*
G01X211111Y686062D02*
X211089Y686063D01*
G01X214351Y673780D02*
X214372Y673779D01*
G01X210411Y673780D02*
X210432Y673779D01*
G01X214508Y691113D02*
X212893D01*
G01X218448D02*
X216833D01*
G01X222388D02*
X220773D01*
G01X231581Y690421D02*
X228081D01*
G01X233981Y689771D02*
X214751D01*
G01X233981Y688171D02*
X214751D01*
G01X223731Y687018D02*
X214751D01*
G01X214508Y686963D02*
X212893D01*
G01X218448D02*
X216833D01*
G01X222388D02*
X220773D01*
G01X215051Y686821D02*
X214751D01*
G01D02*
X212351D01*
G01X218991D02*
X216291D01*
G01X222931D02*
X220231D01*
G01X214508Y686613D02*
X212893D01*
G01X218448D02*
X216833D01*
G01X222388D02*
X220773D01*
G01X214751Y686271D02*
X223731D01*
G01X214508Y686111D02*
X212893D01*
G01X214751Y686071D02*
X223731D01*
G01X215029Y686063D02*
X212372D01*
G01X218969D02*
X216312D01*
G01X222909D02*
X220252D01*
G01X231567Y685921D02*
X231607D01*
G01X219956Y685895D02*
X220331D01*
G01X222830D02*
X223205D01*
G01X218890D02*
X219265D01*
G01X216016D02*
X216391D01*
G01X214950D02*
X215325D01*
G01X211010D02*
X211111D01*
G01X212351D02*
X212451D01*
G01X232581Y685870D02*
X232031D01*
G01Y685669D02*
X232581D01*
G01X215029Y685513D02*
X212372D01*
G01X218969D02*
X216312D01*
G01X222909D02*
X220252D01*
G01X220313Y685483D02*
X220687D01*
G01X222474D02*
X222849D01*
G01X216373D02*
X216747D01*
G01X218534D02*
X218909D01*
G01X214594D02*
X214969D01*
G01X210654D02*
X211029D01*
G01X212433D02*
X212807D01*
G01X214508Y685420D02*
X212893D01*
G01X218448D02*
X216833D01*
G01X222388D02*
X220773D01*
G01X222531Y685371D02*
X223731D01*
G01X218591D02*
X220631D01*
G01X214751D02*
X216691D01*
G01X214651D02*
X214751D01*
G01X212751D02*
X210711D01*
G01X212751Y685157D02*
X210711D01*
G01X216691D02*
X214751D01*
G01D02*
X214651D01*
G01X220631D02*
X218591D01*
G01X223731D02*
X222531D01*
G01X221219Y684986D02*
X221928D01*
G01X217279D02*
X217988D01*
G01X213339D02*
X214048D01*
G01X209399D02*
X210108D01*
G01X232581Y684670D02*
X232341D01*
G01X214508Y683646D02*
X212893D01*
G01X218448D02*
X216833D01*
G01X222388D02*
X220773D01*
G01X212751Y683571D02*
X210711D01*
G01X216691D02*
X214751D01*
G01D02*
X214651D01*
G01X220631D02*
X218591D01*
G01X226152D02*
X222531D01*
G01X214508Y683116D02*
X212893D01*
G01X218448D02*
X216833D01*
G01X222388D02*
X220773D01*
G01X214508Y682666D02*
X212893D01*
G01X218448D02*
X216833D01*
G01X222388D02*
X220773D01*
G01Y682587D02*
X222388D01*
G01X216833D02*
X218448D01*
G01X212893D02*
X214508D01*
G01X222531Y682571D02*
X226516D01*
G01X214751D02*
X216691D01*
G01X214651D02*
X214751D01*
G01X214508D02*
X212893D01*
G01X212751D02*
X210711D01*
G01X220631D02*
X218591D01*
G01X218448D02*
X216833D01*
G01X222388D02*
X220773D01*
G01X221928Y682507D02*
X222388D01*
G01X220773D02*
X221219D01*
G01X217988D02*
X218448D01*
G01X216833D02*
X217279D01*
G01X214048D02*
X214508D01*
G01X210108D02*
X210568D01*
G01X212893D02*
X213339D01*
G01X232581Y682421D02*
X231081D01*
G01X210108Y682231D02*
X209399D01*
G01X214048D02*
X213339D01*
G01X217988D02*
X217279D01*
G01X221928D02*
X221219D01*
G01X232581Y682171D02*
X233031D01*
G01X232581D02*
X232031D01*
G01X221219Y682056D02*
X221928D01*
G01X217279D02*
X217988D01*
G01X213339D02*
X214048D01*
G01X209399D02*
X210108D01*
G01Y682021D02*
X209399D01*
G01X214048D02*
X213339D01*
G01X217988D02*
X217279D01*
G01X221928D02*
X221219D01*
G01X227531Y681971D02*
X223731D01*
G01X214651Y681121D02*
X212751D01*
G01X218591D02*
X216691D01*
G01X222531D02*
X220631D01*
G01X212711Y678721D02*
X210811D01*
G01X216651D02*
X214751D01*
G01X220591D02*
X218691D01*
G01X224531D02*
X222631D01*
G01X223233Y677821D02*
X223942D01*
G01X219293D02*
X220002D01*
G01X215353D02*
X216062D01*
G01X211413D02*
X212122D01*
G01Y677786D02*
X211413D01*
G01X216062D02*
X215353D01*
G01X220002D02*
X219293D01*
G01X223942D02*
X223233D01*
G01X232581Y677671D02*
X233031D01*
G01X232031D02*
X232581D01*
G01X223233Y677611D02*
X223942D01*
G01X219293D02*
X220002D01*
G01X215353D02*
X216062D01*
G01X211413D02*
X212122D01*
G01X231081Y677421D02*
X232581D01*
G01X211413Y677335D02*
X210953D01*
G01X212568D02*
X212122D01*
G01X215353D02*
X214893D01*
G01X216508D02*
X216062D01*
G01X219293D02*
X218833D01*
G01X220448D02*
X220002D01*
G01X223233D02*
X222773D01*
G01X224388D02*
X223942D01*
G01X222773Y677271D02*
X224388D01*
G01X218833D02*
X220448D01*
G01X214893D02*
X216508D01*
G01X210953D02*
X212568D01*
G01X214751D02*
X212711D01*
G01X218691D02*
X216651D01*
G01X222631D02*
X220591D01*
G01X227531D02*
X224531D01*
G01X212568Y677256D02*
X210953D01*
G01X216508D02*
X214893D01*
G01X220448D02*
X218833D01*
G01X224388D02*
X222773D01*
G01Y677177D02*
X224388D01*
G01X218833D02*
X220448D01*
G01X214893D02*
X216508D01*
G01X210953D02*
X212568D01*
G01X222773Y676727D02*
X224388D01*
G01X218833D02*
X220448D01*
G01X214893D02*
X216508D01*
G01X210953D02*
X212568D01*
G01X224531Y676271D02*
X228809D01*
G01X220591D02*
X222631D01*
G01X216651D02*
X218691D01*
G01X212711D02*
X214751D01*
G01X222773Y676196D02*
X224388D01*
G01X218833D02*
X220448D01*
G01X214893D02*
X216508D01*
G01X210953D02*
X212568D01*
G01X232341Y675172D02*
X232581D01*
G01X212122Y674857D02*
X211413D01*
G01X216062D02*
X215353D01*
G01X220002D02*
X219293D01*
G01X223942D02*
X223233D01*
G01X224531Y674686D02*
X227531D01*
G01X220591D02*
X222631D01*
G01X216651D02*
X218691D01*
G01X212711D02*
X214751D01*
G01X224531Y674471D02*
X227531D01*
G01X214751D02*
X212711D01*
G01X218691D02*
X216651D01*
G01X222631D02*
X220591D01*
G01X222773Y674422D02*
X224388D01*
G01X218833D02*
X220448D01*
G01X214893D02*
X216508D01*
G01X210953D02*
X212568D01*
G01X213029Y674359D02*
X212654D01*
G01X210867D02*
X210493D01*
G01X214807D02*
X214433D01*
G01X218747D02*
X218373D01*
G01X216969D02*
X216594D01*
G01X220909D02*
X220534D01*
G01X222687D02*
X222313D01*
G01X224849D02*
X224474D01*
G01X213089Y674329D02*
X210432D01*
G01X217029D02*
X214372D01*
G01X220969D02*
X218312D01*
G01X224909D02*
X222252D01*
G01X232581Y674174D02*
X232031D01*
G01Y673973D02*
X232581D01*
G01X210511Y673947D02*
X210411D01*
G01X213111D02*
X213010D01*
G01X214451D02*
X214351D01*
G01X218391D02*
X218016D01*
G01X217325D02*
X216950D01*
G01X221265D02*
X220890D01*
G01X222331D02*
X221956D01*
G01X225205D02*
X224830D01*
G01X231607Y673921D02*
X231567D01*
G01X213089Y673779D02*
X210432D01*
G01X217029D02*
X214372D01*
G01X220969D02*
X218312D01*
G01X224909D02*
X222252D01*
G01X227531Y673771D02*
X214751D01*
G01X210953Y673732D02*
X212568D01*
G01X227531Y673571D02*
X214751D01*
G01X222773Y673229D02*
X224388D01*
G01X218833D02*
X220448D01*
G01X214893D02*
X216508D01*
G01X210953D02*
X212568D01*
G01X222231Y673021D02*
X224931D01*
G01X218291D02*
X220991D01*
G01X214751D02*
X217051D01*
G01X214351D02*
X214751D01*
G01X210411D02*
X213111D01*
G01X222773Y672879D02*
X224388D01*
G01X218833D02*
X220448D01*
G01X214893D02*
X216508D01*
G01X210953D02*
X212568D01*
G01X214751Y672825D02*
X227531D01*
G01X233981Y671671D02*
X214751D01*
G01X212038Y671571D02*
X211538D01*
G01X233981Y670071D02*
X214751D01*
G01D02*
X212538D01*
G01X231581Y669421D02*
X228081D01*
G01X212568Y668729D02*
X210953D01*
G01X216508D02*
X214893D01*
G01X220448D02*
X218833D01*
G01X224388D02*
X222773D01*
G01X212372Y686063D02*
X212351Y686062D01*
G01X213089Y673779D02*
X213111Y673780D01*
G01X231607Y673921D02*
X232099Y673938D01*
G01X232031Y685992D02*
X233513Y684992D01*
G01X223263Y685526D02*
X222830Y685895D01*
G01X222474Y685483D02*
X222907Y685114D01*
G01X219323Y685526D02*
X218890Y685895D01*
G01X218534Y685483D02*
X218967Y685114D01*
G01X215383Y685526D02*
X214950Y685895D01*
G01X214594Y685483D02*
X214725Y685371D01*
G01X214751Y685350D02*
X215027Y685114D01*
G01X211111Y685810D02*
X211010Y685895D01*
G01X210654Y685483D02*
X210785Y685371D01*
G01X222687Y674359D02*
X222254Y674728D01*
G01X221898Y674316D02*
X222331Y673947D01*
G01X218747Y674359D02*
X218314Y674728D01*
G01X217958Y674316D02*
X218391Y673947D01*
G01X214807Y674359D02*
X214676Y674471D01*
G01X214351Y674033D02*
X214451Y673947D01*
G01X210867Y674359D02*
X210736Y674471D01*
G01X210411Y674033D02*
X210511Y673947D01*
G01X220331Y685895D02*
X220687Y685483D01*
G01X220313D02*
X219956Y685895D01*
G01X220254Y685114D02*
X219898Y685526D01*
G01X216391Y685895D02*
X216747Y685483D01*
G01X216373D02*
X216016Y685895D01*
G01X216314Y685114D02*
X215958Y685526D01*
G01X224907Y674728D02*
X225263Y674316D01*
G01X224849Y674359D02*
X225205Y673947D01*
G01X224830D02*
X224474Y674359D01*
G01X212451Y685895D02*
X212807Y685483D01*
G01X212433D02*
X212351Y685578D01*
G01X220967Y674728D02*
X221323Y674316D01*
G01X220909Y674359D02*
X221265Y673947D01*
G01X220890D02*
X220534Y674359D01*
G01X217027Y674728D02*
X217383Y674316D01*
G01X216969Y674359D02*
X217325Y673947D01*
G01X216950D02*
X216594Y674359D01*
G01X213029D02*
X213111Y674264D01*
G01X213010Y673947D02*
X212654Y674359D01*
G01X228809Y676271D02*
X228399Y677397D01*
G01X226152Y683571D02*
X228178Y678006D01*
G01X223205Y685895D02*
X223263Y685526D01*
G01X222849Y685483D02*
X222907Y685114D01*
G01X222313Y674359D02*
X222254Y674728D01*
G01X221956Y673947D02*
X221898Y674316D01*
G01X219265Y685895D02*
X219323Y685526D01*
G01X218909Y685483D02*
X218967Y685114D01*
G01X218373Y674359D02*
X218314Y674728D01*
G01X218016Y673947D02*
X217958Y674316D01*
G01X215325Y685895D02*
X215383Y685526D01*
G01X214969Y685483D02*
X215027Y685114D01*
G01X214433Y674359D02*
X214415Y674471D01*
G01X211029Y685483D02*
X211046Y685371D01*
G01X210493Y674359D02*
X210475Y674471D01*
G01X233981Y674601D02*
Y670071D01*
G01Y689771D02*
Y685241D01*
G01X233031Y682171D02*
Y677671D01*
G01X232823Y682171D02*
Y677671D01*
G01X232654Y682171D02*
Y677671D01*
G01X232581Y673973D02*
Y685870D01*
G01X232399Y682171D02*
Y677671D01*
G01X232341Y682171D02*
Y684670D01*
G01Y675172D02*
Y677671D01*
G01X232178Y682171D02*
Y677671D01*
G01X232031Y685992D02*
Y673850D01*
G01X231581Y673321D02*
Y669421D01*
G01Y690421D02*
Y686521D01*
G01X231531Y677421D02*
Y673917D01*
G01Y685925D02*
Y682421D01*
G01X231321Y689771D02*
Y670071D01*
G01X231081Y682421D02*
Y677421D01*
G01X231021Y688171D02*
Y671671D01*
G01X228081Y690421D02*
Y669421D01*
G01X227531Y688171D02*
Y671671D01*
G01X224931Y673021D02*
Y674471D01*
G01X224909Y673779D02*
Y674329D01*
G01X224781Y673779D02*
Y674329D01*
G01X224636D02*
Y673779D01*
G01X224531Y678721D02*
Y674471D01*
G01X224428Y673779D02*
Y674329D01*
G01X224399Y673779D02*
Y674329D01*
G01X224388Y677586D02*
Y668729D01*
G01X223942Y677820D02*
Y674857D01*
G01X223731Y688171D02*
Y686271D01*
G01Y686071D02*
Y681971D01*
G01X223233Y674857D02*
Y677820D01*
G01X222931Y685371D02*
Y686821D01*
G01X222909Y685513D02*
Y686063D01*
G01X222781Y685513D02*
Y686063D01*
G01X222773Y668729D02*
Y677574D01*
G01X222762Y674329D02*
Y673779D01*
G01X222733Y674329D02*
Y673779D01*
G01X222636Y686063D02*
Y685513D01*
G01X222631Y678721D02*
Y674471D01*
G01X222531Y685371D02*
Y681121D01*
G01X222525Y673779D02*
Y674329D01*
G01X222428Y685513D02*
Y686063D01*
G01X222399Y685513D02*
Y686063D01*
G01X222388Y682268D02*
Y691113D01*
G01X222381Y674329D02*
Y673779D01*
G01X222252Y674329D02*
Y673779D01*
G01X222231Y674471D02*
Y673021D01*
G01X221928Y684986D02*
Y682022D01*
G01X221219D02*
Y684986D01*
G01X220991Y674471D02*
Y673021D01*
G01X220969Y673779D02*
Y674329D01*
G01X220841Y673779D02*
Y674329D01*
G01X220773Y682257D02*
Y691113D01*
G01X220762Y686063D02*
Y685513D01*
G01X220733Y686063D02*
Y685513D01*
G01X220696Y674329D02*
Y673779D01*
G01X220631Y685371D02*
Y681121D01*
G01X220591Y678721D02*
Y674471D01*
G01X220525Y685513D02*
Y686063D01*
G01X220488Y673779D02*
Y674329D01*
G01X220459Y673779D02*
Y674329D01*
G01X220448Y677586D02*
Y668729D01*
G01X220381Y686063D02*
Y685513D01*
G01X220252Y686063D02*
Y685513D01*
G01X220231Y686821D02*
Y685371D01*
G01X220002Y677820D02*
Y674857D01*
G01X219293D02*
Y677820D01*
G01X218991Y685371D02*
Y686821D01*
G01X218969Y685513D02*
Y686063D01*
G01X218841Y685513D02*
Y686063D01*
G01X218833Y668729D02*
Y677574D01*
G01X218822Y674329D02*
Y673779D01*
G01X218793Y674329D02*
Y673779D01*
G01X218696Y686063D02*
Y685513D01*
G01X218691Y678721D02*
Y674471D01*
G01X218591Y685371D02*
Y681121D01*
G01X218585Y673779D02*
Y674329D01*
G01X218488Y685513D02*
Y686063D01*
G01X218459Y685513D02*
Y686063D01*
G01X218448Y682268D02*
Y691113D01*
G01X218441Y674329D02*
Y673779D01*
G01X218312Y674329D02*
Y673779D01*
G01X218291Y674471D02*
Y673021D01*
G01X217988Y684986D02*
Y682022D01*
G01X217279D02*
Y684986D01*
G01X217051Y674471D02*
Y673021D01*
G01X217029Y673779D02*
Y674329D01*
G01X216901Y673779D02*
Y674329D01*
G01X216833Y682257D02*
Y691113D01*
G01X216822Y686063D02*
Y685513D01*
G01X216793Y686063D02*
Y685513D01*
G01X216756Y674329D02*
Y673779D01*
G01X216691Y685371D02*
Y681121D01*
G01X216651Y678721D02*
Y674471D01*
G01X216585Y685513D02*
Y686063D01*
G01X216548Y673779D02*
Y674329D01*
G01X216519Y673779D02*
Y674329D01*
G01X216508Y677586D02*
Y668729D01*
G01X216441Y686063D02*
Y685513D01*
G01X216312Y686063D02*
Y685513D01*
G01X216291Y686821D02*
Y685371D01*
G01X216062Y677820D02*
Y674857D01*
G01X215353D02*
Y677820D01*
G01X215051Y685371D02*
Y686821D01*
G01X215029Y685513D02*
Y686063D01*
G01X214901Y685513D02*
Y686063D01*
G01X214893Y668729D02*
Y677574D01*
G01X214882Y674329D02*
Y673779D01*
G01X214853Y674329D02*
Y673779D01*
G01X214756Y686063D02*
Y685513D01*
G01X214751Y673771D02*
Y670071D01*
G01Y685371D02*
Y674471D01*
G01Y689771D02*
Y686071D01*
G01X214651Y685371D02*
Y681121D01*
G01X214645Y673779D02*
Y674329D01*
G01X214548Y685513D02*
Y686063D01*
G01X214519Y685513D02*
Y686063D01*
G01X214508Y682268D02*
Y691113D01*
G01X214501Y674329D02*
Y673779D01*
G01X214372Y674329D02*
Y673779D01*
G01X214351Y674471D02*
Y673021D01*
G01X214048Y684986D02*
Y682022D01*
G01X213339D02*
Y684986D01*
G01X213111Y674471D02*
Y673021D01*
G01X213089Y673779D02*
Y674329D01*
G01X212961Y673779D02*
Y674329D01*
G01X212893Y682257D02*
Y691113D01*
G01X212882Y686063D02*
Y685513D01*
G01X212853Y686063D02*
Y685513D01*
G01X212816Y674329D02*
Y673779D01*
G01X212751Y685371D02*
Y681121D01*
G01X212711Y678721D02*
Y674471D01*
G01X212645Y685513D02*
Y686063D01*
G01X212608Y673779D02*
Y674329D01*
G01X212579Y673779D02*
Y674329D01*
G01X212568Y677586D02*
Y668729D01*
G01X212538Y670071D02*
Y671071D01*
G01X212501Y686063D02*
Y685513D01*
G01X212372Y686063D02*
Y685513D01*
G01X212351Y686821D02*
Y685371D01*
G01X212122Y677820D02*
Y674857D01*
G01X211413D02*
Y677820D01*
G01X211111Y685371D02*
Y686821D01*
G01X211089Y685513D02*
Y686063D01*
G01X211038Y671071D02*
Y670071D01*
G01X210961Y685513D02*
Y686063D01*
G01X210953Y668729D02*
Y677574D01*
G01X210942Y674329D02*
Y673779D01*
G01X210913Y674329D02*
Y673779D01*
G01X210816Y686063D02*
Y685513D01*
G01X210811Y678721D02*
Y674471D01*
G01X210711Y685371D02*
Y681121D01*
G01X210705Y673779D02*
Y674329D01*
G01X210608Y685513D02*
Y686063D01*
G01X210579Y685513D02*
Y686063D01*
G01X210568Y682268D02*
Y691113D01*
G01X210561Y674329D02*
Y673779D01*
G01X210432Y674329D02*
Y673779D01*
G01X210411Y674471D02*
Y673021D01*
G01X210108Y684986D02*
Y682022D01*
G01X209399D02*
Y684986D01*
G01X225263Y674316D02*
X225205Y673947D01*
G01X224907Y674728D02*
X224849Y674359D01*
G01X221323Y674316D02*
X221265Y673947D01*
G01X220967Y674728D02*
X220909Y674359D01*
G01X220254Y685114D02*
X220313Y685483D01*
G01X219898Y685526D02*
X219956Y685895D01*
G01X217383Y674316D02*
X217325Y673947D01*
G01X217027Y674728D02*
X216969Y674359D01*
G01X216314Y685114D02*
X216373Y685483D01*
G01X215958Y685526D02*
X216016Y685895D01*
G01X213046Y674471D02*
X213029Y674359D01*
G01X212415Y685371D02*
X212433Y685483D01*
G01X233513Y674850D02*
X232031Y673850D01*
G01X224830Y673947D02*
X225263Y674316D01*
G01X224474Y674359D02*
X224907Y674728D01*
G01X220890Y673947D02*
X221323Y674316D01*
G01X220534Y674359D02*
X220967Y674728D01*
G01X216950Y673947D02*
X217383Y674316D01*
G01X216594Y674359D02*
X217027Y674728D01*
G01X213010Y673947D02*
X213111Y674033D01*
G01X212654Y674359D02*
X212785Y674471D01*
G01X220687Y685483D02*
X220254Y685114D01*
G01X220331Y685895D02*
X219898Y685526D01*
G01X216747Y685483D02*
X216314Y685114D01*
G01X222687Y674359D02*
X222331Y673947D01*
G01X221956D02*
X222313Y674359D01*
G01X222254Y674728D02*
X221898Y674316D01*
G01X218747Y674359D02*
X218391Y673947D01*
G01X218016D02*
X218373Y674359D01*
G01X218314Y674728D02*
X217958Y674316D01*
G01X214807Y674359D02*
X214451Y673947D01*
G01X214351Y674264D02*
X214433Y674359D01*
G01X222907Y685114D02*
X223263Y685526D01*
G01X223205Y685895D02*
X222849Y685483D01*
G01X222474D02*
X222830Y685895D01*
G01X210867Y674359D02*
X210511Y673947D01*
G01X210411Y674264D02*
X210493Y674359D01*
G01X218967Y685114D02*
X219323Y685526D01*
G01X219265Y685895D02*
X218909Y685483D01*
G01X218534D02*
X218890Y685895D01*
G01X215027Y685114D02*
X215383Y685526D01*
G01X215325Y685895D02*
X214969Y685483D01*
G01X214594D02*
X214950Y685895D01*
G01X211111Y685578D02*
X211029Y685483D01*
G01X210654D02*
X211010Y685895D01*
G01X216391D02*
X215958Y685526D01*
G01X212807Y685483D02*
X212676Y685371D01*
G01X212451Y685895D02*
X212351Y685810D01*
G01X275709Y0D02*
G03X279646Y3937I0J3937D01*
G01X291457Y0D02*
X921260D01*
G01X287520Y3937D02*
G03X291457Y0I3937J0D01*
G01X339921Y-1575D02*
X339330Y-2165D01*
G01X339921Y-1575D02*
Y97244D01*
G01X338740Y-2165D02*
Y97244D01*
G01X339921Y-197D02*
X338740D01*
G01X339921Y-1575D02*
X360078D01*
G01X361260Y-2165D02*
X338740D01*
G01X287520Y429331D02*
Y3937D01*
G01X279646Y59055D02*
Y3937D01*
G01X287520Y59055D02*
G03X279646I-3937J0D01*
G01X287520D02*
G03X279646I-3937J0D01*
G01X338759Y54539D02*
X338740Y54704D01*
G01X338815Y54383D02*
X338759Y54539D01*
G01X338906Y54240D02*
X338815Y54383D01*
G01X339028Y54114D02*
X338906Y54240D01*
G01X339179Y54009D02*
X339028Y54114D01*
G01X339349Y53932D02*
X339179Y54009D01*
G01X339533Y53885D02*
X339349Y53932D01*
G01X339724Y53869D02*
X339533Y53885D01*
G01X340008Y12694D02*
X340017Y12668D01*
G01X339992Y12717D02*
X340008Y12694D01*
G01X339971Y12737D02*
X339992Y12717D01*
G01X339927Y12804D02*
X339921Y12843D01*
G01X339944Y12768D02*
X339927Y12804D01*
G01X339971Y12737D02*
X339944Y12768D01*
G01X339726Y63089D02*
X339527Y63106D01*
G01X339916Y63038D02*
X339726Y63089D01*
G01X340090Y62956D02*
X339916Y63038D01*
G01X340243Y62844D02*
X340090Y62956D01*
G01X340364Y62710D02*
X340243Y62844D01*
G01X340451Y62559D02*
X340364Y62710D01*
G01X340304Y61759D02*
X340410Y61902D01*
G01X340167Y61637D02*
X340304Y61759D01*
G01X340004Y61541D02*
X340167Y61637D01*
G01X339821Y61474D02*
X340004Y61541D01*
G01X339423Y61405D02*
X339821Y61474D01*
G01X337397Y62979D02*
X337362Y62793D01*
G01X337498Y63154D02*
X337397Y62979D01*
G01X337661Y63315D02*
X337498Y63154D01*
G01X337881Y63457D02*
X337661Y63315D01*
G01X338153Y63575D02*
X337881Y63457D01*
G01X338458Y63661D02*
X338153Y63575D01*
G01X338789Y63714D02*
X338458Y63661D01*
G01X339134Y63732D02*
X338789Y63714D01*
G01X339822Y62101D02*
X339424Y62031D01*
G01X340004Y62167D02*
X339822Y62101D01*
G01X340168Y62263D02*
X340004Y62167D01*
G01X340307Y62388D02*
X340168Y62263D01*
G01X340412Y62531D02*
X340307Y62388D01*
G01X340362Y63339D02*
X340450Y63188D01*
G01X340240Y63473D02*
X340362Y63339D01*
G01X340089Y63583D02*
X340240Y63473D01*
G01X339915Y63664D02*
X340089Y63583D01*
G01X339725Y63715D02*
X339915Y63664D01*
G01X339527Y63732D02*
X339725Y63715D01*
G01X338192Y63074D02*
X338149Y63482D01*
G01X338322Y62705D02*
X338192Y63074D01*
G01X338543Y62398D02*
X338322Y62705D01*
G01X340073Y12401D02*
X340001Y12583D01*
G01X340189Y12227D02*
X340073Y12401D01*
G01X339931Y12937D02*
X339921Y13000D01*
G01X339962Y12880D02*
X339931Y12937D01*
G01X339990Y12830D02*
X339962Y12880D01*
G01X340002Y12775D02*
X339990Y12830D01*
G01X339942Y12648D02*
X340017Y12422D01*
G01X339921Y12843D02*
X339942Y12648D01*
G01X340005Y12746D02*
X340003Y12767D01*
G01X340017Y12668D02*
X340005Y12746D01*
G01X339530Y54512D02*
X339724Y54495D01*
G01X339346Y54559D02*
X339530Y54512D01*
G01X339177Y54636D02*
X339346Y54559D01*
G01X339028Y54740D02*
X339177Y54636D01*
G01X338904Y54868D02*
X339028Y54740D01*
G01X338814Y55012D02*
X338904Y54868D01*
G01X338759Y55168D02*
X338814Y55012D01*
G01X338740Y55330D02*
X338759Y55168D01*
G01X339745Y55722D02*
X339921Y55462D01*
G01X339623Y55973D02*
X339745Y55722D01*
G01X339551Y56207D02*
X339623Y55973D01*
G01X339527Y56417D02*
X339551Y56207D01*
G01X338913Y55718D02*
X338740Y55462D01*
G01X339036Y55968D02*
X338913Y55718D01*
G01X339109Y56203D02*
X339036Y55968D01*
G01X339134Y56417D02*
X339109Y56203D01*
G01X339232Y61333D02*
X339423Y61405D01*
G01X339066Y61231D02*
X339232Y61333D01*
G01X338928Y61101D02*
X339066Y61231D01*
G01X338825Y60950D02*
X338928Y61101D01*
G01X338761Y60784D02*
X338825Y60950D01*
G01X338740Y60610D02*
X338761Y60784D01*
G01X339017Y63100D02*
X339134Y63106D01*
G01X338907Y63082D02*
X339017Y63100D01*
G01X338805Y63053D02*
X338907Y63082D01*
G01X338716Y63014D02*
X338805Y63053D01*
G01X338642Y62966D02*
X338716Y63014D01*
G01X338588Y62912D02*
X338642Y62966D01*
G01X338554Y62854D02*
X338588Y62912D01*
G01X338543Y62793D02*
X338554Y62854D01*
G01X339436Y5121D02*
X339554Y5288D01*
G01X339357Y5007D02*
X339436Y5121D01*
G01X338762Y61411D02*
X338740Y61236D01*
G01X338827Y61579D02*
X338762Y61411D01*
G01X338931Y61730D02*
X338827Y61579D01*
G01X339069Y61859D02*
X338931Y61730D01*
G01X339236Y61961D02*
X339069Y61859D01*
G01X339424Y62031D02*
X339236Y61961D01*
G01X339386Y4996D02*
X339430Y5042D01*
G01X339274Y4938D02*
X339386Y4996D01*
G01X339724Y42520D02*
G03X339921Y42323I197J0D01*
G01X338543Y42520D02*
G03X338740Y41810I1378J0D01*
G01X340002Y12775D02*
G03X339962Y12880I-196J-15D01*
G01X339921Y13000D02*
G03X339962Y12880I196J0D01*
G01X340002Y12775D02*
G03X340265Y12203I903J69D01*
G01X340189Y12227D02*
G03X340237Y12175I718J614D01*
G01X339921Y12843D02*
G03X340209Y12147I985J0D01*
G01X338740Y12843D02*
G03X339374Y11312I2166J0D01*
G01X339833Y10965D02*
G03X339721Y11020I-139J-141D01*
G01X339610Y11076D02*
G03X339721Y11020I140J139D01*
G01X339085Y6677D02*
G03X338985Y6603I61J-187D01*
G01X339085Y6677D02*
G03X339185Y6751I-61J187D01*
G01X339330Y4967D02*
G03X339430Y5042I-62J187D01*
G01X339330Y4967D02*
G03X339230Y4893I61J-187D01*
G01X340219Y12252D02*
X340159Y12201D01*
G01X340139Y10658D02*
X340083Y10603D01*
G01X340265Y12203D02*
X339374Y11312D01*
G01X340019Y45197D02*
X340610Y45787D01*
G01X339386Y4996D02*
X339430Y5042D01*
G01X339230Y4893D02*
X339274Y4938D01*
G01X341611Y8225D02*
X339435Y5119D01*
G01X341643Y8202D02*
X339430Y5042D01*
G01X341578Y8247D02*
X338339Y3620D01*
G01X340675Y8879D02*
X339185Y6751D01*
G01X340643Y8902D02*
X339085Y6677D01*
G01X340611Y8925D02*
X337823Y4943D01*
G01X339330Y4967D02*
X339357Y5007D01*
G01D02*
X339330Y4967D01*
G01X340118Y97067D02*
Y45886D01*
G01X340019Y51496D02*
Y30433D01*
G01X339724Y53869D02*
Y54495D01*
G01Y49421D02*
Y42520D01*
G01X339626Y62067D02*
Y61441D01*
G01X339527Y96319D02*
Y56417D01*
G01X339232Y49421D02*
Y50984D01*
G01Y47756D02*
Y45197D01*
G01Y89961D02*
Y53346D01*
G01X339134Y56417D02*
Y97165D01*
G01X338543Y97445D02*
Y42520D01*
G01X338149Y63482D02*
Y91573D01*
G01X337362Y97445D02*
Y62003D01*
G01X339962Y12864D02*
Y12880D01*
G01Y12864D02*
X339965Y12815D01*
G01D02*
X339971Y12737D01*
G01X337823Y4943D02*
X338016Y3846D01*
G01X339971Y12737D02*
X340001Y12582D01*
G01X340002Y12775D02*
X339990Y12830D01*
G01X339232Y45197D02*
X340019Y42258D01*
G01X340052Y12544D02*
X340017Y12668D01*
G01X340120Y12396D02*
X340051Y12547D01*
G01X339962Y12880D02*
X339931Y12937D01*
G01X340017Y12422D02*
X340159Y12201D01*
G01X340219Y12252D02*
X340118Y12399D01*
G01X339232Y66063D02*
X338740D01*
G01X339232Y65276D02*
X338740D01*
G01X339527Y63732D02*
X339134D01*
G01X337362Y63482D02*
X338149D01*
G01X339527Y63106D02*
X339134D01*
G01X338543Y62480D02*
X337362D01*
G01Y62001D02*
X338543D01*
G01X339527Y56417D02*
X339134D01*
G01X338740Y55379D02*
X339232D01*
G01Y54845D02*
X338740D01*
G01Y54828D02*
X339921D01*
G01X340512Y54495D02*
X339724D01*
G01X339921Y54232D02*
X338740D01*
G01Y54161D02*
X339921D01*
G01Y54101D02*
X338740D01*
G01X340512Y53869D02*
X339724D01*
G01X339921Y53418D02*
X338740D01*
G01X339921Y53346D02*
X338740D01*
G01Y52472D02*
X339921D01*
G01X340019Y40866D02*
X341201Y39685D01*
G01X341988Y28465D02*
X340019Y30433D01*
G01X340265Y12203D02*
X341392Y11076D01*
G01X340237Y12175D02*
X341364Y11048D01*
G01X340209Y12147D02*
X341336Y11020D01*
G01X339833Y10965D02*
X340556Y10241D01*
G01X339721Y11020D02*
X340529Y10213D01*
G01X339374Y11312D02*
X340501Y10185D01*
G01X346063Y51969D02*
X338740D01*
G01X340019Y51496D02*
X359980D01*
G01X339921Y50984D02*
X338740D01*
G01X339232Y49421D02*
X341201D01*
G01X339921Y48622D02*
X338740D01*
G01X339921Y47953D02*
X338740D01*
G01X340019Y47756D02*
X339232D01*
G01X339921Y47135D02*
X338740D01*
G01X341201Y46870D02*
X340118D01*
G01X339921Y46483D02*
X338740D01*
G01X339921Y46260D02*
X338740D01*
G01Y46189D02*
X339921D01*
G01X340118Y45886D02*
X342972D01*
G01X339921Y45802D02*
X338740D01*
G01Y45505D02*
X339921D01*
G01Y45445D02*
X338740D01*
G01X339921Y45374D02*
X338740D01*
G01Y44291D02*
X338543D01*
G01X339921D02*
X339724D01*
G01X343248Y44016D02*
X340019D01*
G01X338740Y43898D02*
X343661D01*
G01X339921Y41654D02*
X338740D01*
G01X339921Y40866D02*
X338740D01*
G01X359980D02*
X340019D01*
G01Y34370D02*
X359980D01*
G01X338740Y27756D02*
X339921D01*
G01Y26697D02*
X338740D01*
G01X339921Y26453D02*
X338740D01*
G01X339921Y12843D02*
X338740D01*
G01X339369Y7151D02*
X339433Y7106D01*
G01X339659Y5506D02*
X339724Y5461D01*
G01X337877Y5020D02*
X338845Y4343D01*
G01X338016Y3846D02*
X338339Y3620D01*
G01X339921Y2803D02*
X338740D01*
G01X279646Y98425D02*
Y421457D01*
G01Y98425D02*
G03X287520I3937J0D01*
G01X279646D02*
G03X287520I3937J0D01*
G01X340195Y96555D02*
X340470Y96605D01*
G01X339921Y96539D02*
X340195Y96555D01*
G01X338555Y96288D02*
X338543Y96226D01*
G01X338588Y96346D02*
X338555Y96288D01*
G01X338643Y96400D02*
X338588Y96346D01*
G01X338716Y96447D02*
X338643Y96400D01*
G01X338807Y96487D02*
X338716Y96447D01*
G01X338909Y96515D02*
X338807Y96487D01*
G01X339019Y96533D02*
X338909Y96515D01*
G01X339134Y96539D02*
X339019Y96533D01*
G01X338960Y96912D02*
X338740Y97112D01*
G01X339092Y96639D02*
X338960Y96912D01*
G01X339134Y96319D02*
X339092Y96639D01*
G01X338322Y92534D02*
X338543Y93075D01*
G01X338192Y92026D02*
X338322Y92534D01*
G01X338149Y91573D02*
X338192Y92026D01*
G01X338783Y97146D02*
X339134Y97165D01*
G01X338453Y97093D02*
X338783Y97146D01*
G01X338148Y97006D02*
X338453Y97093D01*
G01X337881Y96890D02*
X338148Y97006D01*
G01X337658Y96745D02*
X337881Y96890D01*
G01X337496Y96584D02*
X337658Y96745D01*
G01X337396Y96408D02*
X337496Y96584D01*
G01X337362Y96226D02*
X337396Y96408D01*
G01X339568Y96633D02*
X339527Y96319D01*
G01X339698Y96908D02*
X339568Y96633D01*
G01X339921Y97112D02*
X339698Y96908D01*
G01X340204Y97182D02*
X339921Y97165D01*
G01X340479Y97233D02*
X340204Y97182D01*
G01X339134Y98035D02*
G03X338543Y97445I0J-591D01*
G01X338740Y82206D02*
G03X338543Y81496I1181J-710D01*
G01X339134Y99216D02*
G03X337362Y97445I0J-1772D01*
G01X338628Y88306D02*
G03X338346Y86844I3655J-1463D01*
G01X337531Y88745D02*
G03X337165Y86844I4752J-1901D01*
G01X338543Y80751D02*
X337953Y79728D01*
G01X340708Y88742D02*
X340124Y87618D01*
G01X339232Y89817D02*
X338628Y88306D01*
G01X337531Y88745D02*
X338740Y91767D01*
G01X340124Y87618D02*
X340708Y89867D01*
G01X340040Y98035D02*
Y99216D01*
G01X339527D02*
Y98035D01*
G01X339232Y96181D02*
Y93898D01*
G01X338346Y84452D02*
Y86844D01*
G01X337165D02*
Y84452D01*
G01X339134Y68764D02*
X339232Y68553D01*
G01X339134Y99216D02*
X360866D01*
G01X339134Y98035D02*
X360866D01*
G01X339921Y97244D02*
X338740D01*
G01X339134Y97165D02*
X339921D01*
G01X340118Y97067D02*
X349803D01*
G01X339134Y96539D02*
X339921D01*
G01X339134Y96319D02*
X339527D01*
G01X339232Y96181D02*
X342677D01*
G01X338740Y95930D02*
X339232D01*
G01X337362Y95913D02*
X338543D01*
G01X339232Y95396D02*
X338740D01*
G01X338543Y94098D02*
X337362D01*
G01X339921Y93898D02*
X338740D01*
G01X339921Y93831D02*
X338740D01*
G01X338543Y93311D02*
X337362D01*
G01X338740Y93069D02*
X339921D01*
G01Y92308D02*
X338740D01*
G01X338149Y91573D02*
X337362D01*
G01X338740Y91550D02*
X339921D01*
G01Y90790D02*
X338740D01*
G01Y90028D02*
X339921D01*
G01Y89961D02*
X338740D01*
G01X339232Y88462D02*
X338740D01*
G01X339232Y87928D02*
X338740D01*
G01X340124Y87618D02*
X347795D01*
G01X338346Y84452D02*
X337165D01*
G01X339232D02*
X338740D01*
G01X338543Y84256D02*
X337362D01*
G01Y83862D02*
X338543D01*
G01X339232D02*
X338740D01*
G01X338543Y83468D02*
X337362D01*
G01X339232Y82484D02*
X338740D01*
G01X339232Y82287D02*
X338740D01*
G01Y82062D02*
X339232D01*
G01X338543Y81697D02*
X337362D01*
G01X339232Y81500D02*
X338740D01*
G01X337953Y79728D02*
X337362D01*
G01X338740Y79724D02*
X338543D01*
G01X339232Y75118D02*
X338740D01*
G01X339232Y74921D02*
X339134D01*
G01X338740Y73649D02*
X339232D01*
G01Y72967D02*
X338740D01*
G01X315551Y157677D02*
G03X302559I-6496J0D01*
G01D02*
G03X315551I6496J0D01*
G01X306231Y183650D02*
X305905Y183716D01*
G01X306504Y183466D02*
X306231Y183650D01*
G01X306685Y183193D02*
X306504Y183466D01*
G01X306747Y182871D02*
X306685Y183193D01*
G01X306682Y182549D02*
X306747Y182871D01*
G01X306501Y182279D02*
X306682Y182549D01*
G01X306229Y182097D02*
X306501Y182279D01*
G01X305905Y182032D02*
X306229Y182097D01*
G01X311614Y186496D02*
G03X312401Y187283I0J787D01*
G01X299409Y184547D02*
G03X300197Y183760I787J0D01*
G01X304527D02*
G03X305315Y184542I0J788D01*
G01X305905Y183701D02*
G03Y182047I0J-827D01*
G01X307283Y185709D02*
G03X306102Y184536I0J-1181D01*
G01X311614Y185709D02*
G03X313189Y187283I0J1575D01*
G01X298622Y184547D02*
G03X300197Y182972I1575J0D01*
G01X304527D02*
G03X306102Y184536I0J1575D01*
G01X307283Y186496D02*
G03X305315Y184542I0J-1968D01*
G01X315748Y179724D02*
G03X317716Y181693I0J1968D01*
G01X294094D02*
G03X296063Y179724I1969J0D01*
G01X307924Y182874D02*
G03I-2019J0D01*
G01X308071D02*
G03I-2166J0D01*
G01X316141Y184496D02*
X314567Y183586D01*
G01X302874Y187933D02*
X303661Y188720D01*
G01X317716Y181693D02*
Y189075D01*
G01X316929Y185236D02*
Y182087D01*
G01X316732Y193307D02*
Y192126D01*
G01Y196457D02*
Y195276D01*
G01Y199606D02*
Y198425D01*
G01X316141Y184496D02*
Y182677D01*
G01X313779Y185236D02*
Y182087D01*
G01X313189Y187283D02*
Y383976D01*
G01X312401Y187283D02*
Y383976D01*
G01X311614Y185709D02*
Y186496D01*
G01X309842Y180512D02*
Y179724D01*
G01X308937Y383327D02*
Y187933D01*
G01X308858Y193307D02*
Y192126D01*
G01Y196457D02*
Y195276D01*
G01Y199606D02*
Y198425D01*
G01X308149Y382539D02*
Y188720D01*
G01X307283Y186496D02*
Y185709D01*
G01X306102Y184536D02*
X305315Y184542D01*
G01X302953Y198425D02*
X295078D01*
G01X316732D02*
X308858D01*
G01X302953Y196457D02*
X295078D01*
G01X316732D02*
X308858D01*
G01X302953Y195276D02*
X295078D01*
G01X316732D02*
X308858D01*
G01X302953Y193307D02*
X295078D01*
G01X316732D02*
X308858D01*
G01X302953Y192126D02*
X295078D01*
G01X316732D02*
X308858D01*
G01X299409Y189075D02*
X294094D01*
G01X317716D02*
X312401D01*
G01X308149Y188720D02*
X303661D01*
G01X308937Y187933D02*
X302874D01*
G01X317716Y187500D02*
X294094D01*
G01X312401Y187283D02*
X313189D01*
G01X307283Y186496D02*
X311614D01*
G01Y185709D02*
X307283D01*
G01X316929Y185236D02*
X313779D01*
G01X298622Y184547D02*
X299409D01*
G01X300197Y183760D02*
X304527D01*
G01Y182972D02*
X300197D01*
G01X316929Y182087D02*
X313779D01*
G01X309842Y180512D02*
X301968D01*
G01Y179724D02*
X296063D01*
G01X315748D02*
X309842D01*
G01X305905Y180856D02*
Y182032D01*
G01Y183716D02*
Y184893D01*
G01X304527Y182972D02*
Y183760D01*
G01X303661Y382539D02*
Y188720D01*
G01X302953Y193307D02*
Y192126D01*
G01Y196457D02*
Y195276D01*
G01Y199606D02*
Y198425D01*
G01X302874Y187933D02*
Y383327D01*
G01X301968Y180512D02*
Y179724D01*
G01X300197Y183760D02*
Y182972D01*
G01X299409Y386713D02*
Y184547D01*
G01X298622D02*
Y386713D01*
G01X295078Y193307D02*
Y192126D01*
G01Y196457D02*
Y195276D01*
G01Y199606D02*
Y198425D01*
G01X294094Y189075D02*
Y181693D01*
G01X316141Y182677D02*
X314567Y183586D01*
G01X308149Y188720D02*
X308937Y187933D01*
G01X302953Y264567D02*
X295078D01*
G01X316732D02*
X308858D01*
G01X302953Y262598D02*
X295078D01*
G01X316732D02*
X308858D01*
G01X299409Y262008D02*
X298622D01*
G01X313189D02*
X312401D01*
G01X302953Y261417D02*
X295078D01*
G01X316732D02*
X308858D01*
G01X302953Y259449D02*
X295078D01*
G01X316732D02*
X308858D01*
G01X302953Y258268D02*
X295078D01*
G01X316732D02*
X308858D01*
G01X302953Y256299D02*
X295078D01*
G01X316732D02*
X308858D01*
G01X302953Y255118D02*
X295078D01*
G01X316732D02*
X308858D01*
G01X302953Y253150D02*
X295078D01*
G01X316732D02*
X308858D01*
G01X299409Y252559D02*
X298622D01*
G01X313189D02*
X312401D01*
G01X302953Y251969D02*
X295078D01*
G01X316732D02*
X308858D01*
G01X302953Y250000D02*
X295078D01*
G01X316732D02*
X308858D01*
G01X302953Y248819D02*
X295078D01*
G01X316732D02*
X308858D01*
G01X302953Y246850D02*
X295078D01*
G01X316732D02*
X308858D01*
G01X299409Y246260D02*
X298622D01*
G01X313189D02*
X312401D01*
G01X302953Y245669D02*
X295078D01*
G01X316732D02*
X308858D01*
G01X302953Y243701D02*
X295078D01*
G01X316732D02*
X308858D01*
G01X302953Y242520D02*
X295078D01*
G01X316732D02*
X308858D01*
G01X302953Y240551D02*
X295078D01*
G01X316732D02*
X308858D01*
G01X302953Y239370D02*
X295078D01*
G01X316732D02*
X308858D01*
G01X302953Y237402D02*
X295078D01*
G01X316732D02*
X308858D01*
G01X302953Y236220D02*
X295078D01*
G01X316732D02*
X308858D01*
G01X302953Y234252D02*
X295078D01*
G01X316732D02*
X308858D01*
G01X302953Y233071D02*
X295078D01*
G01X316732D02*
X308858D01*
G01X302953Y231102D02*
X295078D01*
G01X316732D02*
X308858D01*
G01X302953Y229921D02*
X295078D01*
G01X316732D02*
X308858D01*
G01X302953Y227953D02*
X295078D01*
G01X316732D02*
X308858D01*
G01X302953Y226772D02*
X295078D01*
G01X316732D02*
X308858D01*
G01X302953Y224803D02*
X295078D01*
G01X316732D02*
X308858D01*
G01X302953Y223622D02*
X295078D01*
G01X316732D02*
X308858D01*
G01X302953Y221654D02*
X295078D01*
G01X316732D02*
X308858D01*
G01X302953Y220472D02*
X295078D01*
G01X316732D02*
X308858D01*
G01X302953Y218504D02*
X295078D01*
G01X316732D02*
X308858D01*
G01X302953Y217323D02*
X295078D01*
G01X316732D02*
X308858D01*
G01X302953Y215354D02*
X295078D01*
G01X316732D02*
X308858D01*
G01X316732Y202756D02*
Y201575D01*
G01Y205906D02*
Y204724D01*
G01Y209055D02*
Y207874D01*
G01Y212205D02*
Y211024D01*
G01Y215354D02*
Y214173D01*
G01Y218504D02*
Y217323D01*
G01Y221654D02*
Y220472D01*
G01Y224803D02*
Y223622D01*
G01Y227953D02*
Y226772D01*
G01Y231102D02*
Y229921D01*
G01Y234252D02*
Y233071D01*
G01Y237402D02*
Y236220D01*
G01Y240551D02*
Y239370D01*
G01Y243701D02*
Y242520D01*
G01Y246850D02*
Y245669D01*
G01Y250000D02*
Y248819D01*
G01Y253150D02*
Y251969D01*
G01Y256299D02*
Y255118D01*
G01Y259449D02*
Y258268D01*
G01Y262598D02*
Y261417D01*
G01Y265748D02*
Y264567D01*
G01X308858Y202756D02*
Y201575D01*
G01Y205906D02*
Y204724D01*
G01Y209055D02*
Y207874D01*
G01Y212205D02*
Y211024D01*
G01Y215354D02*
Y214173D01*
G01Y218504D02*
Y217323D01*
G01Y221654D02*
Y220472D01*
G01Y224803D02*
Y223622D01*
G01Y227953D02*
Y226772D01*
G01Y231102D02*
Y229921D01*
G01Y234252D02*
Y233071D01*
G01Y237402D02*
Y236220D01*
G01Y240551D02*
Y239370D01*
G01Y243701D02*
Y242520D01*
G01Y246850D02*
Y245669D01*
G01Y250000D02*
Y248819D01*
G01Y253150D02*
Y251969D01*
G01Y256299D02*
Y255118D01*
G01Y259449D02*
Y258268D01*
G01Y262598D02*
Y261417D01*
G01Y265748D02*
Y264567D01*
G01X302953Y214173D02*
X295078D01*
G01X316732D02*
X308858D01*
G01X302953Y212205D02*
X295078D01*
G01X316732D02*
X308858D01*
G01X302953Y211024D02*
X295078D01*
G01X316732D02*
X308858D01*
G01X302953Y209055D02*
X295078D01*
G01X316732D02*
X308858D01*
G01X302953Y207874D02*
X295078D01*
G01X316732D02*
X308858D01*
G01X302953Y205906D02*
X295078D01*
G01X316732D02*
X308858D01*
G01X302953Y204724D02*
X295078D01*
G01X316732D02*
X308858D01*
G01X302953Y202756D02*
X295078D01*
G01X316732D02*
X308858D01*
G01X302953Y201575D02*
X295078D01*
G01X316732D02*
X308858D01*
G01X302953Y199606D02*
X295078D01*
G01X316732D02*
X308858D01*
G01X302953Y202756D02*
Y201575D01*
G01Y205906D02*
Y204724D01*
G01Y209055D02*
Y207874D01*
G01Y212205D02*
Y211024D01*
G01Y215354D02*
Y214173D01*
G01Y218504D02*
Y217323D01*
G01Y221654D02*
Y220472D01*
G01Y224803D02*
Y223622D01*
G01Y227953D02*
Y226772D01*
G01Y231102D02*
Y229921D01*
G01Y234252D02*
Y233071D01*
G01Y237402D02*
Y236220D01*
G01Y240551D02*
Y239370D01*
G01Y243701D02*
Y242520D01*
G01Y246850D02*
Y245669D01*
G01Y250000D02*
Y248819D01*
G01Y253150D02*
Y251969D01*
G01Y256299D02*
Y255118D01*
G01Y259449D02*
Y258268D01*
G01Y262598D02*
Y261417D01*
G01Y265748D02*
Y264567D01*
G01X295078Y202756D02*
Y201575D01*
G01Y209055D02*
Y207874D01*
G01Y205906D02*
Y204724D01*
G01Y212205D02*
Y211024D01*
G01Y215354D02*
Y214173D01*
G01Y218504D02*
Y217323D01*
G01Y221654D02*
Y220472D01*
G01Y224803D02*
Y223622D01*
G01Y227953D02*
Y226772D01*
G01Y231102D02*
Y229921D01*
G01Y234252D02*
Y233071D01*
G01Y237402D02*
Y236220D01*
G01Y240551D02*
Y239370D01*
G01Y243701D02*
Y242520D01*
G01Y246850D02*
Y245669D01*
G01Y250000D02*
Y248819D01*
G01Y253150D02*
Y251969D01*
G01Y256299D02*
Y255118D01*
G01Y259449D02*
Y258268D01*
G01Y262598D02*
Y261417D01*
G01Y265748D02*
Y264567D01*
G01X302953Y328740D02*
X295078D01*
G01X316732D02*
X308858D01*
G01X302953Y327559D02*
X295078D01*
G01X316732D02*
X308858D01*
G01X302953Y325591D02*
X295078D01*
G01X316732D02*
X308858D01*
G01X298622Y325000D02*
X299409D01*
G01X313189D02*
X312401D01*
G01X302953Y324409D02*
X295078D01*
G01X316732D02*
X308858D01*
G01X302953Y322441D02*
X295078D01*
G01X316732D02*
X308858D01*
G01X302953Y321260D02*
X295078D01*
G01X316732D02*
X308858D01*
G01X302953Y319291D02*
X295078D01*
G01X316732D02*
X308858D01*
G01X312401Y318701D02*
X313189D01*
G01X299409D02*
X298622D01*
G01X302953Y318110D02*
X295078D01*
G01X316732D02*
X308858D01*
G01X302953Y316142D02*
X295078D01*
G01X316732D02*
X308858D01*
G01X302953Y314961D02*
X295078D01*
G01X316732D02*
X308858D01*
G01X302953Y312992D02*
X295078D01*
G01X316732D02*
X308858D01*
G01X302953Y311811D02*
X295078D01*
G01X316732D02*
X308858D01*
G01X302953Y309843D02*
X295078D01*
G01X316732D02*
X308858D01*
G01X299409Y309252D02*
X298622D01*
G01X313189D02*
X312401D01*
G01X302953Y308661D02*
X295078D01*
G01X316732D02*
X308858D01*
G01X302953Y306693D02*
X295078D01*
G01X316732D02*
X308858D01*
G01X302953Y305512D02*
X295078D01*
G01X316732D02*
X308858D01*
G01X302953Y303543D02*
X295078D01*
G01X316732D02*
X308858D01*
G01X312401Y302953D02*
X313189D01*
G01X299409D02*
X298622D01*
G01X302953Y302362D02*
X295078D01*
G01X316732D02*
X308858D01*
G01X302953Y300394D02*
X295078D01*
G01X316732D02*
X308858D01*
G01X302953Y299213D02*
X295078D01*
G01X316732D02*
X308858D01*
G01X302953Y297244D02*
X295078D01*
G01X316732D02*
X308858D01*
G01X302953Y296063D02*
X295078D01*
G01X316732D02*
X308858D01*
G01X302953Y294094D02*
X295078D01*
G01X316732D02*
X308858D01*
G01X302953Y292913D02*
X295078D01*
G01X316732D02*
X308858D01*
G01X299449Y291535D02*
X299409D01*
G01X302953Y290945D02*
X295078D01*
G01X316732D02*
X308858D01*
G01X299449Y290822D02*
X299409D01*
G01X302953Y289764D02*
X295078D01*
G01X316732D02*
X308858D01*
G01X302953Y287795D02*
X295078D01*
G01X316732D02*
X308858D01*
G01X299449Y287730D02*
X299409D01*
G01X299449Y287254D02*
X299409D01*
G01X302953Y286614D02*
X295078D01*
G01X316732D02*
X308858D01*
G01X299449Y286302D02*
X299409D01*
G01X299449Y286184D02*
X299409D01*
G01X299449Y285946D02*
X299409D01*
G01X299449Y285589D02*
X299409D01*
G01X299449Y285470D02*
X299409D01*
G01X299449Y285232D02*
X299409D01*
G01X299449Y284994D02*
X299409D01*
G01X299449Y284875D02*
X299409D01*
G01X302953Y284646D02*
X295078D01*
G01X316732D02*
X308858D01*
G01X299449Y284400D02*
X299409D01*
G01X302953Y283465D02*
X295078D01*
G01X316732D02*
X308858D01*
G01X299449Y283329D02*
X299409D01*
G01X299449Y282854D02*
X299409D01*
G01X299449Y282735D02*
X299409D01*
G01X299449Y282497D02*
X299409D01*
G01X299449Y282378D02*
X299409D01*
G01X299449Y282259D02*
X299409D01*
G01X299449Y281783D02*
X299409D01*
G01X299449Y281664D02*
X299409D01*
G01X302953Y281496D02*
X295078D01*
G01X316732D02*
X308858D01*
G01X299449Y280713D02*
X299409D01*
G01X302953Y280315D02*
X295078D01*
G01X316732D02*
X308858D01*
G01X299449Y279999D02*
X299409D01*
G01X302953Y278346D02*
X295078D01*
G01X316732D02*
X308858D01*
G01X302953Y277165D02*
X295078D01*
G01X316732D02*
X308858D01*
G01X302953Y275197D02*
X295078D01*
G01X316732D02*
X308858D01*
G01X302953Y274016D02*
X295078D01*
G01X316732D02*
X308858D01*
G01X302953Y272047D02*
X295078D01*
G01X316732D02*
X308858D01*
G01X302953Y270866D02*
X295078D01*
G01X316732D02*
X308858D01*
G01X302953Y268898D02*
X295078D01*
G01X316732D02*
X308858D01*
G01X299409Y268307D02*
X298622D01*
G01X313189D02*
X312401D01*
G01X302953Y267717D02*
X295078D01*
G01X316732D02*
X308858D01*
G01X302953Y265748D02*
X295078D01*
G01X316732D02*
X308858D01*
G01X316732Y268898D02*
Y267717D01*
G01Y272047D02*
Y270866D01*
G01Y275197D02*
Y274016D01*
G01Y278346D02*
Y277165D01*
G01Y281496D02*
Y280315D01*
G01Y284646D02*
Y283465D01*
G01Y287795D02*
Y286614D01*
G01Y290945D02*
Y289764D01*
G01Y294094D02*
Y292913D01*
G01Y297244D02*
Y296063D01*
G01Y300394D02*
Y299213D01*
G01Y303543D02*
Y302362D01*
G01Y306693D02*
Y305512D01*
G01Y309843D02*
Y308661D01*
G01Y312992D02*
Y311811D01*
G01Y316142D02*
Y314961D01*
G01Y319291D02*
Y318110D01*
G01Y322441D02*
Y321260D01*
G01Y325591D02*
Y324409D01*
G01Y328740D02*
Y327559D01*
G01X308858Y268898D02*
Y267717D01*
G01Y272047D02*
Y270866D01*
G01Y275197D02*
Y274016D01*
G01Y278346D02*
Y277165D01*
G01Y281496D02*
Y280315D01*
G01Y284646D02*
Y283465D01*
G01Y287795D02*
Y286614D01*
G01Y290945D02*
Y289764D01*
G01Y294094D02*
Y292913D01*
G01Y297244D02*
Y296063D01*
G01Y300394D02*
Y299213D01*
G01Y303543D02*
Y302362D01*
G01Y306693D02*
Y305512D01*
G01Y309843D02*
Y308661D01*
G01Y312992D02*
Y311811D01*
G01Y316142D02*
Y314961D01*
G01Y319291D02*
Y318110D01*
G01Y322441D02*
Y321260D01*
G01Y325591D02*
Y324409D01*
G01Y328740D02*
Y327559D01*
G01X302953Y268898D02*
Y267717D01*
G01Y272047D02*
Y270866D01*
G01Y275197D02*
Y274016D01*
G01Y278346D02*
Y277165D01*
G01Y281496D02*
Y280315D01*
G01Y284646D02*
Y283465D01*
G01Y287795D02*
Y286614D01*
G01Y290945D02*
Y289764D01*
G01Y294094D02*
Y292913D01*
G01Y297244D02*
Y296063D01*
G01Y300394D02*
Y299213D01*
G01Y303543D02*
Y302362D01*
G01Y306693D02*
Y305512D01*
G01Y309843D02*
Y308661D01*
G01Y312992D02*
Y311811D01*
G01Y316142D02*
Y314961D01*
G01Y319291D02*
Y318110D01*
G01Y322441D02*
Y321260D01*
G01Y325591D02*
Y324409D01*
G01Y328740D02*
Y327559D01*
G01X299449Y280713D02*
Y279999D01*
G01Y286302D02*
Y281664D01*
G01Y291535D02*
Y287254D01*
G01X295078Y272047D02*
Y270866D01*
G01Y268898D02*
Y267717D01*
G01Y275197D02*
Y274016D01*
G01Y278346D02*
Y277165D01*
G01Y281496D02*
Y280315D01*
G01Y284646D02*
Y283465D01*
G01Y287795D02*
Y286614D01*
G01Y290945D02*
Y289764D01*
G01Y294094D02*
Y292913D01*
G01Y297244D02*
Y296063D01*
G01Y300394D02*
Y299213D01*
G01Y303543D02*
Y302362D01*
G01Y306693D02*
Y305512D01*
G01Y309843D02*
Y308661D01*
G01Y312992D02*
Y311811D01*
G01Y316142D02*
Y314961D01*
G01Y319291D02*
Y318110D01*
G01Y322441D02*
Y321260D01*
G01Y325591D02*
Y324409D01*
G01Y328740D02*
Y327559D01*
G01X312401Y383976D02*
G03X311614Y384764I-788J0D01*
G01X300197Y387500D02*
G03X299409Y386713I0J-788D01*
G01X305315Y386718D02*
G03X304527Y387500I-788J-6D01*
G01X306102Y386724D02*
G03X307283Y385551I1181J8D01*
G01X307122Y388386D02*
G03I-1217J0D01*
G01X307283D02*
G03I-1378J0D01*
G01X313189Y383976D02*
G03X311614Y385551I-1575J0D01*
G01X300197Y388287D02*
G03X298622Y386713I0J-1575D01*
G01X306102Y386724D02*
G03X304527Y388287I-1575J-12D01*
G01X305315Y386718D02*
G03X307283Y384764I1968J14D01*
G01X307874Y388386D02*
G03I-1969J0D01*
G01X317716Y389567D02*
G03X315748Y391535I-1968J0D01*
G01X296063D02*
G03X294094Y389567I0J-1969D01*
G01X301968Y391535D02*
X296063D01*
G01X315748D02*
X309842D01*
G01Y390748D02*
X301968D01*
G01X304527Y388287D02*
X300197D01*
G01X304527Y387500D02*
X300197D01*
G01X299409Y386713D02*
X298622D01*
G01X311614Y385551D02*
X307283D01*
G01X311614Y384764D02*
X307283D01*
G01X313189Y383976D02*
X312401D01*
G01X317716Y383760D02*
X294094D01*
G01X302874Y383327D02*
X308937D01*
G01X308149Y382539D02*
X303661D01*
G01X299409Y382185D02*
X294094D01*
G01X317716D02*
X312401D01*
G01X302953Y379134D02*
X295078D01*
G01X316732D02*
X308858D01*
G01X302953Y377953D02*
X295078D01*
G01X316732D02*
X308858D01*
G01X305315Y386718D02*
X306102Y386724D01*
G01X302953Y375984D02*
X295078D01*
G01X316732D02*
X308858D01*
G01X302953Y374803D02*
X295078D01*
G01X316732D02*
X308858D01*
G01X302953Y372835D02*
X295078D01*
G01X316732D02*
X308858D01*
G01X302953Y371654D02*
X295078D01*
G01X316732D02*
X308858D01*
G01X302953Y369685D02*
X295078D01*
G01X316732D02*
X308858D01*
G01X302953Y368504D02*
X295078D01*
G01X316732D02*
X308858D01*
G01X302953Y366535D02*
X295078D01*
G01X316732D02*
X308858D01*
G01X302953Y365354D02*
X295078D01*
G01X316732D02*
X308858D01*
G01X302953Y363386D02*
X295078D01*
G01X316732D02*
X308858D01*
G01X302953Y362205D02*
X295078D01*
G01X316732D02*
X308858D01*
G01X302953Y360236D02*
X295078D01*
G01X316732D02*
X308858D01*
G01X302953Y359055D02*
X295078D01*
G01X316732D02*
X308858D01*
G01X302953Y357087D02*
X295078D01*
G01X316732D02*
X308858D01*
G01X302953Y355906D02*
X295078D01*
G01X316732D02*
X308858D01*
G01X302953Y353937D02*
X295078D01*
G01X316732D02*
X308858D01*
G01X302953Y352756D02*
X295078D01*
G01X316732D02*
X308858D01*
G01X302953Y350787D02*
X295078D01*
G01X316732D02*
X308858D01*
G01X302953Y349606D02*
X295078D01*
G01X316732D02*
X308858D01*
G01X302953Y347638D02*
X295078D01*
G01X316732D02*
X308858D01*
G01X302953Y346457D02*
X295078D01*
G01X316732D02*
X308858D01*
G01X302953Y344488D02*
X295078D01*
G01X316732D02*
X308858D01*
G01X302953Y343307D02*
X295078D01*
G01X316732D02*
X308858D01*
G01X302953Y341339D02*
X295078D01*
G01X316732D02*
X308858D01*
G01X302953Y340157D02*
X295078D01*
G01X316732D02*
X308858D01*
G01X302953Y338189D02*
X295078D01*
G01X316732D02*
X308858D01*
G01X302953Y337008D02*
X295078D01*
G01X316732D02*
X308858D01*
G01X302953Y335039D02*
X295078D01*
G01X316732D02*
X308858D01*
G01X302953Y333858D02*
X295078D01*
G01X316732D02*
X308858D01*
G01X302953Y331890D02*
X295078D01*
G01X316732D02*
X308858D01*
G01X302953Y330709D02*
X295078D01*
G01X316732D02*
X308858D01*
G01X303661Y382539D02*
X302874Y383327D01*
G01X308937D02*
X308149Y382539D01*
G01X317716Y382185D02*
Y389567D01*
G01X316732Y331890D02*
Y330709D01*
G01Y335039D02*
Y333858D01*
G01Y338189D02*
Y337008D01*
G01Y341339D02*
Y340157D01*
G01Y344488D02*
Y343307D01*
G01Y347638D02*
Y346457D01*
G01Y350787D02*
Y349606D01*
G01Y353937D02*
Y352756D01*
G01Y357087D02*
Y355906D01*
G01Y360236D02*
Y359055D01*
G01Y363386D02*
Y362205D01*
G01Y366535D02*
Y365354D01*
G01Y369685D02*
Y368504D01*
G01Y372835D02*
Y371654D01*
G01Y375984D02*
Y374803D01*
G01Y379134D02*
Y377953D01*
G01X311614Y384764D02*
Y385551D01*
G01X309842Y391535D02*
Y390748D01*
G01X308858Y331890D02*
Y330709D01*
G01Y335039D02*
Y333858D01*
G01Y338189D02*
Y337008D01*
G01Y341339D02*
Y340157D01*
G01Y344488D02*
Y343307D01*
G01Y347638D02*
Y346457D01*
G01Y350787D02*
Y349606D01*
G01Y353937D02*
Y352756D01*
G01Y357087D02*
Y355906D01*
G01Y360236D02*
Y359055D01*
G01Y363386D02*
Y362205D01*
G01Y366535D02*
Y365354D01*
G01Y369685D02*
Y368504D01*
G01Y372835D02*
Y371654D01*
G01Y375984D02*
Y374803D01*
G01Y379134D02*
Y377953D01*
G01X307283Y385551D02*
Y384764D01*
G01X304527Y387500D02*
Y388287D01*
G01X302953Y331890D02*
Y330709D01*
G01Y335039D02*
Y333858D01*
G01Y338189D02*
Y337008D01*
G01Y341339D02*
Y340157D01*
G01Y344488D02*
Y343307D01*
G01Y347638D02*
Y346457D01*
G01Y350787D02*
Y349606D01*
G01Y353937D02*
Y352756D01*
G01Y357087D02*
Y355906D01*
G01Y360236D02*
Y359055D01*
G01Y363386D02*
Y362205D01*
G01Y366535D02*
Y365354D01*
G01Y369685D02*
Y368504D01*
G01Y372835D02*
Y371654D01*
G01Y375984D02*
Y374803D01*
G01Y379134D02*
Y377953D01*
G01X301968Y391535D02*
Y390748D01*
G01X300197Y388287D02*
Y387500D01*
G01X295078Y331890D02*
Y330709D01*
G01Y338189D02*
Y337008D01*
G01Y335039D02*
Y333858D01*
G01Y341339D02*
Y340157D01*
G01Y344488D02*
Y343307D01*
G01Y347638D02*
Y346457D01*
G01Y350787D02*
Y349606D01*
G01Y353937D02*
Y352756D01*
G01Y357087D02*
Y355906D01*
G01Y360236D02*
Y359055D01*
G01Y363386D02*
Y362205D01*
G01Y366535D02*
Y365354D01*
G01Y369685D02*
Y368504D01*
G01Y372835D02*
Y371654D01*
G01Y375984D02*
Y374803D01*
G01Y379134D02*
Y377953D01*
G01X294094Y389567D02*
Y382185D01*
G01X315945Y406890D02*
G03Y420276I0J6693D01*
G01X302559D02*
X315945D01*
G01X302559D02*
G03Y406890I0J-6693D01*
G01X315945D02*
X302559D01*
G01X279646Y421457D02*
G03X275709Y425394I-3937J0D01*
G01X287520Y429331D02*
G03X283583Y433268I-3937J0D01*
G01X321850Y472441D02*
G03X308071I-6889J0D01*
G01D02*
G03X321850I6889J0D01*
G01X377040Y-837696D02*
Y-856633D01*
G01X392242Y-837696D02*
X1042676D01*
G01X356536Y1699D02*
X356678Y1517D01*
G01X356389Y1848D02*
X356536Y1699D01*
G01X355807Y2139D02*
X355669Y2150D01*
G01X355948Y2107D02*
X355807Y2139D01*
G01X356092Y2049D02*
X355948Y2107D01*
G01X356240Y1964D02*
X356092Y2049D01*
G01X356389Y1848D02*
X356240Y1964D01*
G01X356536Y1699D02*
X356389Y1848D01*
G01X356678Y1517D02*
X356536Y1699D01*
G01X356811Y1300D02*
X356678Y1517D01*
G01X356934Y1047D02*
X356811Y1300D01*
G01X351513Y-1387D02*
X351454Y-1181D01*
G01X351576Y-1583D02*
X351513Y-1387D01*
G01X351643Y-1772D02*
X351576Y-1583D01*
G01X348423D02*
X348356Y-1772D01*
G01X348486Y-1387D02*
X348423Y-1583D01*
G01X348546Y-1181D02*
X348486Y-1387D01*
G01X352002Y3293D02*
G03X351890Y2747I1265J-544D01*
G01X352812Y-1912D02*
G03X353297Y-2165I485J338D01*
G01X351220Y-669D02*
G03X351811Y-1260I591J0D01*
G01X352812Y-1912D02*
G03X351643Y-1772I-647J-449D01*
G01X353297Y-1575D02*
G03X351454Y-1181I-1132J-786D01*
G01X346703Y-2165D02*
G03X347187Y-1912I0J589D01*
G01X348356Y-1772D02*
G03X347187Y-1912I-522J-589D01*
G01X348546Y-1181D02*
G03X346703Y-1575I-711J-1180D01*
G01X352812Y-1912D02*
X353297Y-1575D01*
G01X357244Y1102D02*
X355880Y-1260D01*
G01X352130Y725D02*
X351947Y325D01*
G01X361260Y-2165D02*
Y97244D01*
G01X360078Y-1575D02*
Y97244D01*
G01X359488Y51969D02*
Y-2165D01*
G01X357244Y38898D02*
Y1102D01*
G01X355669Y39685D02*
Y2150D01*
G01X353464Y5253D02*
Y-79D01*
G01X353297Y-1575D02*
Y-2165D01*
G01X351890Y2747D02*
Y-79D01*
G01X351220Y-669D02*
Y-79D01*
G01X350590Y7992D02*
Y79D01*
G01X350000Y39685D02*
Y1102D01*
G01X346703Y-2165D02*
Y-1575D01*
G01X343740Y-2165D02*
Y4235D01*
G01X343661Y-2165D02*
Y4235D01*
G01X340512Y51969D02*
Y-2165D01*
G01X352130Y725D02*
X351889Y7615D01*
G01X351315Y1484D02*
X351102Y7587D01*
G01X351315Y1484D02*
X351671Y315D01*
G01X356934Y1047D02*
X357043Y755D01*
G01X350000Y1102D02*
X351364Y-1260D01*
G01X360078Y-1575D02*
X360669Y-2165D01*
G01X346703Y-1575D02*
X347187Y-1912D01*
G01X355669Y2150D02*
X355807Y2139D01*
G01X355669Y2150D02*
X350000D01*
G01X351220Y-79D02*
X353464D01*
G01X361260Y-197D02*
X360078D01*
G01X348546Y-1181D02*
X351454D01*
G01X355880Y-1260D02*
X351364D01*
G01X351643Y-1772D02*
X348356D01*
G01X351302Y1870D02*
X351890Y1891D01*
G01Y1619D02*
X351311Y1598D01*
G01X352001Y444D02*
X351889Y440D01*
G01X351947Y325D02*
X351671Y315D01*
G01X412402Y39370D02*
G03X398622I-6890J0D01*
G01D02*
G03X412402I6890J0D01*
G01X347798Y24757D02*
X347731Y24779D01*
G01X347863Y24739D02*
X347798Y24757D01*
G01X347927Y24727D02*
X347863Y24739D01*
G01X353222Y17280D02*
X353150Y17403D01*
G01X353300Y17151D02*
X353222Y17280D01*
G01X353406Y17030D02*
X353300Y17151D01*
G01X353538Y16923D02*
X353406Y17030D01*
G01X353690Y16838D02*
X353538Y16923D01*
G01X353853Y16781D02*
X353690Y16838D01*
G01X360726Y4938D02*
X360770Y4893D01*
G01X360613Y4996D02*
X360726Y4938D01*
G01X352131Y24752D02*
X352062Y24739D01*
G01X352269Y24779D02*
X352131Y24752D01*
G01X353383Y24757D02*
X353450Y24779D01*
G01X353318Y24739D02*
X353383Y24757D01*
G01X353253Y24727D02*
X353318Y24739D01*
G01X348291Y27872D02*
X348238Y27626D01*
G01X348371Y28090D02*
X348291Y27872D01*
G01X348471Y28275D02*
X348371Y28090D01*
G01X348584Y28426D02*
X348471Y28275D01*
G01X348704Y28542D02*
X348584Y28426D01*
G01X348828Y28628D02*
X348704Y28542D01*
G01X348952Y28687D02*
X348828Y28628D01*
G01X349078Y28721D02*
X348952Y28687D01*
G01X349203Y28732D02*
X349078Y28721D01*
G01X349741Y28791D02*
X349641Y28713D01*
G01X349853Y28857D02*
X349741Y28791D01*
G01X349977Y28909D02*
X349853Y28857D01*
G01X350109Y28948D02*
X349977Y28909D01*
G01X350247Y28971D02*
X350109Y28948D01*
G01X350384Y28978D02*
X350247Y28971D01*
G01X341155Y54334D02*
X341267Y54263D01*
G01X341037Y54391D02*
X341155Y54334D01*
G01X340912Y54436D02*
X341037Y54391D01*
G01X340781Y54469D02*
X340912Y54436D01*
G01X340647Y54489D02*
X340781Y54469D01*
G01X340512Y54495D02*
X340647Y54489D01*
G01X351440Y28791D02*
X351540Y28713D01*
G01X351327Y28857D02*
X351440Y28791D01*
G01X351204Y28909D02*
X351327Y28857D01*
G01X351072Y28948D02*
X351204Y28909D01*
G01X350934Y28971D02*
X351072Y28948D01*
G01X350797Y28978D02*
X350934Y28971D01*
G01X353913Y55027D02*
X353937Y54829D01*
G01X353846Y55214D02*
X353913Y55027D01*
G01X353737Y55386D02*
X353846Y55214D01*
G01X353591Y55537D02*
X353737Y55386D01*
G01X353409Y55663D02*
X353591Y55537D01*
G01X353206Y55755D02*
X353409Y55663D01*
G01X352985Y55812D02*
X353206Y55755D01*
G01X352756Y55831D02*
X352985Y55812D01*
G01X352889Y27872D02*
X352942Y27626D01*
G01X352809Y28090D02*
X352889Y27872D01*
G01X352709Y28275D02*
X352809Y28090D01*
G01X352596Y28426D02*
X352709Y28275D01*
G01X352476Y28542D02*
X352596Y28426D01*
G01X352353Y28628D02*
X352476Y28542D01*
G01X352228Y28687D02*
X352353Y28628D01*
G01X352103Y28721D02*
X352228Y28687D01*
G01X351978Y28732D02*
X352103Y28721D01*
G01X361238Y60785D02*
X361260Y60610D01*
G01X361173Y60953D02*
X361238Y60785D01*
G01X361069Y61104D02*
X361173Y60953D01*
G01X360931Y61233D02*
X361069Y61104D01*
G01X360764Y61335D02*
X360931Y61233D01*
G01X360575Y61405D02*
X360764Y61335D01*
G01X360178Y61475D02*
X360575Y61405D01*
G01X360273Y63715D02*
X360472Y63732D01*
G01X360083Y63664D02*
X360273Y63715D01*
G01X359910Y63582D02*
X360083Y63664D01*
G01X359756Y63470D02*
X359910Y63582D01*
G01X359635Y63336D02*
X359756Y63470D01*
G01X359548Y63185D02*
X359635Y63336D01*
G01X359499Y63021D02*
X359548Y63185D01*
G01X359489Y62853D02*
X359499Y63021D01*
G01X359520Y62686D02*
X359489Y62853D01*
G01X359590Y62528D02*
X359520Y62686D01*
G01X359695Y62385D02*
X359590Y62528D01*
G01X359832Y62263D02*
X359695Y62385D01*
G01X359996Y62167D02*
X359832Y62263D01*
G01X360179Y62100D02*
X359996Y62167D01*
G01X358545Y54082D02*
X358732Y54263D01*
G01X358406Y53901D02*
X358545Y54082D01*
G01X358311Y53725D02*
X358406Y53901D01*
G01X358255Y53555D02*
X358311Y53725D01*
G01X358231Y53388D02*
X358255Y53555D01*
G01X358236Y53217D02*
X358231Y53388D01*
G01X358269Y53050D02*
X358236Y53217D01*
G01X358321Y52902D02*
X358269Y53050D01*
G01X358381Y52775D02*
X358321Y52902D01*
G01X358444Y52667D02*
X358381Y52775D01*
G01X358501Y52581D02*
X358444Y52667D01*
G01X358571Y52489D02*
X358501Y52581D01*
G01X358648Y52413D02*
X358571Y52489D01*
G01X358743Y52337D02*
X358648Y52413D01*
G01X358857Y52262D02*
X358743Y52337D01*
G01X358987Y52188D02*
X358857Y52262D01*
G01X359135Y52115D02*
X358987Y52188D01*
G01X359302Y52042D02*
X359135Y52115D01*
G01X359488Y51969D02*
X359302Y52042D01*
G01X340651Y53862D02*
X340512Y53869D01*
G01X340785Y53842D02*
X340651Y53862D01*
G01X340915Y53809D02*
X340785Y53842D01*
G01X341040Y53764D02*
X340915Y53809D01*
G01X341158Y53706D02*
X341040Y53764D01*
G01X341267Y53638D02*
X341158Y53706D01*
G01X352101Y28972D02*
X351978Y28978D01*
G01X352222Y28954D02*
X352101Y28972D01*
G01X352337Y28925D02*
X352222Y28954D01*
G01X352449Y28885D02*
X352337Y28925D01*
G01X352550Y28835D02*
X352449Y28885D01*
G01X352644Y28775D02*
X352550Y28835D01*
G01X347928Y24731D02*
Y24736D01*
G01X347925Y24734D02*
X347928Y24731D01*
G01X349969Y13268D02*
X349961Y13277D01*
G01X349980Y13255D02*
X349969Y13268D01*
G01X340501Y62395D02*
X340451Y62559D01*
G01X340510Y62227D02*
X340501Y62395D01*
G01X340480Y62060D02*
X340510Y62227D01*
G01X340410Y61902D02*
X340480Y62060D01*
G01X359995Y61541D02*
X360178Y61475D01*
G01X359832Y61637D02*
X359995Y61541D01*
G01X359692Y61762D02*
X359832Y61637D01*
G01X359588Y61905D02*
X359692Y61762D01*
G01X359519Y62064D02*
X359588Y61905D01*
G01X359489Y62230D02*
X359519Y62064D01*
G01X359500Y62399D02*
X359489Y62230D01*
G01X359550Y62562D02*
X359500Y62399D01*
G01X359637Y62714D02*
X359550Y62562D01*
G01X359759Y62847D02*
X359637Y62714D01*
G01X359910Y62957D02*
X359759Y62847D01*
G01X360084Y63038D02*
X359910Y62957D01*
G01X360274Y63089D02*
X360084Y63038D01*
G01X360472Y63106D02*
X360274Y63089D01*
G01X361240Y55165D02*
X361260Y55330D01*
G01X361184Y55009D02*
X361240Y55165D01*
G01X361093Y54866D02*
X361184Y55009D01*
G01X360971Y54740D02*
X361093Y54866D01*
G01X360820Y54635D02*
X360971Y54740D01*
G01X360650Y54558D02*
X360820Y54635D01*
G01X360467Y54511D02*
X360650Y54558D01*
G01X360275Y54495D02*
X360467Y54511D01*
G01X346086Y54401D02*
X346063Y54203D01*
G01X346153Y54588D02*
X346086Y54401D01*
G01X346262Y54760D02*
X346153Y54588D01*
G01X346409Y54911D02*
X346262Y54760D01*
G01X346590Y55037D02*
X346409Y54911D01*
G01X346794Y55129D02*
X346590Y55037D01*
G01X347014Y55186D02*
X346794Y55129D01*
G01X347244Y55205D02*
X347014Y55186D01*
G01X350334Y68110D02*
X350353Y68273D01*
G01X350279Y67957D02*
X350334Y68110D01*
G01X350189Y67816D02*
X350279Y67957D01*
G01X350069Y67692D02*
X350189Y67816D01*
G01X349920Y67589D02*
X350069Y67692D01*
G01X349754Y67513D02*
X349920Y67589D01*
G01X349573Y67467D02*
X349754Y67513D01*
G01X349384Y67451D02*
X349573Y67467D01*
G01X358845Y53708D02*
X358732Y53638D01*
G01X358963Y53765D02*
X358845Y53708D01*
G01X359088Y53810D02*
X358963Y53765D01*
G01X359218Y53843D02*
X359088Y53810D01*
G01X359352Y53863D02*
X359218Y53843D01*
G01X359488Y53869D02*
X359352Y53863D01*
G01X361445Y62855D02*
X361456Y62793D01*
G01X361411Y62913D02*
X361445Y62855D01*
G01X361357Y62967D02*
X361411Y62913D01*
G01X361283Y63014D02*
X361357Y62967D01*
G01X361193Y63054D02*
X361283Y63014D01*
G01X361091Y63082D02*
X361193Y63054D01*
G01X360981Y63100D02*
X361091Y63082D01*
G01X360866Y63106D02*
X360981Y63100D01*
G01X348163Y68215D02*
X348144Y68377D01*
G01X348219Y68061D02*
X348163Y68215D01*
G01X348308Y67920D02*
X348219Y68061D01*
G01X348428Y67796D02*
X348308Y67920D01*
G01X348577Y67693D02*
X348428Y67796D01*
G01X348744Y67618D02*
X348577Y67693D01*
G01X348925Y67571D02*
X348744Y67618D01*
G01X349113Y67556D02*
X348925Y67571D01*
G01X340481Y62690D02*
X340412Y62531D01*
G01X340510Y62856D02*
X340481Y62690D01*
G01X340500Y63025D02*
X340510Y62856D01*
G01X340450Y63188D02*
X340500Y63025D01*
G01X340737Y51980D02*
X340512Y51969D01*
G01X340940Y52006D02*
X340737Y51980D01*
G01X341118Y52047D02*
X340940Y52006D01*
G01X341273Y52101D02*
X341118Y52047D01*
G01X341401Y52169D02*
X341273Y52101D01*
G01X341501Y52247D02*
X341401Y52169D01*
G01X341576Y52334D02*
X341501Y52247D01*
G01X341629Y52430D02*
X341576Y52334D01*
G01X341663Y52539D02*
X341629Y52430D01*
G01X341676Y52661D02*
X341663Y52539D01*
G01X341667Y52798D02*
X341676Y52661D01*
G01X341635Y52947D02*
X341667Y52798D01*
G01X341579Y53107D02*
X341635Y52947D01*
G01X341499Y53276D02*
X341579Y53107D01*
G01X341396Y53453D02*
X341499Y53276D01*
G01X341267Y53638D02*
X341396Y53453D01*
G01X351725Y28362D02*
X351771Y28200D01*
G01X351646Y28535D02*
X351725Y28362D01*
G01X351540Y28713D02*
X351646Y28535D01*
G01X340755Y51987D02*
X340512Y51969D01*
G01X340969Y52028D02*
X340755Y51987D01*
G01X341152Y52090D02*
X340969Y52028D01*
G01X341302Y52169D02*
X341152Y52090D01*
G01X341421Y52262D02*
X341302Y52169D01*
G01X341515Y52370D02*
X341421Y52262D01*
G01X341588Y52494D02*
X341515Y52370D01*
G01X341640Y52640D02*
X341588Y52494D01*
G01X341670Y52809D02*
X341640Y52640D01*
G01X341675Y53002D02*
X341670Y52809D01*
G01X341652Y53218D02*
X341675Y53002D01*
G01X341601Y53454D02*
X341652Y53218D01*
G01X341521Y53707D02*
X341601Y53454D01*
G01X341410Y53978D02*
X341521Y53707D01*
G01X341267Y54263D02*
X341410Y53978D01*
G01X352755Y28615D02*
X352644Y28775D01*
G01X352842Y28464D02*
X352755Y28615D01*
G01X352913Y28308D02*
X352842Y28464D01*
G01X352953Y28169D02*
X352913Y28308D01*
G01X352951Y27589D02*
X352953Y27580D01*
G01X352949Y27597D02*
X352951Y27589D01*
G01X352948Y27605D02*
X352949Y27597D01*
G01X352946Y27613D02*
X352948Y27605D01*
G01X352944Y27621D02*
X352946Y27613D01*
G01X352942Y27626D02*
X352944Y27621D01*
G01X353124Y17633D02*
X353084Y17856D01*
G01X353176Y17410D02*
X353124Y17633D01*
G01X350922Y28721D02*
X350797Y28732D01*
G01X351047Y28687D02*
X350922Y28721D01*
G01X351171Y28628D02*
X351047Y28687D01*
G01X351295Y28542D02*
X351171Y28628D01*
G01X351415Y28426D02*
X351295Y28542D01*
G01X351528Y28276D02*
X351415Y28426D01*
G01X351628Y28090D02*
X351528Y28276D01*
G01X351708Y27872D02*
X351628Y28090D01*
G01X351761Y27626D02*
X351708Y27872D01*
G01X353344Y25544D02*
X353450Y24974D01*
G01X353238Y26098D02*
X353344Y25544D01*
G01X353133Y26591D02*
X353238Y26098D01*
G01X352884Y27667D02*
X352970Y27328D01*
G01X352802Y28015D02*
X352884Y27667D01*
G01X352724Y28378D02*
X352802Y28015D01*
G01X352829Y27868D02*
X352928Y27427D01*
G01X352736Y28317D02*
X352829Y27868D01*
G01X352644Y28775D02*
X352736Y28317D01*
G01X351763Y27617D02*
X351761Y27626D01*
G01X351765Y27609D02*
X351763Y27617D01*
G01X351767Y27602D02*
X351765Y27609D01*
G01X351769Y27594D02*
X351767Y27602D01*
G01X351770Y27586D02*
X351769Y27594D01*
G01X351771Y27580D02*
X351770Y27586D01*
G01X352057Y26098D02*
X351951Y26591D01*
G01X352163Y25544D02*
X352057Y26098D01*
G01X352269Y24974D02*
X352163Y25544D01*
G01X353240Y18119D02*
X353276Y17856D01*
G01X353199Y18392D02*
X353240Y18119D01*
G01X353154Y18674D02*
X353199Y18392D01*
G01X352189Y25424D02*
X352269Y24779D01*
G01X352110Y26051D02*
X352189Y25424D01*
G01X352032Y26658D02*
X352110Y26051D01*
G01X351951Y27205D02*
X352032Y26658D01*
G01X351817Y26870D02*
X351880Y26367D01*
G01X351753Y27328D02*
X351817Y26870D01*
G01X361216Y63713D02*
X360866Y63732D01*
G01X361547Y63660D02*
X361216Y63713D01*
G01X361851Y63573D02*
X361547Y63660D01*
G01X362119Y63457D02*
X361851Y63573D01*
G01X362342Y63313D02*
X362119Y63457D01*
G01X362504Y63151D02*
X362342Y63313D01*
G01X362604Y62975D02*
X362504Y63151D01*
G01X362638Y62793D02*
X362604Y62975D01*
G01X353206Y26707D02*
X353132Y27205D01*
G01X353282Y26126D02*
X353206Y26707D01*
G01X360576Y62031D02*
X360179Y62100D01*
G01X360767Y61959D02*
X360576Y62031D01*
G01X360934Y61856D02*
X360767Y61959D01*
G01X361072Y61727D02*
X360934Y61856D01*
G01X361174Y61576D02*
X361072Y61727D01*
G01X361238Y61410D02*
X361174Y61576D01*
G01X361260Y61236D02*
X361238Y61410D01*
G01X353175Y25396D02*
X353258Y24742D01*
G01X353092Y26103D02*
X353175Y25396D01*
G01X353010Y26771D02*
X353092Y26103D01*
G01D02*
X353010Y26771D01*
G01X353175Y25395D02*
X353092Y26103D01*
G01X353255Y24734D02*
X353175Y25395D01*
G01X352008Y25285D02*
X352062Y24740D01*
G01X351880Y26367D02*
X352008Y25285D01*
G01X348921Y67468D02*
X349113Y67451D01*
G01X348741Y67514D02*
X348921Y67468D01*
G01X348574Y67590D02*
X348741Y67514D01*
G01X348428Y67692D02*
X348574Y67590D01*
G01X348306Y67818D02*
X348428Y67692D01*
G01X348217Y67960D02*
X348306Y67818D01*
G01X348163Y68113D02*
X348217Y67960D01*
G01X348144Y68273D02*
X348163Y68113D01*
G01X352989Y55185D02*
X352756Y55205D01*
G01X353210Y55128D02*
X352989Y55185D01*
G01X353413Y55036D02*
X353210Y55128D01*
G01X353591Y54911D02*
X353413Y55036D01*
G01X353739Y54757D02*
X353591Y54911D01*
G01X353848Y54585D02*
X353739Y54757D01*
G01X353914Y54398D02*
X353848Y54585D01*
G01X353937Y54203D02*
X353914Y54398D01*
G01X361084Y55722D02*
X361260Y55462D01*
G01X360961Y55973D02*
X361084Y55722D01*
G01X360889Y56207D02*
X360961Y55973D01*
G01X360866Y56417D02*
X360889Y56207D01*
G01X360037Y12864D02*
X360035Y12815D01*
G01X360038Y12880D02*
X360037Y12864D01*
G01X347010Y55811D02*
X347244Y55831D01*
G01X346790Y55754D02*
X347010Y55811D01*
G01X346587Y55661D02*
X346790Y55754D01*
G01X346409Y55537D02*
X346587Y55661D01*
G01X346260Y55383D02*
X346409Y55537D01*
G01X346152Y55211D02*
X346260Y55383D01*
G01X346085Y55024D02*
X346152Y55211D01*
G01X346063Y54829D02*
X346085Y55024D01*
G01X349576Y67572D02*
X349384Y67556D01*
G01X349757Y67619D02*
X349576Y67572D01*
G01X349923Y67694D02*
X349757Y67619D01*
G01X350069Y67796D02*
X349923Y67694D01*
G01X350191Y67922D02*
X350069Y67796D01*
G01X350280Y68064D02*
X350191Y67922D01*
G01X350335Y68217D02*
X350280Y68064D01*
G01X350353Y68377D02*
X350335Y68217D01*
G01X359995Y12746D02*
X359983Y12668D01*
G01X359997Y12767D02*
X359995Y12746D01*
G01X361677Y62704D02*
X361456Y62398D01*
G01X361808Y63074D02*
X361677Y62704D01*
G01X361850Y63482D02*
X361808Y63074D01*
G01X360252Y55718D02*
X360078Y55462D01*
G01X360375Y55968D02*
X360252Y55718D01*
G01X360448Y56203D02*
X360375Y55968D01*
G01X360472Y56417D02*
X360448Y56203D01*
G01X360470Y53886D02*
X360275Y53869D01*
G01X360654Y53933D02*
X360470Y53886D01*
G01X360823Y54010D02*
X360654Y53933D01*
G01X360971Y54114D02*
X360823Y54010D01*
G01X361095Y54242D02*
X360971Y54114D01*
G01X361185Y54386D02*
X361095Y54242D01*
G01X361241Y54542D02*
X361185Y54386D01*
G01X361260Y54704D02*
X361241Y54542D01*
G01X348006Y25395D02*
X348088Y26103D01*
G01X347925Y24734D02*
X348006Y25395D01*
G01Y25396D02*
X347923Y24742D01*
G01X348088Y26103D02*
X348006Y25396D01*
G01X348170Y26771D02*
X348088Y26103D01*
G01X347975Y26707D02*
X348048Y27205D01*
G01X347898Y26126D02*
X347975Y26707D01*
G01X347731Y24779D02*
X347898Y26126D01*
G01X349301Y26367D02*
X349173Y25285D01*
G01X349363Y26870D02*
X349301Y26367D01*
G01X349428Y27328D02*
X349363Y26870D01*
G01X348991Y25424D02*
X348912Y24779D01*
G01X349070Y26051D02*
X348991Y25424D01*
G01X349149Y26658D02*
X349070Y26051D01*
G01X349229Y27205D02*
X349149Y26658D01*
G01X360056Y12769D02*
X360029Y12737D01*
G01X360073Y12805D02*
X360056Y12769D01*
G01X360078Y12843D02*
X360073Y12805D01*
G01X347941Y18119D02*
X347905Y17856D01*
G01X347982Y18392D02*
X347941Y18119D01*
G01X348026Y18674D02*
X347982Y18392D01*
G01X360068Y12937D02*
X360038Y12880D01*
G01X360078Y13000D02*
X360068Y12937D01*
G01X349123Y26098D02*
X349229Y26591D01*
G01X349018Y25544D02*
X349123Y26098D01*
G01X348912Y24974D02*
X349018Y25544D01*
G01X349417Y27617D02*
X349419Y27626D01*
G01X349415Y27609D02*
X349417Y27617D01*
G01X349413Y27602D02*
X349415Y27609D01*
G01X349412Y27594D02*
X349413Y27602D01*
G01X349410Y27586D02*
X349412Y27594D01*
G01X349409Y27580D02*
X349410Y27586D01*
G01X348351Y27868D02*
X348253Y27427D01*
G01X348445Y28317D02*
X348351Y27868D01*
G01X348537Y28775D02*
X348445Y28317D01*
G01X348297Y27667D02*
X348210Y27328D01*
G01X348379Y28015D02*
X348297Y27667D01*
G01X348456Y28378D02*
X348379Y28015D01*
G01X347836Y25544D02*
X347731Y24974D01*
G01X347942Y26098D02*
X347836Y25544D01*
G01X348048Y26591D02*
X347942Y26098D01*
G01X350259Y28721D02*
X350384Y28732D01*
G01X350134Y28687D02*
X350259Y28721D01*
G01X350009Y28628D02*
X350134Y28687D01*
G01X349886Y28542D02*
X350009Y28628D01*
G01X349766Y28426D02*
X349886Y28542D01*
G01X349653Y28276D02*
X349766Y28426D01*
G01X349552Y28090D02*
X349653Y28276D01*
G01X349472Y27872D02*
X349552Y28090D01*
G01X349419Y27626D02*
X349472Y27872D01*
G01X348057Y17633D02*
X348097Y17856D01*
G01X348005Y17410D02*
X348057Y17633D01*
G01X348230Y27589D02*
X348228Y27580D01*
G01X348231Y27597D02*
X348230Y27589D01*
G01X348233Y27605D02*
X348231Y27597D01*
G01X348235Y27613D02*
X348233Y27605D01*
G01X348237Y27621D02*
X348235Y27613D01*
G01X348238Y27626D02*
X348237Y27621D01*
G01X348425Y28615D02*
X348537Y28775D01*
G01X348338Y28464D02*
X348425Y28615D01*
G01X348268Y28308D02*
X348338Y28464D01*
G01X348228Y28169D02*
X348268Y28308D01*
G01X360057Y12648D02*
X360078Y12843D01*
G01X359982Y12422D02*
X360057Y12648D01*
G01X360007Y12717D02*
X360029Y12737D01*
G01X359991Y12694D02*
X360007Y12717D01*
G01X359983Y12668D02*
X359991Y12694D01*
G01X359927Y12401D02*
X359811Y12227D01*
G01X359998Y12582D02*
X359927Y12401D01*
G01D02*
X359811Y12227D01*
G01X359998Y12582D02*
X359927Y12401D01*
G01X359881Y12397D02*
X359781Y12252D01*
G01X359948Y12546D02*
X359881Y12397D01*
G01X360010Y12830D02*
X359997Y12775D01*
G01X360038Y12880D02*
X360010Y12830D01*
G01D02*
X359997Y12775D01*
G01X360038Y12880D02*
X360010Y12830D01*
G01X349456Y28362D02*
X349409Y28200D01*
G01X349534Y28535D02*
X349456Y28362D01*
G01X349641Y28713D02*
X349534Y28535D01*
G01X359330Y52014D02*
X359488Y51969D01*
G01X359185Y52059D02*
X359330Y52014D01*
G01X359052Y52104D02*
X359185Y52059D01*
G01X358932Y52150D02*
X359052Y52104D01*
G01X358825Y52196D02*
X358932Y52150D01*
G01X358731Y52243D02*
X358825Y52196D01*
G01X358650Y52290D02*
X358731Y52243D01*
G01X358577Y52342D02*
X358650Y52290D01*
G01X358506Y52408D02*
X358577Y52342D01*
G01X358440Y52481D02*
X358506Y52408D01*
G01X358383Y52553D02*
X358440Y52481D01*
G01X358324Y52643D02*
X358383Y52553D01*
G01X358272Y52749D02*
X358324Y52643D01*
G01X358239Y52861D02*
X358272Y52749D01*
G01X358229Y52972D02*
X358239Y52861D01*
G01X358243Y53081D02*
X358229Y52972D01*
G01X358282Y53192D02*
X358243Y53081D01*
G01X358350Y53304D02*
X358282Y53192D01*
G01X358448Y53418D02*
X358350Y53304D01*
G01X358576Y53530D02*
X358448Y53418D01*
G01X358732Y53638D02*
X358576Y53530D01*
G01X349080Y28972D02*
X349203Y28978D01*
G01X348958Y28954D02*
X349080Y28972D01*
G01X348844Y28925D02*
X348958Y28954D01*
G01X348732Y28885D02*
X348844Y28925D01*
G01X348630Y28835D02*
X348732Y28885D01*
G01X348537Y28775D02*
X348630Y28835D01*
G01X359349Y54488D02*
X359488Y54495D01*
G01X359215Y54468D02*
X359349Y54488D01*
G01X359085Y54435D02*
X359215Y54468D01*
G01X358960Y54389D02*
X359085Y54435D01*
G01X358842Y54332D02*
X358960Y54389D01*
G01X358732Y54263D02*
X358842Y54332D01*
G01X347958Y17280D02*
X348030Y17403D01*
G01X347881Y17151D02*
X347958Y17280D01*
G01X347775Y17030D02*
X347881Y17151D01*
G01X347642Y16923D02*
X347775Y17030D01*
G01X347490Y16838D02*
X347642Y16923D01*
G01X347327Y16781D02*
X347490Y16838D01*
G01X360078Y42323D02*
G03X360275Y42520I0J197D01*
G01X353937Y46049D02*
G03X354330Y45367I788J0D01*
G01X361260Y41810D02*
G03X361456Y42520I-1182J708D01*
G01X353937Y43898D02*
G03X354330Y45367I0J787D01*
G01X350212Y46481D02*
G03X349795Y46654I-418J-418D01*
G01X350827Y44488D02*
G03X351417Y43898I590J0D01*
G01X350827Y45622D02*
G03X350654Y46039I-591J-1D01*
G01X348879Y39685D02*
G03X349449Y39364I1041J1182D01*
G01X348750Y39699D02*
G03X349425Y39289I1171J1167D01*
G01X348600Y39685D02*
G03X349389Y39176I1321J1181D01*
G01X349803Y38613D02*
G03X349390Y39176I-590J0D01*
G01X349921Y38613D02*
G03X349425Y39289I-709J0D01*
G01X350000Y38613D02*
G03X349449Y39364I-787J0D01*
G01X350000Y36096D02*
G03X349901Y36267I-197J0D01*
G01X349803Y36437D02*
G03X349901Y36267I196J0D01*
G01X350000Y36043D02*
G03X349901Y36214I-197J0D01*
G01X349803Y36384D02*
G03X349901Y36214I196J0D01*
G01X349203Y30906D02*
G03X346669Y28707I0J-2560D01*
G01X353331D02*
G03X350797Y30906I-2534J-361D01*
G01X350384D02*
G03X347850Y28707I0J-2560D01*
G01X354512D02*
G03X351978Y30906I-2534J-361D01*
G01X360374Y17731D02*
G03X360264Y16470I696J-696D01*
G01X359539Y18566D02*
G03X359296Y15793I1531J-1531D01*
G01X360278Y11020D02*
G03X360167Y10965I28J-195D01*
G01X360278Y11020D02*
G03X360390Y11076I-28J195D01*
G01X360038Y12880D02*
G03X359997Y12775I155J-121D01*
G01X359499Y10185D02*
G03X359389Y8925I696J-696D01*
G01X359471Y10213D02*
G03X359356Y8902I724J-724D01*
G01X359443Y10241D02*
G03X359324Y8879I752J-752D01*
G01X358664Y11020D02*
G03X358421Y8247I1531J-1531D01*
G01X358636Y11048D02*
G03X358389Y8225I1559J-1559D01*
G01X358608Y11076D02*
G03X358357Y8202I1587J-1587D01*
G01X360078Y14366D02*
G03X359900Y14930I-984J0D01*
G01X361260Y14366D02*
G03X360868Y15608I-2166J-1D01*
G01X360038Y12880D02*
G03X360078Y13000I-156J119D01*
G01X359735Y12203D02*
G03X359997Y12775I-641J640D01*
G01X359762Y12175D02*
G03X359810Y12227I-670J666D01*
G01X359790Y12147D02*
G03X360078Y12843I-697J696D01*
G01X360625Y11312D02*
G03X361260Y12843I-1531J1532D01*
G01X361014Y6603D02*
G03X360914Y6677I-161J-113D01*
G01X360814Y6751D02*
G03X360914Y6677I161J113D01*
G01X360570Y5042D02*
G03X360670Y4967I162J112D01*
G01X360770Y4893D02*
G03X360670Y4967I-161J-113D01*
G01X354527Y17409D02*
G03X356086Y17630I780J110D01*
G01X353346Y17409D02*
G03X354905Y17630I779J110D01*
G01X354332Y17381D02*
G03X356003Y18215I974J139D01*
G01X354495Y9760D02*
G03X355078Y10521I-205J761D01*
G01X355615Y7259D02*
G03X355866Y7835I-537J577D01*
G01X354699Y9000D02*
G03X355866Y10521I-408J1521D01*
G01X349185Y17878D02*
G03X348990Y15659I1012J-1207D01*
G01X348679Y18481D02*
G03X348387Y15153I1518J-1810D01*
G01X352472Y8403D02*
G03X351889Y7615I204J-761D01*
G01X352268Y9164D02*
G03X351102Y7587I408J-1521D01*
G01X352644Y4488D02*
G03X352319Y4026I941J-1007D01*
G01X347401Y41929D02*
G03X347008Y42323I-394J0D01*
G01Y40354D02*
G03X347401Y40748I0J393D01*
G01X346614Y41535D02*
G03X345740Y41897I-512J0D01*
G01X345362Y46654D02*
G03X344945Y46481I1J-591D01*
G01X344503Y46039D02*
G03X344330Y45622I418J-418D01*
G01X343740Y43898D02*
G03X344330Y44488I0J590D01*
G01X343740Y41434D02*
G03X344748Y41017I590J0D01*
G01X346693Y41535D02*
G03X345685Y41953I-591J0D01*
G01X343661Y41434D02*
G03X344804Y40961I669J0D01*
G01X345669Y45367D02*
G03X346063Y43898I394J-682D01*
G01X345669Y45367D02*
G03X346063Y46049I-393J682D01*
G01X347401Y34449D02*
G03X347008Y34843I-394J0D01*
G01Y32874D02*
G03X347401Y33268I0J393D01*
G01X345740Y33300D02*
G03X346614Y33661I362J361D01*
G01X344748Y34180D02*
G03X343740Y33763I-418J-417D01*
G01X345685Y33244D02*
G03X346693Y33661I418J417D01*
G01X344804Y34236D02*
G03X343661Y33763I-474J-473D01*
G01X342874Y40748D02*
G03X343267Y40354I394J0D01*
G01Y42323D02*
G03X342874Y41929I0J-393D01*
G01Y33268D02*
G03X343267Y32874I394J0D01*
G01Y34843D02*
G03X342874Y34449I0J-393D01*
G01X346275Y17630D02*
G03X347834Y17409I779J-111D01*
G01X345094Y17630D02*
G03X346653Y17409I780J-111D01*
G01X345177Y18215D02*
G03X346848Y17381I697J-695D01*
G01X348679Y18481D02*
G03X349803Y20819I-2025J2413D01*
G01X349185Y17878D02*
G03X350000Y18819I-2532J3016D01*
G01X347401Y12402D02*
G03X347008Y12795I-393J0D01*
G01Y10827D02*
G03X347401Y11220I0J393D01*
G01X346614Y12008D02*
G03X345740Y12370I-512J0D01*
G01X346693Y12008D02*
G03X345685Y12425I-590J0D01*
G01X343740Y11907D02*
G03X344748Y11489I591J0D01*
G01X343661Y11907D02*
G03X344804Y11433I670J0D01*
G01X347401Y4921D02*
G03X347008Y5315I-394J0D01*
G01Y3346D02*
G03X347401Y3740I0J393D01*
G01X345740Y3772D02*
G03X346614Y4134I362J362D01*
G01X344748Y4653D02*
G03X343740Y4235I-417J-418D01*
G01X345685Y3716D02*
G03X346693Y4134I417J418D01*
G01X344804Y4708D02*
G03X343661Y4235I-474J-473D01*
G01X343267Y12795D02*
G03X342874Y12402I0J-393D01*
G01Y11220D02*
G03X343267Y10827I393J0D01*
G01X340611Y8925D02*
G03X340501Y10185I-806J564D01*
G01X340643Y8902D02*
G03X340529Y10213I-838J588D01*
G01X340675Y8879D02*
G03X340556Y10241I-870J610D01*
G01X341578Y8247D02*
G03X341336Y11020I-1773J1242D01*
G01X341611Y8225D02*
G03X341364Y11048I-1806J1264D01*
G01X341643Y8202D02*
G03X341392Y11076I-1838J1287D01*
G01X342874Y3740D02*
G03X343267Y3346I394J0D01*
G01Y5315D02*
G03X342874Y4921I0J-393D01*
G01X353258Y24742D02*
X353447Y24803D01*
G01X353051Y54365D02*
X350984Y53642D01*
G01X349428Y27328D02*
X349233Y27224D01*
G01X352953Y69902D02*
X346949Y67482D01*
G01X353051Y70172D02*
X347008Y67736D01*
G01X358425Y39685D02*
X357244Y38898D01*
G01X361983Y3846D02*
X361661Y3620D01*
G01X362122Y5020D02*
X361155Y4343D01*
G01X360276Y5461D02*
X360340Y5506D01*
G01X360631Y7151D02*
X360566Y7106D01*
G01X359389Y8925D02*
X358357Y8202D01*
G01X360868Y15608D02*
X359900Y14930D01*
G01X360264Y16470D02*
X359296Y15793D01*
G01X352953Y62028D02*
X346949Y57591D01*
G01X353051Y62359D02*
X347008Y57894D01*
G01X350000Y13310D02*
X349961Y13277D01*
G01X348990Y15659D02*
X348387Y15153D01*
G01X355615Y7259D02*
X352644Y4488D01*
G01X360625Y11312D02*
X359499Y10185D01*
G01X360278Y11020D02*
X359471Y10213D01*
G01X360167Y10965D02*
X359443Y10241D01*
G01X359790Y12147D02*
X358664Y11020D01*
G01X359762Y12175D02*
X358636Y11048D01*
G01X359735Y12203D02*
X358608Y11076D01*
G01X361406Y18763D02*
X360374Y17731D01*
G01X361128Y20155D02*
X359539Y18566D01*
G01X356456Y16063D02*
X355866Y15472D01*
G01X345740Y12370D02*
X344804Y11433D01*
G01X345685Y12425D02*
X344748Y11489D01*
G01X341392Y11076D02*
X340501Y10185D01*
G01X359980Y30433D02*
X358012Y28465D01*
G01X352953Y54154D02*
X352165Y53453D01*
G01X359980Y40866D02*
X358799Y39685D01*
G01X348228Y30433D02*
X346260Y28465D01*
G01X358307Y48543D02*
X358110Y48346D01*
G01X353543Y45197D02*
X352362Y44016D01*
G01X345740Y41897D02*
X344804Y40961D01*
G01X345685Y41953D02*
X344748Y41017D01*
G01X344035Y44803D02*
X343248Y44016D01*
G01X344945Y46481D02*
X344503Y46039D01*
G01X341890Y51496D02*
X341693Y51299D01*
G01X353255Y24734D02*
X353253Y24731D01*
G01X353258Y24742D02*
X353252Y24736D01*
G01X359840Y12201D02*
X359982Y12422D01*
G01X360068Y12937D02*
X360038Y12880D01*
G01X352319Y4026D02*
X352002Y3293D01*
G01X359927Y12401D02*
X359999Y12583D01*
G01X349449Y39364D02*
X349390Y39176D01*
G01X359983Y12669D02*
X359948Y12544D01*
G01X360767Y45197D02*
X359980Y42258D01*
G01X359999Y12583D02*
X360029Y12737D01*
G01X348048Y27205D02*
X348228Y28169D01*
G01X349229Y26591D02*
X349409Y27580D01*
G01X348228D02*
X348048Y26591D01*
G01X349409Y28200D02*
X349229Y27205D01*
G01X362177Y4943D02*
X361983Y3846D01*
G01X348225Y18635D02*
X348097Y17857D01*
G01X346916D02*
X347044Y18635D01*
G01X346717Y17857D02*
X346845Y18674D01*
G01X349641Y28713D02*
X349428Y27328D01*
G01X348223Y18621D02*
X349111Y24741D01*
G01X348912Y24779D02*
X348026Y18674D01*
G01Y18868D02*
X348912Y24974D01*
G01X347927Y24727D02*
X347042Y18621D01*
G01X346845Y18674D02*
X347731Y24779D01*
G01Y24974D02*
X346845Y18868D01*
G01X347898Y17857D02*
X347834Y17409D01*
G01X346916Y17857D02*
X346848Y17381D01*
G01X346717Y17857D02*
X346653Y17409D01*
G01X347850Y28707D02*
X346275Y17631D01*
G01X346669Y28707D02*
X345094Y17631D01*
G01X348170Y26771D02*
X348244Y27328D01*
G01X347898Y17857D02*
X348026Y18868D01*
G01X346845D02*
X346717Y17857D01*
G01X347927Y24727D02*
X347929Y24740D01*
G01X360035Y12815D02*
X360029Y12737D01*
G01X349173Y25285D02*
X349119Y24740D01*
G01X360037Y12864D02*
X360035Y12815D01*
G01X349998Y28884D02*
X349803Y20819D01*
G01X362638Y62003D02*
Y97445D01*
G01X361850Y91573D02*
Y63482D01*
G01X361456Y97445D02*
Y42520D01*
G01X361406Y19877D02*
Y18763D01*
G01X360886Y51772D02*
Y89521D01*
G01X360866Y97165D02*
Y56417D01*
G01X360767Y45197D02*
Y47756D01*
G01X360472Y56417D02*
Y96319D01*
G01X360374Y61441D02*
Y62067D01*
G01X360275Y49421D02*
Y42520D01*
G01Y54495D02*
Y53869D01*
G01X359980Y30433D02*
Y51496D01*
G01X359882Y97067D02*
Y45886D01*
G01X359488Y62271D02*
Y62897D01*
G01Y53869D02*
Y54495D01*
G01X359390Y45787D02*
Y49421D01*
G01X358799Y39685D02*
Y54646D01*
G01X358732Y53638D02*
Y54263D01*
G01X358405Y51594D02*
Y48248D01*
G01X358307Y48543D02*
Y51299D01*
G01X358229Y53335D02*
Y52962D01*
G01X357027Y48248D02*
Y45886D01*
G01X356929Y45787D02*
Y48346D01*
G01X356693Y55531D02*
Y54646D01*
G01X355866Y7835D02*
Y39685D01*
G01X355078Y10521D02*
Y39685D01*
G01X354336Y18868D02*
Y18674D01*
G01X354134Y34370D02*
Y30433D01*
G01Y77975D02*
Y55531D01*
G01X353937Y46049D02*
Y83689D01*
G01Y8780D02*
Y39685D01*
G01X353543Y48150D02*
Y45197D01*
G01X353450Y24779D02*
Y24974D01*
G01X353154Y18674D02*
Y18868D01*
G01X353149Y39685D02*
Y11170D01*
G01Y83689D02*
Y54241D01*
G01X353133Y26591D02*
Y27205D01*
G01X353051Y62359D02*
Y63511D01*
G01Y54365D02*
Y55704D01*
G01X352953Y28169D02*
Y27580D01*
G01X352756Y55831D02*
Y55205D01*
G01X352559Y58681D02*
Y55531D01*
G01X352269Y24974D02*
Y24779D01*
G01X352165Y53453D02*
Y51594D01*
G01Y58681D02*
Y55531D01*
G01X351978Y28732D02*
Y28978D01*
G01X351971Y70060D02*
Y67451D01*
G01X351968Y11170D02*
Y10945D01*
G01X351951Y27205D02*
Y26591D01*
G01X351771Y27580D02*
Y28200D01*
G01X351515Y39685D02*
Y44016D01*
G01X351181Y11170D02*
Y10945D01*
G01X351122Y44803D02*
Y46969D01*
G01X351121Y69759D02*
Y67451D01*
G01X351102Y11170D02*
Y7992D01*
G01X350984Y53642D02*
Y51594D01*
G01X350827Y44488D02*
Y45622D01*
G01X350797Y28978D02*
Y28732D01*
G01X350384Y28978D02*
Y28732D01*
G01X350353Y69759D02*
Y68273D01*
G01X349901Y38613D02*
Y36214D01*
G01X349803Y38613D02*
Y36384D01*
G01X349409Y27580D02*
Y28200D01*
G01X349384Y67451D02*
Y67556D01*
G01X349229Y27205D02*
Y26591D01*
G01X349203Y28732D02*
Y28978D01*
G01X349113Y67556D02*
Y67451D01*
G01X348912Y24974D02*
Y24779D01*
G01X348228Y28169D02*
Y27580D01*
G01Y34370D02*
Y30433D01*
G01X348144Y70881D02*
Y68273D01*
G01X348048Y26591D02*
Y27205D01*
G01X348026Y18674D02*
Y18868D01*
G01X347731Y24779D02*
Y24974D01*
G01X347401Y40748D02*
Y41929D01*
G01Y33268D02*
Y34449D01*
G01Y11220D02*
Y12402D01*
G01Y3740D02*
Y4921D01*
G01X347244Y55205D02*
Y55831D01*
G01X346949Y57591D02*
Y56341D01*
G01Y67482D02*
Y66236D01*
G01X346850Y73522D02*
Y55216D01*
G01X346845Y18868D02*
Y18674D01*
G01X346693Y33661D02*
Y41535D01*
G01Y4134D02*
Y12008D01*
G01X353252Y24740D02*
X353253Y24727D01*
G01X353450Y24779D02*
X353282Y26126D01*
G01X354336Y18868D02*
X354464Y17857D01*
G01X353283D02*
X353154Y18868D01*
G01X353010Y26771D02*
X352936Y27328D01*
G01X354512Y28707D02*
X356086Y17631D01*
G01X353331Y28707D02*
X354905Y17631D01*
G01X346614Y33661D02*
Y41535D01*
G01Y4134D02*
Y12008D01*
G01X346456Y45197D02*
Y48150D01*
G01X346063Y54829D02*
Y46049D01*
G01Y73522D02*
Y55216D01*
G01X346023Y57894D02*
Y56122D01*
G01Y67736D02*
Y65965D01*
G01X344330Y45622D02*
Y44488D01*
G01X344035Y44803D02*
Y46969D01*
G01X343740Y41434D02*
Y43898D01*
G01Y11907D02*
Y33763D01*
G01X343661Y41434D02*
Y43898D01*
G01Y11907D02*
Y33763D01*
G01X343641Y44016D02*
Y39685D01*
G01X343071Y48346D02*
Y45787D01*
G01X342972Y45886D02*
Y48248D01*
G01X342874Y4921D02*
Y3740D01*
G01Y12402D02*
Y11220D01*
G01Y34449D02*
Y33268D01*
G01Y41929D02*
Y40748D01*
G01X341693Y51299D02*
Y48543D01*
G01X341676Y52674D02*
Y52939D01*
G01X341594Y48248D02*
Y51594D01*
G01X341267Y54263D02*
Y53638D01*
G01X341201Y39685D02*
Y54646D01*
G01X340610Y49421D02*
Y45787D01*
G01X340512Y62271D02*
Y62897D01*
G01Y54495D02*
Y53869D01*
G01X354464Y17857D02*
X354527Y17409D01*
G01X354265Y17857D02*
X354332Y17381D01*
G01X353283Y17857D02*
X353346Y17409D01*
G01X353450Y24974D02*
X354336Y18868D01*
G01Y18674D02*
X353450Y24779D01*
G01X353253Y24727D02*
X354139Y18621D01*
G01X353154Y18868D02*
X352269Y24974D01*
G01Y24779D02*
X353154Y18674D01*
G01X352958Y18621D02*
X352070Y24741D01*
G01X351540Y28713D02*
X351753Y27328D01*
G01X354464Y17857D02*
X354336Y18674D01*
G01X354265Y17857D02*
X354136Y18635D01*
G01X352955D02*
X353084Y17857D01*
G01X351771Y28200D02*
X351951Y27205D01*
G01X352953Y27580D02*
X353133Y26591D01*
G01X351951D02*
X351771Y27580D01*
G01X353132Y27205D02*
X352953Y28169D01*
G01X360643Y5007D02*
X360670Y4967D01*
G01D02*
X360642Y5007D01*
G01X360565Y5119D02*
X360643Y5007D01*
G01X360642D02*
X360564Y5120D01*
G01X360264Y16470D02*
X360868Y15608D01*
G01X359296Y15793D02*
X359900Y14930D01*
G01X359389Y8925D02*
X362177Y4943D01*
G01X359356Y8902D02*
X360914Y6677D01*
G01X359324Y8879D02*
X360814Y6751D01*
G01X358421Y8247D02*
X361661Y3620D01*
G01X358389Y8225D02*
X360565Y5119D01*
G01X358357Y8202D02*
X360570Y5042D01*
G01X347923Y24742D02*
X347928Y24736D01*
G01X348679Y18481D02*
X349185Y17878D01*
G01X348990Y15659D02*
X350000Y14456D01*
G01X348387Y15153D02*
X349961Y13277D01*
G01X349966Y13271D02*
X349972Y13265D01*
G01X358110Y51496D02*
X358307Y51299D01*
G01X359390Y45787D02*
X359980Y45197D01*
G01X350212Y46481D02*
X350654Y46039D01*
G01X351122Y44803D02*
X351909Y44016D01*
G01X346456Y45197D02*
X347638Y44016D01*
G01X341693Y48543D02*
X341890Y48346D01*
G01X356102Y28465D02*
X354134Y30433D01*
G01X347008Y67736D02*
X346023D01*
G01X346850Y67638D02*
X346063D01*
G01X346850Y67620D02*
X346063D01*
G01X351971Y67556D02*
X351121D01*
G01X349384D02*
X349113D01*
G01X349384Y67451D02*
X349113D01*
G01X351971D02*
X351121D01*
G01X346063Y67343D02*
X346850D01*
G01X346063Y66358D02*
X346850D01*
G01X346063Y66081D02*
X346850D01*
G01Y66063D02*
X346063D01*
G01X361260D02*
X360886D01*
G01X347008Y65965D02*
X346023D01*
G01X361260Y65276D02*
X360886D01*
G01X353937Y63799D02*
X352953D01*
G01X360866Y63732D02*
X360472D01*
G01X353937Y63690D02*
X353149D01*
G01X353937Y63672D02*
X353149D01*
G01X361850Y63482D02*
X362638D01*
G01X353149Y63395D02*
X353937D01*
G01X360866Y63106D02*
X360472D01*
G01X362638Y62480D02*
X361456D01*
G01X353149Y62410D02*
X353937D01*
G01X353149Y62133D02*
X353937D01*
G01Y62115D02*
X353149D01*
G01X353937Y62028D02*
X352953D01*
G01X362638Y62001D02*
X361456D01*
G01X346850Y61850D02*
X346063D01*
G01X353937Y60593D02*
X353149D01*
G01X346063Y59764D02*
X346850D01*
G01X359882Y58681D02*
X352165D01*
G01X353149Y58507D02*
X353937D01*
G01X354134Y57927D02*
X359882D01*
G01X347008Y57894D02*
X346023D01*
G01X346850Y57795D02*
X346063D01*
G01X346850Y57777D02*
X346063D01*
G01Y57500D02*
X346850D01*
G01X346063Y56516D02*
X346850D01*
G01X360866Y56417D02*
X360472D01*
G01X346063Y56239D02*
X346850D01*
G01Y56220D02*
X346063D01*
G01X347008Y56122D02*
X346023D01*
G01X353937Y55925D02*
X352953D01*
G01X352756Y55831D02*
X347244D01*
G01X353937Y55816D02*
X353149D01*
G01X353937Y55798D02*
X353149D01*
G01X352165Y55531D02*
X359882D01*
G01X353149Y55521D02*
X353937D01*
G01X346850Y55216D02*
X346063D01*
G01X352756Y55205D02*
X347244D01*
G01X361260Y54828D02*
X360078D01*
G01X341201Y54646D02*
X358799D01*
G01X353149Y54536D02*
X353937D01*
G01X360275Y54495D02*
X359488D01*
G01X346063Y54263D02*
X341267D01*
G01X358732D02*
X353937D01*
G01X353149Y54259D02*
X353937D01*
G01Y54241D02*
X353149D01*
G01X353937Y54154D02*
X352953D01*
G01X360886Y53923D02*
X361260D01*
G01X360275Y53869D02*
X359488D01*
G01X353937Y53638D02*
X358732D01*
G01X341267D02*
X346063D01*
G01X360886Y53241D02*
X361260D01*
G01X353154Y18674D02*
X352958Y18621D01*
G01X354139D02*
X354336Y18674D01*
G01X349975Y13261D02*
X349969Y13267D01*
G01X349989Y13246D02*
X349980Y13255D01*
G01X349991Y13243D02*
X349980Y13255D01*
G01X349994Y13240D02*
X349989Y13246D01*
G01X349991Y13243D02*
X350000Y13234D01*
G01X360570Y5042D02*
X360613Y4996D01*
G01X360570Y5042D02*
X360613Y4996D01*
G01X361128Y20155D02*
X361406Y19877D01*
G01X360493Y19520D02*
X361328Y18685D01*
G01X344804Y34236D02*
X345740Y33300D01*
G01X344748Y34180D02*
X345685Y33244D01*
G01X359539Y18566D02*
X360374Y17731D01*
G01X359735Y12203D02*
X360625Y11312D01*
G01X359861Y10658D02*
X359916Y10603D01*
G01X358608Y11076D02*
X359499Y10185D01*
G01X350590Y7992D02*
X350000Y8583D01*
G01X344804Y4708D02*
X345740Y3772D01*
G01X344748Y4653D02*
X345685Y3716D01*
G01X359781Y12252D02*
X359840Y12201D01*
G01X350000Y38898D02*
X348819Y39685D01*
G01X351753Y27328D02*
X351948Y27224D01*
G01X352953Y63799D02*
X346949Y66236D01*
G01X353051Y63511D02*
X347008Y65965D01*
G01X352953Y55925D02*
X346949Y56341D01*
G01X353051Y55704D02*
X347008Y56122D01*
G01X348030Y17403D02*
X347835Y17409D01*
G01X350000Y28097D02*
X349979D01*
G01X350000Y20814D02*
X349803Y20819D01*
G01X353937Y51969D02*
X361260D01*
G01Y51772D02*
X360078D01*
G01X361260Y51705D02*
X360078D01*
G01X350984Y51594D02*
X341594D01*
G01X358405D02*
X352165D01*
G01X359882D02*
X358799D01*
G01X360078Y50943D02*
X361260D01*
G01Y50182D02*
X360078D01*
G01Y49424D02*
X361260D01*
G01X358799Y49421D02*
X360275D01*
G01X358307D02*
X358405D01*
G01X341594D02*
X341693D01*
G01X361260Y48664D02*
X360078D01*
G01X356929Y48346D02*
X358110D01*
G01X341890D02*
X343071D01*
G01X342972Y48248D02*
X341594D01*
G01X358405D02*
X357027D01*
G01X353543Y48150D02*
X346456D01*
G01X361260Y47953D02*
X360078D01*
G01Y47902D02*
X361260D01*
G01Y47835D02*
X360078D01*
G01X360767Y47756D02*
X359980D01*
G01X346456Y47165D02*
X353543D01*
G01X351122Y46969D02*
X344035D01*
G01X359882Y46870D02*
X358799D01*
G01X349795Y46654D02*
X345362D01*
G01X361260Y46483D02*
X360078D01*
G01X344724Y46260D02*
X350433D01*
G01X357027Y45886D02*
X359882D01*
G01X361260Y45802D02*
X360078D01*
G01X343071Y45787D02*
X340610D01*
G01X359390D02*
X356929D01*
G01X361456Y44291D02*
X361260D01*
G01X360275D02*
X360078D01*
G01X359980Y44016D02*
X343641D01*
G01X346063Y43898D02*
X361260D01*
G01X343661Y42323D02*
X343267D01*
G01X347008D02*
X343740D01*
G01X361260Y41654D02*
X360078D01*
G01X361260Y40866D02*
X360078D01*
G01X346693Y40354D02*
X347008D01*
G01X343267D02*
X346614D01*
G01X358799Y39685D02*
X341201D01*
G01X355866Y39569D02*
X355078D01*
G01X357244Y38898D02*
X350000D01*
G01Y38613D02*
X349803D01*
G01X355866Y38558D02*
X355078D01*
G01X355866Y38512D02*
X355078D01*
G01X355866Y38217D02*
X355078D01*
G01X355866Y38164D02*
X355078D01*
G01X355866Y37717D02*
X355078D01*
G01X350000Y36732D02*
X349803D01*
G01X346614Y34843D02*
X343267D01*
G01X347008D02*
X346693D01*
G01X343267Y32874D02*
X343661D01*
G01X343740D02*
X347008D01*
G01X349203Y30906D02*
X351978D01*
G01X347441Y29646D02*
X340807D01*
G01X359193D02*
X354921D01*
G01X349203Y28978D02*
X351978D01*
G01X349203Y28732D02*
X351978D01*
G01X356102Y28465D02*
X358012D01*
G01X341988D02*
X346260D01*
G01X360078Y27756D02*
X361260D01*
G01X348238Y27626D02*
X352942D01*
G01X348244Y27328D02*
X352936D01*
G01X361260Y26697D02*
X360078D01*
G01X348048Y26591D02*
X353133D01*
G01X361260Y26453D02*
X360078D01*
G01X347731Y24974D02*
X353450D01*
G01X347929Y24740D02*
X353252D01*
G01X361260Y22402D02*
X360078D01*
G01X361260Y20066D02*
X360078D01*
G01X346845Y18868D02*
X354336D01*
G01X347044Y18635D02*
X354136D01*
G01X346916Y17857D02*
X346717D01*
G01D02*
X354464D01*
G01X354265D02*
X354464D01*
G01X355866Y16063D02*
X357244D01*
G01X361260Y14366D02*
X360078D01*
G01X361260Y12843D02*
X360078D01*
G01X343661Y12795D02*
X343267D01*
G01X347008D02*
X343740D01*
G01X353150Y17403D02*
X353345Y17409D01*
G01X354332Y17381D02*
X354527Y17409D01*
G01X354495Y9760D02*
X352268Y9164D01*
G01X354699Y9000D02*
X352472Y8403D01*
G01X340611Y8925D02*
X341643Y8202D01*
G01X347923Y24742D02*
X347734Y24803D01*
G01X348026Y18674D02*
X348223Y18621D01*
G01X347042D02*
X346845Y18674D01*
G01X348912Y24779D02*
X349050Y24752D01*
G01D02*
X349119Y24739D01*
G01X346848Y17381D02*
X346653Y17409D01*
G01X353149Y11170D02*
X351102D01*
G01X351968Y10945D02*
X351181D01*
G01X346693Y10827D02*
X347008D01*
G01X343267D02*
X346614D01*
G01X353937Y9764D02*
X351102D01*
G01X353937Y8780D02*
X351102D01*
G01Y7992D02*
X350590D01*
G01X361260Y6447D02*
X360078D01*
G01X361260Y6309D02*
X360078D01*
G01Y5591D02*
X361260D01*
G01X346614Y5315D02*
X343267D01*
G01X347008D02*
X346693D01*
G01X343267Y3346D02*
X343661D01*
G01X343740D02*
X347008D01*
G01X361260Y2803D02*
X360078D01*
G01X349760Y68658D02*
X349762Y68677D01*
G01X349753Y68639D02*
X349760Y68658D01*
G01X349742Y68622D02*
X349753Y68639D01*
G01X349728Y68607D02*
X349742Y68622D01*
G01X349710Y68594D02*
X349728Y68607D01*
G01X349689Y68585D02*
X349710Y68594D01*
G01X349667Y68579D02*
X349689Y68585D01*
G01X349644Y68577D02*
X349667Y68579D01*
G01X350355Y69779D02*
X350353Y69759D01*
G01X350362Y69798D02*
X350355Y69779D01*
G01X350373Y69815D02*
X350362Y69798D01*
G01X350388Y69830D02*
X350373Y69815D01*
G01X350406Y69843D02*
X350388Y69830D01*
G01X350426Y69852D02*
X350406Y69843D01*
G01X350448Y69858D02*
X350426Y69852D01*
G01X350471Y69859D02*
X350448Y69858D01*
G01X349782Y70118D02*
X349762Y69955D01*
G01X349837Y70271D02*
X349782Y70118D01*
G01X349926Y70412D02*
X349837Y70271D01*
G01X350046Y70536D02*
X349926Y70412D01*
G01X350195Y70640D02*
X350046Y70536D01*
G01X350362Y70715D02*
X350195Y70640D01*
G01X350543Y70761D02*
X350362Y70715D01*
G01X350731Y70777D02*
X350543Y70761D01*
G01X350355Y73966D02*
X350353Y73946D01*
G01X350362Y73985D02*
X350355Y73966D01*
G01X350373Y74002D02*
X350362Y73985D01*
G01X350388Y74017D02*
X350373Y74002D01*
G01X350406Y74029D02*
X350388Y74017D01*
G01X350426Y74039D02*
X350406Y74029D01*
G01X350448Y74044D02*
X350426Y74039D01*
G01X350471Y74046D02*
X350448Y74044D01*
G01X348997Y73966D02*
X348995Y73946D01*
G01X349004Y73985D02*
X348997Y73966D01*
G01X349015Y74002D02*
X349004Y73985D01*
G01X349029Y74017D02*
X349015Y74002D01*
G01X349047Y74029D02*
X349029Y74017D01*
G01X349068Y74039D02*
X349047Y74029D01*
G01X349090Y74044D02*
X349068Y74039D01*
G01X349113Y74046D02*
X349090Y74044D01*
G01X348163Y74305D02*
X348144Y74142D01*
G01X348219Y74458D02*
X348163Y74305D01*
G01X348308Y74599D02*
X348219Y74458D01*
G01X348428Y74723D02*
X348308Y74599D01*
G01X348577Y74826D02*
X348428Y74723D01*
G01X348744Y74902D02*
X348577Y74826D01*
G01X348925Y74948D02*
X348744Y74902D01*
G01X349113Y74964D02*
X348925Y74948D01*
G01X351118Y78163D02*
X351121Y78183D01*
G01X351112Y78144D02*
X351118Y78163D01*
G01X351101Y78127D02*
X351112Y78144D01*
G01X351086Y78112D02*
X351101Y78127D01*
G01X351068Y78100D02*
X351086Y78112D01*
G01X351048Y78090D02*
X351068Y78100D01*
G01X351026Y78085D02*
X351048Y78090D01*
G01X351003Y78083D02*
X351026Y78085D01*
G01X351952Y80631D02*
X351971Y80793D01*
G01X351897Y80477D02*
X351952Y80631D01*
G01X351807Y80336D02*
X351897Y80477D01*
G01X351687Y80212D02*
X351807Y80336D01*
G01X351539Y80109D02*
X351687Y80212D01*
G01X351372Y80034D02*
X351539Y80109D01*
G01X351191Y79987D02*
X351372Y80034D01*
G01X351003Y79972D02*
X351191Y79987D01*
G01X350764Y81178D02*
X350766Y81198D01*
G01X350757Y81159D02*
X350764Y81178D01*
G01X350746Y81142D02*
X350757Y81159D01*
G01X350732Y81127D02*
X350746Y81142D01*
G01X350714Y81114D02*
X350732Y81127D01*
G01X350693Y81105D02*
X350714Y81114D01*
G01X350671Y81100D02*
X350693Y81105D01*
G01X350648Y81098D02*
X350671Y81100D01*
G01X349351Y82340D02*
X349349Y82320D01*
G01X349358Y82358D02*
X349351Y82340D01*
G01X349369Y82375D02*
X349358Y82358D01*
G01X349384Y82391D02*
X349369Y82375D01*
G01X349402Y82403D02*
X349384Y82391D01*
G01X349422Y82412D02*
X349402Y82403D01*
G01X349444Y82418D02*
X349422Y82412D01*
G01X349467Y82420D02*
X349444Y82418D01*
G01X348650Y87587D02*
X348658D01*
G01X348643Y87588D02*
X348650Y87587D01*
G01X348637Y87588D02*
X348643D01*
G01X348630D02*
X348637D01*
G01X348623D02*
X348630D01*
G01X348617D02*
X348623D01*
G01X362603Y96411D02*
X362638Y96226D01*
G01X362501Y96587D02*
X362603Y96411D01*
G01X362338Y96748D02*
X362501Y96587D01*
G01X362119Y96890D02*
X362338Y96748D01*
G01X361846Y97008D02*
X362119Y96890D01*
G01X361541Y97094D02*
X361846Y97008D01*
G01X361210Y97147D02*
X361541Y97094D01*
G01X360866Y97165D02*
X361210Y97147D01*
G01X358797Y97567D02*
X358596Y97736D01*
G01X359024Y97425D02*
X358797Y97567D01*
G01X359265Y97314D02*
X359024Y97425D01*
G01X359529Y97231D02*
X359265Y97314D01*
G01X359805Y97181D02*
X359529Y97231D01*
G01X360078Y97165D02*
X359805Y97181D01*
G01X348625Y87484D02*
X348617D01*
G01X348632D02*
X348625D01*
G01X348638D02*
X348632D01*
G01X348645Y87483D02*
X348638Y87484D01*
G01X348651Y87483D02*
X348645D01*
G01X348658Y87482D02*
X348651Y87483D01*
G01X348997Y68553D02*
X348995Y68573D01*
G01X349004Y68535D02*
X348997Y68553D01*
G01X349015Y68517D02*
X349004Y68535D01*
G01X349029Y68502D02*
X349015Y68517D01*
G01X349047Y68490D02*
X349029Y68502D01*
G01X349068Y68481D02*
X349047Y68490D01*
G01X349090Y68475D02*
X349068Y68481D01*
G01X349113Y68473D02*
X349090Y68475D01*
G01X351118Y69675D02*
X351121Y69655D01*
G01X351112Y69693D02*
X351118Y69675D01*
G01X351101Y69711D02*
X351112Y69693D01*
G01X351086Y69726D02*
X351101Y69711D01*
G01X351068Y69738D02*
X351086Y69726D01*
G01X351048Y69748D02*
X351068Y69738D01*
G01X351026Y69753D02*
X351048Y69748D01*
G01X351003Y69755D02*
X351026Y69753D01*
G01X351952Y70222D02*
X351971Y70060D01*
G01X351897Y70375D02*
X351952Y70222D01*
G01X351807Y70517D02*
X351897Y70375D01*
G01X351687Y70641D02*
X351807Y70517D01*
G01X351539Y70744D02*
X351687Y70641D01*
G01X351372Y70819D02*
X351539Y70744D01*
G01X351191Y70865D02*
X351372Y70819D01*
G01X351003Y70881D02*
X351191Y70865D01*
G01X349760Y73862D02*
X349762Y73842D01*
G01X349753Y73880D02*
X349760Y73862D01*
G01X349742Y73897D02*
X349753Y73880D01*
G01X349728Y73913D02*
X349742Y73897D01*
G01X349710Y73925D02*
X349728Y73913D01*
G01X349689Y73934D02*
X349710Y73925D01*
G01X349667Y73940D02*
X349689Y73934D01*
G01X349644Y73942D02*
X349667Y73940D01*
G01X351118Y73862D02*
X351121Y73842D01*
G01X351112Y73880D02*
X351118Y73862D01*
G01X351101Y73897D02*
X351112Y73880D01*
G01X351086Y73913D02*
X351101Y73897D01*
G01X351068Y73925D02*
X351086Y73913D01*
G01X351048Y73934D02*
X351068Y73925D01*
G01X351026Y73940D02*
X351048Y73934D01*
G01X351003Y73942D02*
X351026Y73940D01*
G01X351952Y74409D02*
X351971Y74247D01*
G01X351897Y74562D02*
X351952Y74409D01*
G01X351807Y74703D02*
X351897Y74562D01*
G01X351687Y74827D02*
X351807Y74703D01*
G01X351539Y74931D02*
X351687Y74827D01*
G01X351372Y75006D02*
X351539Y74931D01*
G01X351191Y75052D02*
X351372Y75006D01*
G01X351003Y75068D02*
X351191Y75052D01*
G01X351118Y76876D02*
X351121Y76857D01*
G01X351112Y76895D02*
X351118Y76876D01*
G01X351101Y76912D02*
X351112Y76895D01*
G01X351086Y76927D02*
X351101Y76912D01*
G01X351068Y76940D02*
X351086Y76927D01*
G01X351048Y76949D02*
X351068Y76940D01*
G01X351026Y76955D02*
X351048Y76949D01*
G01X351003Y76957D02*
X351026Y76955D01*
G01X348163Y80735D02*
X348144Y80897D01*
G01X348219Y80582D02*
X348163Y80735D01*
G01X348308Y80440D02*
X348219Y80582D01*
G01X348428Y80317D02*
X348308Y80440D01*
G01X348577Y80213D02*
X348428Y80317D01*
G01X348744Y80138D02*
X348577Y80213D01*
G01X348925Y80092D02*
X348744Y80138D01*
G01X349113Y80076D02*
X348925Y80092D01*
G01X349351Y81074D02*
X349349Y81094D01*
G01X349358Y81055D02*
X349351Y81074D01*
G01X349369Y81038D02*
X349358Y81055D01*
G01X349384Y81023D02*
X349369Y81038D01*
G01X349402Y81010D02*
X349384Y81023D01*
G01X349422Y81001D02*
X349402Y81010D01*
G01X349444Y80995D02*
X349422Y81001D01*
G01X349467Y80993D02*
X349444Y80995D01*
G01X350764Y82235D02*
X350766Y82215D01*
G01X350757Y82254D02*
X350764Y82235D01*
G01X350746Y82271D02*
X350757Y82254D01*
G01X350732Y82286D02*
X350746Y82271D01*
G01X350714Y82299D02*
X350732Y82286D01*
G01X350693Y82308D02*
X350714Y82299D01*
G01X350671Y82314D02*
X350693Y82308D01*
G01X350648Y82316D02*
X350671Y82314D01*
G01X351952Y82783D02*
X351971Y82620D01*
G01X351897Y82936D02*
X351952Y82783D01*
G01X351807Y83077D02*
X351897Y82936D01*
G01X351687Y83201D02*
X351807Y83077D01*
G01X351539Y83304D02*
X351687Y83201D01*
G01X351372Y83380D02*
X351539Y83304D01*
G01X351191Y83426D02*
X351372Y83380D01*
G01X351003Y83442D02*
X351191Y83426D01*
G01X345540Y97497D02*
X345669Y97576D01*
G01X345432Y97398D02*
X345540Y97497D01*
G01X345350Y97282D02*
X345432Y97398D01*
G01X345298Y97157D02*
X345350Y97282D01*
G01X345276Y97023D02*
X345298Y97157D01*
G01X345286Y96889D02*
X345276Y97023D01*
G01X345327Y96761D02*
X345286Y96889D01*
G01X345398Y96640D02*
X345327Y96761D01*
G01X345496Y96534D02*
X345398Y96640D01*
G01X345616Y96448D02*
X345496Y96534D01*
G01X345755Y96383D02*
X345616Y96448D01*
G01X345907Y96343D02*
X345755Y96383D01*
G01X346063Y96330D02*
X345907Y96343D01*
G01X341537Y97261D02*
X341403Y97110D01*
G01X341635Y97400D02*
X341537Y97261D01*
G01X341701Y97527D02*
X341635Y97400D01*
G01X341741Y97642D02*
X341701Y97527D01*
G01X341755Y97746D02*
X341741Y97642D01*
G01X341743Y97839D02*
X341755Y97746D01*
G01X341705Y97917D02*
X341743Y97839D01*
G01X341638Y97979D02*
X341705Y97917D01*
G01X341539Y98020D02*
X341638Y97979D01*
G01X341403Y98035D02*
X341539Y98020D01*
G01X341630Y98189D02*
X341403Y97736D01*
G01X341742Y98599D02*
X341630Y98189D01*
G01X341738Y98931D02*
X341742Y98599D01*
G01X341625Y99140D02*
X341738Y98931D01*
G01X341403Y99216D02*
X341625Y99140D01*
G01X354143Y97078D02*
X354111Y97110D01*
G01X354177Y97048D02*
X354143Y97078D01*
G01X354214Y97020D02*
X354177Y97048D01*
G01X354250Y96995D02*
X354214Y97020D01*
G01X354291Y96971D02*
X354250Y96995D01*
G01X354330Y96950D02*
X354291Y96971D01*
G01X354095Y96344D02*
X353937Y96330D01*
G01X354247Y96384D02*
X354095Y96344D01*
G01X354386Y96449D02*
X354247Y96384D01*
G01X354505Y96536D02*
X354386Y96449D01*
G01X354603Y96642D02*
X354505Y96536D01*
G01X354674Y96763D02*
X354603Y96642D01*
G01X354714Y96891D02*
X354674Y96763D01*
G01X354723Y97026D02*
X354714Y96891D01*
G01X354701Y97159D02*
X354723Y97026D01*
G01X354648Y97284D02*
X354701Y97159D01*
G01X354566Y97400D02*
X354648Y97284D01*
G01X354457Y97499D02*
X354566Y97400D01*
G01X354330Y97576D02*
X354457Y97499D01*
G01X349011Y86477D02*
X348995Y86427D01*
G01X349054Y86514D02*
X349011Y86477D01*
G01X349114Y86527D02*
X349054Y86514D01*
G01X354460Y96871D02*
X354330Y96950D01*
G01X354567Y96772D02*
X354460Y96871D01*
G01X354649Y96656D02*
X354567Y96772D01*
G01X354701Y96531D02*
X354649Y96656D01*
G01X354724Y96398D02*
X354701Y96531D01*
G01X354714Y96263D02*
X354724Y96398D01*
G01X354673Y96135D02*
X354714Y96263D01*
G01X354602Y96014D02*
X354673Y96135D01*
G01X354503Y95908D02*
X354602Y96014D01*
G01X354384Y95822D02*
X354503Y95908D01*
G01X354244Y95757D02*
X354384Y95822D01*
G01X354092Y95717D02*
X354244Y95757D01*
G01X353937Y95704D02*
X354092Y95717D01*
G01X348163Y82678D02*
X348144Y82516D01*
G01X348219Y82832D02*
X348163Y82678D01*
G01X348308Y82973D02*
X348219Y82832D01*
G01X348428Y83097D02*
X348308Y82973D01*
G01X348577Y83200D02*
X348428Y83097D01*
G01X348744Y83275D02*
X348577Y83200D01*
G01X348925Y83322D02*
X348744Y83275D01*
G01X349113Y83337D02*
X348925Y83322D01*
G01X348154Y87163D02*
X348144Y87083D01*
G01X348181Y87237D02*
X348154Y87163D01*
G01X348224Y87306D02*
X348181Y87237D01*
G01X348283Y87367D02*
X348224Y87306D01*
G01X348355Y87417D02*
X348283Y87367D01*
G01X348437Y87454D02*
X348355Y87417D01*
G01X348525Y87476D02*
X348437Y87454D01*
G01X348617Y87484D02*
X348525Y87476D01*
G01X341202Y96941D02*
X341403Y97110D01*
G01X340976Y96799D02*
X341202Y96941D01*
G01X340734Y96688D02*
X340976Y96799D01*
G01X340470Y96605D02*
X340734Y96688D01*
G01X359796Y96556D02*
X360078Y96539D01*
G01X359521Y96607D02*
X359796Y96556D01*
G01X359264Y96689D02*
X359521Y96607D01*
G01X359016Y96803D02*
X359264Y96689D01*
G01X358791Y96946D02*
X359016Y96803D01*
G01X358596Y97110D02*
X358791Y96946D01*
G01X354289Y97598D02*
X354330Y97576D01*
G01X354248Y97622D02*
X354289Y97598D01*
G01X354210Y97649D02*
X354248Y97622D01*
G01X354176Y97675D02*
X354210Y97649D01*
G01X354141Y97706D02*
X354176Y97675D01*
G01X354111Y97736D02*
X354141Y97706D01*
G01X358462Y98026D02*
X358596Y98035D01*
G01X358365Y98001D02*
X358462Y98026D01*
G01X358298Y97960D02*
X358365Y98001D01*
G01X358259Y97902D02*
X358298Y97960D01*
G01X358245Y97827D02*
X358259Y97902D01*
G01X358256Y97733D02*
X358245Y97827D01*
G01X358294Y97617D02*
X358256Y97733D01*
G01X358361Y97476D02*
X358294Y97617D01*
G01X358460Y97308D02*
X358361Y97476D01*
G01X358596Y97110D02*
X358460Y97308D01*
G01X353969Y97359D02*
X353937Y97410D01*
G01X353996Y97313D02*
X353969Y97359D01*
G01X354024Y97265D02*
X353996Y97313D01*
G01X354055Y97210D02*
X354024Y97265D01*
G01X354083Y97161D02*
X354055Y97210D01*
G01X354111Y97110D02*
X354083Y97161D01*
G01X361808Y92026D02*
X361850Y91573D01*
G01X361677Y92533D02*
X361808Y92026D01*
G01X361456Y93075D02*
X361677Y92533D01*
G01X358369Y99165D02*
X358596Y99216D01*
G01X358257Y98996D02*
X358369Y99165D01*
G01X358262Y98696D02*
X358257Y98996D01*
G01X358375Y98281D02*
X358262Y98696D01*
G01X358596Y97736D02*
X358375Y98281D01*
G01X354081Y97823D02*
X354111Y97736D01*
G01X354052Y97908D02*
X354081Y97823D01*
G01X354022Y97990D02*
X354052Y97908D01*
G01X353992Y98071D02*
X354022Y97990D01*
G01X353963Y98149D02*
X353992Y98071D01*
G01X353937Y98217D02*
X353963Y98149D01*
G01X360983Y96533D02*
X360866Y96539D01*
G01X361093Y96515D02*
X360983Y96533D01*
G01X361194Y96486D02*
X361093Y96515D01*
G01X361283Y96447D02*
X361194Y96486D01*
G01X361358Y96399D02*
X361283Y96447D01*
G01X361412Y96345D02*
X361358Y96399D01*
G01X361445Y96287D02*
X361412Y96345D01*
G01X361456Y96226D02*
X361445Y96287D01*
G01X360298Y96912D02*
X360078Y97112D01*
G01X360430Y96639D02*
X360298Y96912D01*
G01X360472Y96319D02*
X360430Y96639D01*
G01X349089Y68579D02*
X349113Y68577D01*
G01X349067Y68585D02*
X349089Y68579D01*
G01X349047Y68594D02*
X349067Y68585D01*
G01X349029Y68607D02*
X349047Y68594D01*
G01X349014Y68622D02*
X349029Y68607D01*
G01X349004Y68639D02*
X349014Y68622D01*
G01X348997Y68658D02*
X349004Y68639D01*
G01X348995Y68677D02*
X348997Y68658D01*
G01X348921Y79988D02*
X349113Y79972D01*
G01X348741Y80035D02*
X348921Y79988D01*
G01X348574Y80111D02*
X348741Y80035D01*
G01X348428Y80212D02*
X348574Y80111D01*
G01X348306Y80339D02*
X348428Y80212D01*
G01X348217Y80480D02*
X348306Y80339D01*
G01X348163Y80634D02*
X348217Y80480D01*
G01X348144Y80793D02*
X348163Y80634D01*
G01X349668Y74044D02*
X349644Y74046D01*
G01X349690Y74039D02*
X349668Y74044D01*
G01X349710Y74029D02*
X349690Y74039D01*
G01X349728Y74017D02*
X349710Y74029D01*
G01X349743Y74001D02*
X349728Y74017D01*
G01X349753Y73984D02*
X349743Y74001D01*
G01X349760Y73966D02*
X349753Y73984D01*
G01X349762Y73946D02*
X349760Y73966D01*
G01X349444Y81100D02*
X349467Y81098D01*
G01X349422Y81105D02*
X349444Y81100D01*
G01X349401Y81115D02*
X349422Y81105D01*
G01X349384Y81127D02*
X349401Y81115D01*
G01X349369Y81142D02*
X349384Y81127D01*
G01X349358Y81160D02*
X349369Y81142D01*
G01X349351Y81178D02*
X349358Y81160D01*
G01X349349Y81198D02*
X349351Y81178D01*
G01X351026Y69857D02*
X351003Y69859D01*
G01X351048Y69852D02*
X351026Y69857D01*
G01X351068Y69842D02*
X351048Y69852D01*
G01X351086Y69830D02*
X351068Y69842D01*
G01X351101Y69815D02*
X351086Y69830D01*
G01X351112Y69797D02*
X351101Y69815D01*
G01X351118Y69779D02*
X351112Y69797D01*
G01X351121Y69759D02*
X351118Y69779D01*
G01X351026Y74044D02*
X351003Y74046D01*
G01X351048Y74039D02*
X351026Y74044D01*
G01X351068Y74029D02*
X351048Y74039D01*
G01X351086Y74017D02*
X351068Y74029D01*
G01X351101Y74001D02*
X351086Y74017D01*
G01X351112Y73984D02*
X351101Y74001D01*
G01X351118Y73966D02*
X351112Y73984D01*
G01X351121Y73946D02*
X351118Y73966D01*
G01X351026Y77059D02*
X351003Y77061D01*
G01X351048Y77053D02*
X351026Y77059D01*
G01X351068Y77044D02*
X351048Y77053D01*
G01X351086Y77032D02*
X351068Y77044D01*
G01X351101Y77016D02*
X351086Y77032D01*
G01X351112Y76999D02*
X351101Y77016D01*
G01X351118Y76980D02*
X351112Y76999D01*
G01X351121Y76961D02*
X351118Y76980D01*
G01X351194Y70761D02*
X351003Y70777D01*
G01X351375Y70714D02*
X351194Y70761D01*
G01X351541Y70638D02*
X351375Y70714D01*
G01X351687Y70536D02*
X351541Y70638D01*
G01X351809Y70410D02*
X351687Y70536D01*
G01X351898Y70268D02*
X351809Y70410D01*
G01X351953Y70115D02*
X351898Y70268D01*
G01X351971Y69955D02*
X351953Y70115D01*
G01X350672Y82418D02*
X350648Y82420D01*
G01X350694Y82412D02*
X350672Y82418D01*
G01X350714Y82403D02*
X350694Y82412D01*
G01X350732Y82391D02*
X350714Y82403D01*
G01X350747Y82375D02*
X350732Y82391D01*
G01X350757Y82358D02*
X350747Y82375D01*
G01X350764Y82339D02*
X350757Y82358D01*
G01X350766Y82320D02*
X350764Y82339D01*
G01X351194Y74947D02*
X351003Y74964D01*
G01X351375Y74901D02*
X351194Y74947D01*
G01X351541Y74825D02*
X351375Y74901D01*
G01X351687Y74723D02*
X351541Y74825D01*
G01X351809Y74597D02*
X351687Y74723D01*
G01X351898Y74455D02*
X351809Y74597D01*
G01X351953Y74302D02*
X351898Y74455D01*
G01X351971Y74142D02*
X351953Y74302D01*
G01X351194Y83321D02*
X351003Y83337D01*
G01X351375Y83274D02*
X351194Y83321D01*
G01X351541Y83198D02*
X351375Y83274D01*
G01X351687Y83097D02*
X351541Y83198D01*
G01X351809Y82970D02*
X351687Y83097D01*
G01X351898Y82829D02*
X351809Y82970D01*
G01X351953Y82675D02*
X351898Y82829D01*
G01X351971Y82516D02*
X351953Y82675D01*
G01X348523Y87580D02*
X348617Y87588D01*
G01X348435Y87558D02*
X348523Y87580D01*
G01X348354Y87521D02*
X348435Y87558D01*
G01X348283Y87471D02*
X348354Y87521D01*
G01X348223Y87409D02*
X348283Y87471D01*
G01X348180Y87340D02*
X348223Y87409D01*
G01X348153Y87265D02*
X348180Y87340D01*
G01X348144Y87188D02*
X348153Y87265D01*
G01X348921Y83425D02*
X349113Y83442D01*
G01X348741Y83378D02*
X348921Y83425D01*
G01X348574Y83303D02*
X348741Y83378D01*
G01X348428Y83201D02*
X348574Y83303D01*
G01X348306Y83075D02*
X348428Y83201D01*
G01X348217Y82933D02*
X348306Y83075D01*
G01X348163Y82780D02*
X348217Y82933D01*
G01X348144Y82620D02*
X348163Y82780D01*
G01X348921Y75052D02*
X349113Y75068D01*
G01X348741Y75005D02*
X348921Y75052D01*
G01X348574Y74929D02*
X348741Y75005D01*
G01X348428Y74827D02*
X348574Y74929D01*
G01X348306Y74701D02*
X348428Y74827D01*
G01X348217Y74560D02*
X348306Y74701D01*
G01X348163Y74406D02*
X348217Y74560D01*
G01X348144Y74247D02*
X348163Y74406D01*
G01X349444Y82314D02*
X349467Y82316D01*
G01X349422Y82308D02*
X349444Y82314D01*
G01X349401Y82299D02*
X349422Y82308D01*
G01X349384Y82286D02*
X349401Y82299D01*
G01X349369Y82271D02*
X349384Y82286D01*
G01X349358Y82254D02*
X349369Y82271D01*
G01X349351Y82235D02*
X349358Y82254D01*
G01X349349Y82215D02*
X349351Y82235D01*
G01X349089Y73940D02*
X349113Y73942D01*
G01X349067Y73934D02*
X349089Y73940D01*
G01X349047Y73925D02*
X349067Y73934D01*
G01X349029Y73913D02*
X349047Y73925D01*
G01X349014Y73897D02*
X349029Y73913D01*
G01X349004Y73880D02*
X349014Y73897D01*
G01X348997Y73861D02*
X349004Y73880D01*
G01X348995Y73842D02*
X348997Y73861D01*
G01X350672Y80995D02*
X350648Y80993D01*
G01X350694Y81001D02*
X350672Y80995D01*
G01X350714Y81010D02*
X350694Y81001D01*
G01X350732Y81023D02*
X350714Y81010D01*
G01X350747Y81038D02*
X350732Y81023D01*
G01X350757Y81055D02*
X350747Y81038D01*
G01X350764Y81074D02*
X350757Y81055D01*
G01X350766Y81094D02*
X350764Y81074D01*
G01X350539Y70865D02*
X350731Y70881D01*
G01X350359Y70818D02*
X350539Y70865D01*
G01X350192Y70742D02*
X350359Y70818D01*
G01X350046Y70641D02*
X350192Y70742D01*
G01X349924Y70514D02*
X350046Y70641D01*
G01X349835Y70373D02*
X349924Y70514D01*
G01X349781Y70219D02*
X349835Y70373D01*
G01X349762Y70060D02*
X349781Y70219D01*
G01X350448Y73940D02*
X350471Y73942D01*
G01X350426Y73934D02*
X350448Y73940D01*
G01X350405Y73925D02*
X350426Y73934D01*
G01X350388Y73913D02*
X350405Y73925D01*
G01X350373Y73897D02*
X350388Y73913D01*
G01X350362Y73880D02*
X350373Y73897D01*
G01X350355Y73861D02*
X350362Y73880D01*
G01X350353Y73842D02*
X350355Y73861D01*
G01X349668Y68475D02*
X349644Y68473D01*
G01X349690Y68481D02*
X349668Y68475D01*
G01X349710Y68490D02*
X349690Y68481D01*
G01X349728Y68502D02*
X349710Y68490D01*
G01X349743Y68518D02*
X349728Y68502D01*
G01X349753Y68535D02*
X349743Y68518D01*
G01X349760Y68554D02*
X349753Y68535D01*
G01X349762Y68573D02*
X349760Y68554D01*
G01X351026Y77980D02*
X351003Y77978D01*
G01X351048Y77986D02*
X351026Y77980D01*
G01X351068Y77995D02*
X351048Y77986D01*
G01X351086Y78008D02*
X351068Y77995D01*
G01X351101Y78023D02*
X351086Y78008D01*
G01X351112Y78040D02*
X351101Y78023D01*
G01X351118Y78059D02*
X351112Y78040D01*
G01X351121Y78079D02*
X351118Y78059D01*
G01X350448Y69753D02*
X350471Y69755D01*
G01X350426Y69747D02*
X350448Y69753D01*
G01X350405Y69738D02*
X350426Y69747D01*
G01X350388Y69726D02*
X350405Y69738D01*
G01X350373Y69710D02*
X350388Y69726D01*
G01X350362Y69693D02*
X350373Y69710D01*
G01X350355Y69674D02*
X350362Y69693D01*
G01X350353Y69655D02*
X350355Y69674D01*
G01X351194Y80092D02*
X351003Y80076D01*
G01X351375Y80139D02*
X351194Y80092D01*
G01X351541Y80215D02*
X351375Y80139D01*
G01X351687Y80317D02*
X351541Y80215D01*
G01X351809Y80443D02*
X351687Y80317D01*
G01X351898Y80584D02*
X351809Y80443D01*
G01X351953Y80738D02*
X351898Y80584D01*
G01X351971Y80897D02*
X351953Y80738D01*
G01X349054Y86409D02*
X349114Y86423D01*
G01X349011Y86373D02*
X349054Y86409D01*
G01X348995Y86323D02*
X349011Y86373D01*
G01X346033Y98140D02*
X346063Y98217D01*
G01X346003Y98061D02*
X346033Y98140D01*
G01X345974Y97980D02*
X346003Y98061D01*
G01X345944Y97897D02*
X345974Y97980D01*
G01X345915Y97813D02*
X345944Y97897D01*
G01X345889Y97736D02*
X345915Y97813D01*
G01X345921Y97168D02*
X345889Y97110D01*
G01X345948Y97218D02*
X345921Y97168D01*
G01X345976Y97266D02*
X345948Y97218D01*
G01X346007Y97320D02*
X345976Y97266D01*
G01X346035Y97366D02*
X346007Y97320D01*
G01X346063Y97410D02*
X346035Y97366D01*
G01X345711Y96972D02*
X345669Y96950D01*
G01X345751Y96996D02*
X345711Y96972D01*
G01X345790Y97023D02*
X345751Y96996D01*
G01X345824Y97049D02*
X345790Y97023D01*
G01X345858Y97080D02*
X345824Y97049D01*
G01X345889Y97110D02*
X345858Y97080D01*
G01X360906Y96633D02*
X360866Y96319D01*
G01X361037Y96908D02*
X360906Y96633D01*
G01X361260Y97112D02*
X361037Y96908D01*
G01X340736Y97314D02*
X340479Y97233D01*
G01X340983Y97429D02*
X340736Y97314D01*
G01X341209Y97571D02*
X340983Y97429D01*
G01X341403Y97736D02*
X341209Y97571D01*
G01X345904Y95718D02*
X346063Y95704D01*
G01X345753Y95758D02*
X345904Y95718D01*
G01X345613Y95824D02*
X345753Y95758D01*
G01X345494Y95910D02*
X345613Y95824D01*
G01X345396Y96016D02*
X345494Y95910D01*
G01X345326Y96137D02*
X345396Y96016D01*
G01X345285Y96265D02*
X345326Y96137D01*
G01X345276Y96400D02*
X345285Y96265D01*
G01X345299Y96533D02*
X345276Y96400D01*
G01X345351Y96658D02*
X345299Y96533D01*
G01X345434Y96774D02*
X345351Y96658D01*
G01X345542Y96873D02*
X345434Y96774D01*
G01X345669Y96950D02*
X345542Y96873D01*
G01X345857Y97704D02*
X345889Y97736D01*
G01X345822Y97674D02*
X345857Y97704D01*
G01X345786Y97646D02*
X345822Y97674D01*
G01X345749Y97621D02*
X345786Y97646D01*
G01X345709Y97597D02*
X345749Y97621D01*
G01X345669Y97576D02*
X345709Y97597D01*
G01X361456Y97445D02*
G03X360866Y98035I-590J0D01*
G01X361456Y81496D02*
G03X361260Y82206I-1378J2D01*
G01X362638Y97445D02*
G03X360866Y99216I-1771J0D01*
G01X361653Y86844D02*
G03X361372Y88306I-3937J1D01*
G01X362834Y86844D02*
G03X362468Y88745I-5118J0D01*
G01X352953Y77776D02*
X346949Y75361D01*
G01X353051Y78041D02*
X347008Y75610D01*
G01X362834Y86844D02*
Y84452D01*
G01X361653D02*
Y86844D01*
G01X360886Y93110D02*
Y90748D01*
G01Y96181D02*
Y95472D01*
G01X360472Y98035D02*
Y99216D01*
G01X359960D02*
Y98035D01*
G01X359488Y99216D02*
Y98035D01*
G01X359448D02*
Y99216D01*
G01X359291Y88742D02*
Y97067D01*
G01X359029Y99216D02*
Y98035D01*
G01X358596D02*
Y99216D01*
G01Y97736D02*
Y97110D01*
G01X358405Y93130D02*
Y97067D01*
G01X358346Y98035D02*
Y99216D01*
G01X358245Y98877D02*
Y97823D01*
G01X356043Y97067D02*
Y93130D01*
G01X354724Y96372D02*
Y96998D01*
G01X354330Y97576D02*
Y96950D01*
G01X354134Y85421D02*
Y81173D01*
G01X354111Y97110D02*
Y97736D01*
G01X353937Y95704D02*
Y96330D01*
G01Y87421D02*
Y85650D01*
G01Y99216D02*
Y97410D01*
G01X353149Y98035D02*
Y99216D01*
G01Y87312D02*
Y85737D01*
G01X353051Y85848D02*
Y87044D01*
G01Y78041D02*
Y79193D01*
G01Y70172D02*
Y71380D01*
G01X352756Y99216D02*
Y98035D01*
G01X352559Y85421D02*
Y75668D01*
G01X352165Y75921D02*
Y90177D01*
G01X351971Y74247D02*
Y71598D01*
G01Y79255D02*
Y75785D01*
G01Y82620D02*
Y80793D01*
G01Y87341D02*
Y86211D01*
G01X351121Y73946D02*
Y71598D01*
G01Y76961D02*
Y75785D01*
G01Y79255D02*
Y78079D01*
G01X351003Y79972D02*
Y80076D01*
G01Y76957D02*
Y77061D01*
G01Y73942D02*
Y74046D01*
G01Y69755D02*
Y69859D01*
G01Y70881D02*
Y70777D01*
G01Y75068D02*
Y74964D01*
G01Y78083D02*
Y77978D01*
G01Y83442D02*
Y83337D01*
G01X350766Y82320D02*
Y81094D01*
G01X350731Y70777D02*
Y70881D01*
G01X350648Y82316D02*
Y82420D01*
G01Y81098D02*
Y80993D01*
G01X350471Y69859D02*
Y69755D01*
G01Y74046D02*
Y73942D01*
G01X350353Y73946D02*
Y71999D01*
G01X350197Y97067D02*
Y90177D01*
G01X349803Y97067D02*
Y90177D01*
G01X349762Y70060D02*
Y68573D01*
G01Y73946D02*
Y71999D01*
G01X349644Y73942D02*
Y74046D01*
G01Y68577D02*
Y68473D01*
G01X349467Y80993D02*
Y81098D01*
G01Y82420D02*
Y82316D01*
G01X349349Y82320D02*
Y81094D01*
G01X349123Y86527D02*
Y86422D01*
G01X349113Y83337D02*
Y83442D01*
G01Y74964D02*
Y75068D01*
G01Y68473D02*
Y68577D01*
G01Y74046D02*
Y73942D01*
G01Y80076D02*
Y79972D01*
G01X348995Y70881D02*
Y68573D01*
G01Y73946D02*
Y71598D01*
G01Y86427D02*
Y84159D01*
G01X348658Y87482D02*
Y87587D01*
G01X348144Y74247D02*
Y71598D01*
G01Y78083D02*
Y76957D01*
G01Y82620D02*
Y80793D01*
G01Y87188D02*
Y84159D01*
G01X347795Y90177D02*
Y87618D01*
G01X347244Y98035D02*
Y99216D01*
G01X346949Y75361D02*
Y74116D01*
G01Y85257D02*
Y84006D01*
G01X346850Y83780D02*
Y85354D01*
G01Y73937D02*
Y75512D01*
G01Y99216D02*
Y98035D01*
G01X346063Y83780D02*
Y85354D01*
G01Y73937D02*
Y75512D01*
G01Y96330D02*
Y95704D01*
G01Y99216D02*
Y97410D01*
G01X346023Y75610D02*
Y73839D01*
G01Y85453D02*
Y83681D01*
G01X345889Y97736D02*
Y97110D01*
G01X345669Y97576D02*
Y96950D01*
G01X345275Y96372D02*
Y96998D01*
G01X343956Y93130D02*
Y97067D01*
G01X342677D02*
Y96181D01*
G01X341755Y97751D02*
Y98762D01*
G01X341653Y99216D02*
Y98035D01*
G01X341594Y97067D02*
Y93130D01*
G01X341403Y97110D02*
Y97736D01*
G01Y99216D02*
Y98035D01*
G01X340971D02*
Y99216D01*
G01X340708Y88742D02*
Y97067D01*
G01X340551Y98035D02*
Y99216D01*
G01X340512D02*
Y98035D01*
G01X352559Y85421D02*
X352165Y87029D01*
G01X362468Y88745D02*
X361260Y91767D01*
G01X360886Y89521D02*
X361372Y88306D01*
G01X359882Y87606D02*
X359291Y88742D01*
G01X361456Y80751D02*
X362047Y79728D01*
G01X359882Y93156D02*
X359291Y94101D01*
G01X354111Y97736D02*
X358596D01*
G01X341403D02*
X345889D01*
G01X361260Y97244D02*
X360078D01*
G01Y97165D02*
X360866D01*
G01X345889Y97110D02*
X341403D01*
G01X358596D02*
X354111D01*
G01X359882Y97067D02*
X350197D01*
G01X360078Y96539D02*
X360866D01*
G01X360078Y96358D02*
X361260D01*
G01X353937Y96330D02*
X346063D01*
G01X360472Y96319D02*
X360866D01*
G01X360078Y96287D02*
X361260D01*
G01X360078Y96260D02*
X361260D01*
G01Y96227D02*
X360078D01*
G01X359291Y96181D02*
X360886D01*
G01X349803D02*
X350197D01*
G01X361456Y95913D02*
X362638D01*
G01X353937Y95704D02*
X346063D01*
G01X361260Y95544D02*
X360078D01*
G01X361260Y95472D02*
X360078D01*
G01X350197Y95216D02*
X359291D01*
G01X340708Y94709D02*
X349803D01*
G01X360078Y94598D02*
X361260D01*
G01X362638Y94098D02*
X361456D01*
G01X362638Y93311D02*
X361456D01*
G01X356043Y93130D02*
X358405D01*
G01X341594D02*
X343956D01*
G01X361260Y93110D02*
X360078D01*
G01X353051Y85848D02*
X347008Y85453D01*
G01X352953Y85650D02*
X346949Y85257D01*
G01X350197Y90177D02*
X352953Y87421D01*
G01X349803Y90292D02*
X353051Y87044D01*
G01X346949Y84006D02*
X352953Y79547D01*
G01X347008Y83681D02*
X353051Y79193D01*
G01X352559Y75668D02*
X352165Y75921D01*
G01X348658Y87587D02*
X351971Y87341D01*
G01Y87237D02*
X348658Y87482D01*
G01X351971Y86315D02*
X349114Y86527D01*
G01Y86423D02*
X351971Y86211D01*
G01X362638Y91573D02*
X361850D01*
G01X361260Y90748D02*
X360078D01*
G01X350197Y90177D02*
X352165D01*
G01X349803D02*
X347795D01*
G01X361260Y89261D02*
X360078D01*
G01X361260Y88386D02*
X360078D01*
G01Y88315D02*
X361260D01*
G01X360078Y87631D02*
X361260D01*
G01Y87571D02*
X360078D01*
G01Y87500D02*
X361260D01*
G01X353937Y87421D02*
X352953D01*
G01X353937Y87312D02*
X353149D01*
G01X353937Y87294D02*
X353149D01*
G01Y87017D02*
X353937D01*
G01X360886Y86917D02*
X361260D01*
G01Y86235D02*
X360886D01*
G01X353149Y86032D02*
X353937D01*
G01X353149Y85755D02*
X353937D01*
G01Y85737D02*
X353149D01*
G01X353937Y85650D02*
X352953D01*
G01X347008Y85453D02*
X346023D01*
G01X352559Y85421D02*
X354134D01*
G01X346850Y85354D02*
X346063D01*
G01X346850Y85336D02*
X346063D01*
G01Y85059D02*
X346850D01*
G01X362834Y84452D02*
X361653D01*
G01X361260D02*
X360886D01*
G01X348995Y84263D02*
X348144D01*
G01X362638Y84256D02*
X361456D01*
G01X348995Y84159D02*
X348144D01*
G01X346063Y84075D02*
X346850D01*
G01X361260Y83862D02*
X360886D01*
G01X362638D02*
X361456D01*
G01X346063Y83798D02*
X346850D01*
G01Y83780D02*
X346063D01*
G01X353937Y83689D02*
X353149D01*
G01X347008Y83681D02*
X346023D01*
G01X361456Y83468D02*
X362638D01*
G01X349113Y83442D02*
X351003D01*
G01X349113Y83337D02*
X351003D01*
G01X361260Y82484D02*
X360886D01*
G01X349467Y82420D02*
X350648D01*
G01X349467Y82316D02*
X350648D01*
G01X361260Y82287D02*
X360886D01*
G01X361260Y82062D02*
X360886D01*
G01X354134Y81911D02*
X359882D01*
G01X362638Y81697D02*
X361456D01*
G01X361260Y81500D02*
X360886D01*
G01X354134Y81173D02*
X359882D01*
G01X350648Y81098D02*
X349467D01*
G01X350648Y80993D02*
X349467D01*
G01X351003Y80076D02*
X349113D01*
G01X351003Y79972D02*
X349113D01*
G01X362638Y79728D02*
X362047D01*
G01X361456Y79724D02*
X361260D01*
G01X353937Y79547D02*
X352953D01*
G01X353937Y79438D02*
X353149D01*
G01X353937Y79420D02*
X353149D01*
G01X351121Y79255D02*
X351971D01*
G01X351121Y79150D02*
X351971D01*
G01X353149Y79143D02*
X353937D01*
G01X353149Y78158D02*
X353937D01*
G01X348144Y78083D02*
X351003D01*
G01X348144Y77978D02*
X351003D01*
G01X354134Y77975D02*
X359882D01*
G01X353149Y77881D02*
X353937D01*
G01Y77863D02*
X353149D01*
G01X353937Y77776D02*
X352953D01*
G01X351003Y77061D02*
X348144D01*
G01X351003Y76957D02*
X348144D01*
G01X354134Y76554D02*
X352165D01*
G01X359882Y76410D02*
X354134D01*
G01X351971Y75889D02*
X351121D01*
G01X351971Y75785D02*
X351121D01*
G01X354134Y75668D02*
X352559D01*
G01X347008Y75610D02*
X346023D01*
G01X346850Y75512D02*
X346063D01*
G01X346850Y75494D02*
X346063D01*
G01Y75217D02*
X346850D01*
G01X361260Y75118D02*
X360886D01*
G01X349113Y75068D02*
X351003D01*
G01X349113Y74964D02*
X351003D01*
G01X353937Y74887D02*
X353149D01*
G01Y74443D02*
X353937D01*
G01X346063Y74232D02*
X346850D01*
G01X351003Y74046D02*
X350471D01*
G01X349644D02*
X349113D01*
G01X346063Y73955D02*
X346850D01*
G01X349644Y73942D02*
X349113D01*
G01X351003D02*
X350471D01*
G01X346850Y73937D02*
X346063D01*
G01X347008Y73839D02*
X346023D01*
G01X360886Y73649D02*
X361260D01*
G01X354134Y73644D02*
X359882D01*
G01X346850Y73522D02*
X346063D01*
G01X361260Y72967D02*
X360886D01*
G01X354134Y72380D02*
X359882D01*
G01X350353Y72103D02*
X349762D01*
G01X350353Y71999D02*
X349762D01*
G01X348995Y71702D02*
X348144D01*
G01X351971D02*
X351121D01*
G01X353937Y71673D02*
X352953D01*
G01X348995Y71598D02*
X348144D01*
G01X351971D02*
X351121D01*
G01X353937Y71564D02*
X353149D01*
G01X353937Y71546D02*
X353149D01*
G01Y71269D02*
X353937D01*
G01X350731Y70881D02*
X351003D01*
G01X348144D02*
X348995D01*
G01X350731Y70777D02*
X351003D01*
G01X348144D02*
X348995D01*
G01X353149Y70284D02*
X353937D01*
G01X353149Y70007D02*
X353937D01*
G01Y69989D02*
X353149D01*
G01X353937Y69902D02*
X352953D01*
G01X351003Y69859D02*
X350471D01*
G01X351003Y69755D02*
X350471D01*
G01X346850Y69519D02*
X346063D01*
G01Y68821D02*
X346850D01*
G01X349113Y68577D02*
X349644D01*
G01X349113Y68473D02*
X349644D01*
G01X352953Y71673D02*
X346949Y74116D01*
G01X353051Y71380D02*
X347008Y73839D01*
G01X371063Y740157D02*
G03X357283I-6890J0D01*
G01D02*
G03X371063I6890J0D01*
G01X403756Y763780D02*
G03X400235Y758082I0J-3937D01*
G01X414895Y728762D02*
X400235Y758082D01*
G01X389671Y761603D02*
G03X386149Y763780I-3522J-1760D01*
G01X407852Y725241D02*
X389671Y761603D01*
G01X403756Y763780D02*
X428096D01*
G01X377986Y1340060D02*
Y1321123D01*
G01X415824Y121385D02*
X415853Y121021D01*
G01X415740Y121735D02*
X415824Y121385D01*
G01X415607Y122056D02*
X415740Y121735D01*
G01X415435Y122334D02*
X415607Y122056D01*
G01X415233Y122562D02*
X415435Y122334D01*
G01X415015Y122736D02*
X415233Y122562D01*
G01X422910Y121385D02*
X422939Y121021D01*
G01X422827Y121735D02*
X422910Y121385D01*
G01X422694Y122056D02*
X422827Y121735D01*
G01X422521Y122334D02*
X422694Y122056D01*
G01X422320Y122562D02*
X422521Y122334D01*
G01X422102Y122736D02*
X422320Y122562D01*
G01X429997Y121385D02*
X430026Y121021D01*
G01X429913Y121735D02*
X429997Y121385D01*
G01X429781Y122056D02*
X429913Y121735D01*
G01X429608Y122334D02*
X429781Y122056D01*
G01X429406Y122562D02*
X429608Y122334D01*
G01X429188Y122736D02*
X429406Y122562D01*
G01X437083Y121385D02*
X437112Y121021D01*
G01X437000Y121735D02*
X437083Y121385D01*
G01X436867Y122056D02*
X437000Y121735D01*
G01X436694Y122334D02*
X436867Y122056D01*
G01X436493Y122562D02*
X436694Y122334D01*
G01X436275Y122736D02*
X436493Y122562D01*
G01X444170Y121385D02*
X444199Y121021D01*
G01X444086Y121735D02*
X444170Y121385D01*
G01X443954Y122056D02*
X444086Y121735D01*
G01X443781Y122334D02*
X443954Y122056D01*
G01X443580Y122562D02*
X443781Y122334D01*
G01X443361Y122736D02*
X443580Y122562D01*
G01X451257Y121385D02*
X451286Y121021D01*
G01X451173Y121735D02*
X451257Y121385D01*
G01X451041Y122056D02*
X451173Y121735D01*
G01X450868Y122334D02*
X451041Y122056D01*
G01X450666Y122562D02*
X450868Y122334D01*
G01X450448Y122736D02*
X450666Y122562D01*
G01X458343Y121385D02*
X458372Y121021D01*
G01X458260Y121735D02*
X458343Y121385D01*
G01X458127Y122056D02*
X458260Y121735D01*
G01X457954Y122334D02*
X458127Y122056D01*
G01X457753Y122562D02*
X457954Y122334D01*
G01X457535Y122736D02*
X457753Y122562D01*
G01X465430Y121385D02*
X465459Y121021D01*
G01X465346Y121735D02*
X465430Y121385D01*
G01X465214Y122056D02*
X465346Y121735D01*
G01X465041Y122334D02*
X465214Y122056D01*
G01X464840Y122562D02*
X465041Y122334D01*
G01X464621Y122736D02*
X464840Y122562D01*
G01X415381Y122514D02*
X415015Y122736D01*
G01X415643Y122234D02*
X415381Y122514D01*
G01X415800Y121920D02*
X415643Y122234D01*
G01X415853Y121593D02*
X415800Y121920D01*
G01X422467Y122514D02*
X422102Y122736D01*
G01X422730Y122234D02*
X422467Y122514D01*
G01X422886Y121920D02*
X422730Y122234D01*
G01X422939Y121593D02*
X422886Y121920D01*
G01X429554Y122514D02*
X429188Y122736D01*
G01X429816Y122234D02*
X429554Y122514D01*
G01X429973Y121920D02*
X429816Y122234D01*
G01X430026Y121593D02*
X429973Y121920D01*
G01X436641Y122514D02*
X436275Y122736D01*
G01X436903Y122234D02*
X436641Y122514D01*
G01X437060Y121920D02*
X436903Y122234D01*
G01X437112Y121593D02*
X437060Y121920D01*
G01X443727Y122514D02*
X443361Y122736D01*
G01X443990Y122234D02*
X443727Y122514D01*
G01X444146Y121920D02*
X443990Y122234D01*
G01X444199Y121593D02*
X444146Y121920D01*
G01X450814Y122514D02*
X450448Y122736D01*
G01X451076Y122234D02*
X450814Y122514D01*
G01X451233Y121920D02*
X451076Y122234D01*
G01X451286Y121593D02*
X451233Y121920D01*
G01X457900Y122514D02*
X457535Y122736D01*
G01X458163Y122234D02*
X457900Y122514D01*
G01X458319Y121920D02*
X458163Y122234D01*
G01X458372Y121593D02*
X458319Y121920D01*
G01X464987Y122514D02*
X464621Y122736D01*
G01X465249Y122234D02*
X464987Y122514D01*
G01X465406Y121920D02*
X465249Y122234D01*
G01X465459Y121593D02*
X465406Y121920D01*
G01X420428Y122562D02*
X420647Y122736D01*
G01X420227Y122334D02*
X420428Y122562D01*
G01X420054Y122056D02*
X420227Y122334D01*
G01X419922Y121735D02*
X420054Y122056D01*
G01X419838Y121385D02*
X419922Y121735D01*
G01X419809Y121021D02*
X419838Y121385D01*
G01X427515Y122562D02*
X427733Y122736D01*
G01X427314Y122334D02*
X427515Y122562D01*
G01X427141Y122056D02*
X427314Y122334D01*
G01X427008Y121735D02*
X427141Y122056D01*
G01X426925Y121385D02*
X427008Y121735D01*
G01X426896Y121021D02*
X426925Y121385D01*
G01X434602Y122562D02*
X434820Y122736D01*
G01X434400Y122334D02*
X434602Y122562D01*
G01X434227Y122056D02*
X434400Y122334D01*
G01X434095Y121735D02*
X434227Y122056D01*
G01X434011Y121385D02*
X434095Y121735D01*
G01X433982Y121021D02*
X434011Y121385D01*
G01X441688Y122562D02*
X441907Y122736D01*
G01X441487Y122334D02*
X441688Y122562D01*
G01X441314Y122056D02*
X441487Y122334D01*
G01X441182Y121735D02*
X441314Y122056D01*
G01X441098Y121385D02*
X441182Y121735D01*
G01X441069Y121021D02*
X441098Y121385D01*
G01X448775Y122562D02*
X448993Y122736D01*
G01X448574Y122334D02*
X448775Y122562D01*
G01X448401Y122056D02*
X448574Y122334D01*
G01X448268Y121735D02*
X448401Y122056D01*
G01X448185Y121385D02*
X448268Y121735D01*
G01X448156Y121021D02*
X448185Y121385D01*
G01X455862Y122562D02*
X456080Y122736D01*
G01X455660Y122334D02*
X455862Y122562D01*
G01X455487Y122056D02*
X455660Y122334D01*
G01X455355Y121735D02*
X455487Y122056D01*
G01X455271Y121385D02*
X455355Y121735D01*
G01X455242Y121021D02*
X455271Y121385D01*
G01X462948Y122562D02*
X463166Y122736D01*
G01X462747Y122334D02*
X462948Y122562D01*
G01X462574Y122056D02*
X462747Y122334D01*
G01X462441Y121735D02*
X462574Y122056D01*
G01X462358Y121385D02*
X462441Y121735D01*
G01X462329Y121021D02*
X462358Y121385D01*
G01X470035Y122562D02*
X470253Y122736D01*
G01X469833Y122334D02*
X470035Y122562D01*
G01X469661Y122056D02*
X469833Y122334D01*
G01X469528Y121735D02*
X469661Y122056D01*
G01X469444Y121385D02*
X469528Y121735D01*
G01X469415Y121021D02*
X469444Y121385D01*
G01X420185Y122429D02*
X420647Y122736D01*
G01X419903Y122029D02*
X420185Y122429D01*
G01X419809Y121593D02*
X419903Y122029D01*
G01X427271Y122429D02*
X427733Y122736D01*
G01X426990Y122029D02*
X427271Y122429D01*
G01X426896Y121593D02*
X426990Y122029D01*
G01X434358Y122429D02*
X434820Y122736D01*
G01X434077Y122029D02*
X434358Y122429D01*
G01X433982Y121593D02*
X434077Y122029D01*
G01X441445Y122429D02*
X441907Y122736D01*
G01X441163Y122029D02*
X441445Y122429D01*
G01X441069Y121593D02*
X441163Y122029D01*
G01X448531Y122429D02*
X448993Y122736D01*
G01X448250Y122029D02*
X448531Y122429D01*
G01X448156Y121593D02*
X448250Y122029D01*
G01X455618Y122429D02*
X456080Y122736D01*
G01X455336Y122029D02*
X455618Y122429D01*
G01X455242Y121593D02*
X455336Y122029D01*
G01X462704Y122429D02*
X463166Y122736D01*
G01X462423Y122029D02*
X462704Y122429D01*
G01X462329Y121593D02*
X462423Y122029D01*
G01X469791Y122429D02*
X470253Y122736D01*
G01X469510Y122029D02*
X469791Y122429D01*
G01X469415Y121593D02*
X469510Y122029D01*
G01X471968Y131496D02*
G03I-708J0D01*
G01X464882Y130709D02*
G03I-709J0D01*
G01Y126378D02*
G03I-709J0D01*
G01X471968Y125984D02*
G03I-708J0D01*
G01Y121654D02*
G03I-708J0D01*
G01X464626Y122745D02*
G03X463162I-732J-1394D01*
G01X471712D02*
G03X470248I-732J-1394D01*
G01X457795Y131496D02*
G03I-709J0D01*
G01X450708Y130709D02*
G03I-708J0D01*
G01Y126378D02*
G03I-708J0D01*
G01X457795Y125984D02*
G03I-709J0D01*
G01Y121654D02*
G03I-709J0D01*
G01X450453Y122745D02*
G03X448989I-732J-1394D01*
G01X457539D02*
G03X456075I-732J-1394D01*
G01X443622Y131496D02*
G03I-709J0D01*
G01X436535Y130709D02*
G03I-708J0D01*
G01Y126378D02*
G03I-708J0D01*
G01X443622Y125984D02*
G03I-709J0D01*
G01Y121654D02*
G03I-709J0D01*
G01X443366Y122745D02*
G03X441902I-732J-1394D01*
G01X429449Y131496D02*
G03I-709J0D01*
G01Y125984D02*
G03I-709J0D01*
G01Y121654D02*
G03I-709J0D01*
G01X429193Y122745D02*
G03X427729I-732J-1394D01*
G01X436279D02*
G03X434815I-732J-1394D01*
G01X422362Y130709D02*
G03I-709J0D01*
G01Y126378D02*
G03I-709J0D01*
G01X415020Y122745D02*
G03X414288Y122925I-731J-1394D01*
G01X422106Y122745D02*
G03X420642I-732J-1394D01*
G01X472516Y115256D02*
X471335Y114075D01*
G01X422910Y115256D02*
X421728Y114075D01*
G01X469445Y118012D02*
Y115256D01*
G01X469415Y121593D02*
Y115650D01*
G01X465459Y121593D02*
Y115650D01*
G01X462329Y121593D02*
Y115650D01*
G01X458372Y121593D02*
Y115650D01*
G01X455242Y121593D02*
Y115650D01*
G01X451286Y121593D02*
Y115650D01*
G01X448156Y121593D02*
Y115650D01*
G01X444199Y121593D02*
Y115650D01*
G01X441069Y121593D02*
Y115650D01*
G01X437112Y121593D02*
Y115650D01*
G01X433982Y121593D02*
Y115650D01*
G01X430026Y121593D02*
Y115650D01*
G01X426896Y121593D02*
Y115650D01*
G01X422939Y121593D02*
Y115650D01*
G01X422910Y115256D02*
Y118012D01*
G01X419839D02*
Y115256D01*
G01X419809Y121593D02*
Y115650D01*
G01X417818Y201804D02*
Y113091D01*
G01X415853Y121593D02*
Y115650D01*
G01X414288Y122916D02*
Y138996D01*
G01Y115650D02*
Y118012D01*
G01X469445Y115256D02*
X470626Y114075D01*
G01X419839Y115256D02*
X421020Y114075D01*
G01X473956Y126536D02*
X417818D01*
G01X420647Y122736D02*
X415015D01*
G01X427733D02*
X422102D01*
G01X434820D02*
X429188D01*
G01X441907D02*
X436275D01*
G01X448993D02*
X443361D01*
G01X456080D02*
X450448D01*
G01X463166D02*
X457535D01*
G01X470253D02*
X464621D01*
G01X473956Y120492D02*
X417818D01*
G01X473956Y120020D02*
X417818D01*
G01X559016Y118012D02*
X414288D01*
G01X473956Y116437D02*
X417818D01*
G01X559016Y115650D02*
X414288D01*
G01X422910Y115256D02*
X419839D01*
G01X472516D02*
X469445D01*
G01X421728Y114075D02*
X421020D01*
G01X471335D02*
X470626D01*
G01X473956Y113091D02*
X417818D01*
G01X416142Y200787D02*
G03X420079Y196850I3937J0D01*
G01X556299D02*
X420079D01*
G01X408268Y188976D02*
Y723480D01*
G01Y188976D02*
G03X412205I1968J0D01*
G01X564173D02*
X412205D01*
G01X422694Y190749D02*
X422678Y190748D01*
G01X422710Y190751D02*
X422694Y190749D01*
G01X422726Y190755D02*
X422710Y190751D01*
G01X432323Y190836D02*
X432295Y190882D01*
G01X432356Y190797D02*
X432323Y190836D01*
G01X432396Y190770D02*
X432356Y190797D01*
G01X432441Y190753D02*
X432396Y190770D01*
G01X432486Y190748D02*
X432441Y190753D01*
G01X446496Y190836D02*
X446468Y190882D01*
G01X446529Y190797D02*
X446496Y190836D01*
G01X446570Y190770D02*
X446529Y190797D01*
G01X446615Y190753D02*
X446570Y190770D01*
G01X446660Y190748D02*
X446615Y190753D01*
G01X460669Y190836D02*
X460641Y190882D01*
G01X460702Y190797D02*
X460669Y190836D01*
G01X460743Y190770D02*
X460702Y190797D01*
G01X460788Y190753D02*
X460743Y190770D01*
G01X460833Y190748D02*
X460788Y190753D01*
G01X424868Y196164D02*
X424811Y196457D01*
G01X425040Y195905D02*
X424868Y196164D01*
G01X425303Y195730D02*
X425040Y195905D01*
G01X425611Y195669D02*
X425303Y195730D01*
G01X439042Y196164D02*
X438984Y196457D01*
G01X439213Y195905D02*
X439042Y196164D01*
G01X439477Y195730D02*
X439213Y195905D01*
G01X439784Y195669D02*
X439477Y195730D01*
G01X453215Y196164D02*
X453157Y196457D01*
G01X453386Y195905D02*
X453215Y196164D01*
G01X453650Y195730D02*
X453386Y195905D01*
G01X453957Y195669D02*
X453650Y195730D01*
G01X467388Y196164D02*
X467331Y196457D01*
G01X467560Y195905D02*
X467388Y196164D01*
G01X467823Y195730D02*
X467560Y195905D01*
G01X468130Y195669D02*
X467823Y195730D01*
G01X425252Y196264D02*
X425199Y196457D01*
G01X425402Y196117D02*
X425252Y196264D01*
G01X425611Y196063D02*
X425402Y196117D01*
G01X439425Y196264D02*
X439372Y196457D01*
G01X439575Y196117D02*
X439425Y196264D01*
G01X439784Y196063D02*
X439575Y196117D01*
G01X453598Y196264D02*
X453545Y196457D01*
G01X453748Y196117D02*
X453598Y196264D01*
G01X453957Y196063D02*
X453748Y196117D01*
G01X467772Y196264D02*
X467718Y196457D01*
G01X467922Y196117D02*
X467772Y196264D01*
G01X468130Y196063D02*
X467922Y196117D01*
G01X469080Y190749D02*
X469095Y190748D01*
G01X469064Y190751D02*
X469080Y190749D01*
G01X469048Y190755D02*
X469064Y190751D01*
G01X419473Y190749D02*
X419489Y190748D01*
G01X419457Y190751D02*
X419473Y190749D01*
G01X419442Y190755D02*
X419457Y190751D01*
G01X469008Y190761D02*
X469048Y190755D01*
G01X468967Y190776D02*
X469008Y190761D01*
G01X468930Y190800D02*
X468967Y190776D01*
G01X468899Y190833D02*
X468930Y190800D01*
G01X419401Y190761D02*
X419442Y190755D01*
G01X419361Y190776D02*
X419401Y190761D01*
G01X419324Y190800D02*
X419361Y190776D01*
G01X419292Y190833D02*
X419324Y190800D01*
G01X425574Y196270D02*
X425654Y196260D01*
G01X425498Y196288D02*
X425574Y196270D01*
G01X425429Y196312D02*
X425498Y196288D01*
G01X425369Y196343D02*
X425429Y196312D01*
G01X425321Y196378D02*
X425369Y196343D01*
G01X425286Y196417D02*
X425321Y196378D01*
G01X425266Y196457D02*
X425286Y196417D01*
G01X425649Y197005D02*
X425729Y196994D01*
G01X425573Y197022D02*
X425649Y197005D01*
G01X425504Y197047D02*
X425573Y197022D01*
G01X425444Y197078D02*
X425504Y197047D01*
G01X425395Y197113D02*
X425444Y197078D01*
G01X425361Y197151D02*
X425395Y197113D01*
G01X425341Y197191D02*
X425361Y197151D01*
G01X439747Y196270D02*
X439827Y196260D01*
G01X439672Y196288D02*
X439747Y196270D01*
G01X439602Y196312D02*
X439672Y196288D01*
G01X439542Y196343D02*
X439602Y196312D01*
G01X439494Y196378D02*
X439542Y196343D01*
G01X439459Y196417D02*
X439494Y196378D01*
G01X439439Y196457D02*
X439459Y196417D01*
G01X439822Y197005D02*
X439902Y196994D01*
G01X439746Y197022D02*
X439822Y197005D01*
G01X439677Y197047D02*
X439746Y197022D01*
G01X439617Y197078D02*
X439677Y197047D01*
G01X439569Y197113D02*
X439617Y197078D01*
G01X439534Y197151D02*
X439569Y197113D01*
G01X439514Y197191D02*
X439534Y197151D01*
G01X453920Y196270D02*
X454000Y196260D01*
G01X453845Y196288D02*
X453920Y196270D01*
G01X453776Y196312D02*
X453845Y196288D01*
G01X453715Y196343D02*
X453776Y196312D01*
G01X453667Y196378D02*
X453715Y196343D01*
G01X453632Y196417D02*
X453667Y196378D01*
G01X453612Y196457D02*
X453632Y196417D01*
G01X453995Y197005D02*
X454075Y196994D01*
G01X453920Y197022D02*
X453995Y197005D01*
G01X453850Y197047D02*
X453920Y197022D01*
G01X453790Y197078D02*
X453850Y197047D01*
G01X453742Y197113D02*
X453790Y197078D01*
G01X453707Y197151D02*
X453742Y197113D01*
G01X453687Y197191D02*
X453707Y197151D01*
G01X468094Y196270D02*
X468173Y196260D01*
G01X468018Y196288D02*
X468094Y196270D01*
G01X467949Y196312D02*
X468018Y196288D01*
G01X467889Y196343D02*
X467949Y196312D01*
G01X467840Y196378D02*
X467889Y196343D01*
G01X467805Y196417D02*
X467840Y196378D01*
G01X467786Y196457D02*
X467805Y196417D01*
G01X468168Y197005D02*
X468248Y196994D01*
G01X468093Y197022D02*
X468168Y197005D01*
G01X468024Y197047D02*
X468093Y197022D01*
G01X467963Y197078D02*
X468024Y197047D01*
G01X467915Y197113D02*
X467963Y197078D01*
G01X467880Y197151D02*
X467915Y197113D01*
G01X467860Y197191D02*
X467880Y197151D01*
G01X426501Y190764D02*
X426576Y190748D01*
G01X426436Y190806D02*
X426501Y190764D01*
G01X426394Y190871D02*
X426436Y190806D01*
G01X426379Y190945D02*
X426394Y190871D01*
G01X433587Y190764D02*
X433662Y190748D01*
G01X433523Y190806D02*
X433587Y190764D01*
G01X433481Y190871D02*
X433523Y190806D01*
G01X433465Y190945D02*
X433481Y190871D01*
G01X440674Y190764D02*
X440749Y190748D01*
G01X440610Y190806D02*
X440674Y190764D01*
G01X440567Y190871D02*
X440610Y190806D01*
G01X440552Y190945D02*
X440567Y190871D01*
G01X447761Y190764D02*
X447836Y190748D01*
G01X447696Y190806D02*
X447761Y190764D01*
G01X447654Y190871D02*
X447696Y190806D01*
G01X447639Y190945D02*
X447654Y190871D01*
G01X454847Y190764D02*
X454922Y190748D01*
G01X454783Y190806D02*
X454847Y190764D01*
G01X454741Y190871D02*
X454783Y190806D01*
G01X454725Y190945D02*
X454741Y190871D01*
G01X461934Y190764D02*
X462009Y190748D01*
G01X461869Y190806D02*
X461934Y190764D01*
G01X461827Y190871D02*
X461869Y190806D01*
G01X461812Y190945D02*
X461827Y190871D01*
G01X425567Y196073D02*
X425654Y196063D01*
G01X425485Y196102D02*
X425567Y196073D01*
G01X425412Y196149D02*
X425485Y196102D01*
G01X425350Y196212D02*
X425412Y196149D01*
G01X425304Y196287D02*
X425350Y196212D01*
G01X425276Y196369D02*
X425304Y196287D01*
G01X425266Y196457D02*
X425276Y196369D01*
G01X439740Y196073D02*
X439827Y196063D01*
G01X439658Y196102D02*
X439740Y196073D01*
G01X439585Y196149D02*
X439658Y196102D01*
G01X439523Y196212D02*
X439585Y196149D01*
G01X439477Y196287D02*
X439523Y196212D01*
G01X439449Y196369D02*
X439477Y196287D01*
G01X439439Y196457D02*
X439449Y196369D01*
G01X424581Y201043D02*
Y196457D01*
G01X438755Y201043D02*
X438754Y196457D01*
G01X452928Y201043D02*
X452927Y196457D01*
G01X429840Y190764D02*
X429765Y190748D01*
G01X429904Y190806D02*
X429840Y190764D01*
G01X429947Y190871D02*
X429904Y190806D01*
G01X429962Y190945D02*
X429947Y190871D01*
G01X453913Y196073D02*
X454000Y196063D01*
G01X453831Y196102D02*
X453913Y196073D01*
G01X453758Y196149D02*
X453831Y196102D01*
G01X453696Y196212D02*
X453758Y196149D01*
G01X453651Y196287D02*
X453696Y196212D01*
G01X453622Y196369D02*
X453651Y196287D01*
G01X453612Y196457D02*
X453622Y196369D01*
G01X468086Y196073D02*
X468173Y196063D01*
G01X468005Y196102D02*
X468086Y196073D01*
G01X467932Y196149D02*
X468005Y196102D01*
G01X467870Y196212D02*
X467932Y196149D01*
G01X467824Y196287D02*
X467870Y196212D01*
G01X467795Y196369D02*
X467824Y196287D01*
G01X467786Y196457D02*
X467795Y196369D01*
G01X467101Y201043D02*
Y196457D01*
G01X436927Y190764D02*
X436851Y190748D01*
G01X436991Y190806D02*
X436927Y190764D01*
G01X437034Y190871D02*
X436991Y190806D01*
G01X437048Y190945D02*
X437034Y190871D01*
G01X444014Y190764D02*
X443938Y190748D01*
G01X444078Y190806D02*
X444014Y190764D01*
G01X444120Y190871D02*
X444078Y190806D01*
G01X444135Y190945D02*
X444120Y190871D01*
G01X451100Y190764D02*
X451025Y190748D01*
G01X451164Y190806D02*
X451100Y190764D01*
G01X451207Y190871D02*
X451164Y190806D01*
G01X451221Y190945D02*
X451207Y190871D01*
G01X458187Y190764D02*
X458111Y190748D01*
G01X458251Y190806D02*
X458187Y190764D01*
G01X458293Y190871D02*
X458251Y190806D01*
G01X458308Y190945D02*
X458293Y190871D01*
G01X465273Y190764D02*
X465198Y190748D01*
G01X465337Y190806D02*
X465273Y190764D01*
G01X465380Y190871D02*
X465337Y190806D01*
G01X465395Y190945D02*
X465380Y190871D01*
G01X436936Y190766D02*
X436851Y190748D01*
G01X436999Y190815D02*
X436936Y190766D01*
G01X437043Y190882D02*
X436999Y190815D01*
G01X451109Y190766D02*
X451025Y190748D01*
G01X451173Y190815D02*
X451109Y190766D01*
G01X451216Y190882D02*
X451173Y190815D01*
G01X465283Y190766D02*
X465198Y190748D01*
G01X465346Y190815D02*
X465283Y190766D01*
G01X465390Y190882D02*
X465346Y190815D01*
G01X422766Y190761D02*
X422725Y190755D01*
G01X422806Y190776D02*
X422766Y190761D01*
G01X422843Y190800D02*
X422806Y190776D01*
G01X422875Y190833D02*
X422843Y190800D01*
G01X467088Y196457D02*
G03X467482Y196063I394J0D01*
G01X462717D02*
G03X462324Y195669I0J-393D01*
G01X464883D02*
G03X464489Y196063I-394J0D01*
G01X469804D02*
G03X469410Y195669I0J-394D01*
G01X464882Y183071D02*
G03I-709J0D01*
G01X466734Y196457D02*
G03X467482Y195709I748J0D01*
G01X471968Y174016D02*
G03I-708J0D01*
G01X469445Y174944D02*
G03Y173164I1299J-890D01*
G01X471968Y168504D02*
G03I-708J0D01*
G01X469445Y167621D02*
G03Y165841I1299J-890D01*
G01X464882Y178740D02*
G03I-709J0D01*
G01Y173228D02*
G03I-709J0D01*
G01Y168898D02*
G03I-709J0D01*
G01X471968Y164173D02*
G03I-708J0D01*
G01X464882Y164567D02*
G03I-709J0D01*
G01Y159055D02*
G03I-709J0D01*
G01X471968Y159843D02*
G03I-708J0D01*
G01X468618Y157126D02*
G03X469603Y156142I984J0D01*
G01X469406Y160650D02*
G03X472555I1574J0D01*
G01X462319D02*
G03X465469I1575J0D01*
G01X471968Y154331D02*
G03I-708J0D01*
G01X464882Y154724D02*
G03I-709J0D01*
G01X471968Y150000D02*
G03I-708J0D01*
G01X464882Y150394D02*
G03I-709J0D01*
G01X471968Y145669D02*
G03I-708J0D01*
G01X464882Y144882D02*
G03I-709J0D01*
G01Y140551D02*
G03I-709J0D01*
G01X471968Y140157D02*
G03I-708J0D01*
G01Y135827D02*
G03I-708J0D01*
G01X464882Y136220D02*
G03I-709J0D01*
G01X472949Y140965D02*
G03I-1969J0D01*
G01X465862D02*
G03I-1968J0D01*
G01X452915Y196457D02*
G03X453309Y196063I394J0D01*
G01X448544D02*
G03X448151Y195669I0J-393D01*
G01X450710D02*
G03X450316Y196063I-394J0D01*
G01X455631D02*
G03X455237Y195669I0J-394D01*
G01X457796D02*
G03X457403Y196063I-394J0D01*
G01X452561Y196457D02*
G03X453309Y195709I748J0D01*
G01X450708Y183071D02*
G03I-708J0D01*
G01Y178740D02*
G03I-708J0D01*
G01X457795Y174016D02*
G03I-709J0D01*
G01X438742Y196457D02*
G03X439135Y196063I394J0D01*
G01X436536Y195669D02*
G03X436143Y196063I-394J0D01*
G01X441458D02*
G03X441064Y195669I0J-394D01*
G01X443623D02*
G03X443229Y196063I-394J0D01*
G01X438387Y196457D02*
G03X439135Y195709I748J0D01*
G01X436535Y183071D02*
G03I-708J0D01*
G01Y178740D02*
G03I-708J0D01*
G01X443622Y174016D02*
G03I-709J0D01*
G01X424568Y196457D02*
G03X424962Y196063I394J0D01*
G01X422363Y195669D02*
G03X421969Y196063I-394J0D01*
G01X420198D02*
G03X419804Y195669I0J-394D01*
G01X434371Y196063D02*
G03X433977Y195669I0J-394D01*
G01X427284Y196063D02*
G03X426891Y195669I0J-393D01*
G01X429450D02*
G03X429056Y196063I-394J0D01*
G01X422362Y178740D02*
G03I-709J0D01*
G01X429449Y174016D02*
G03I-709J0D01*
G01X422362Y183071D02*
G03I-709J0D01*
G01X424214Y196457D02*
G03X424962Y195709I748J0D01*
G01X450708Y173228D02*
G03I-708J0D01*
G01X457795Y168504D02*
G03I-709J0D01*
G01X450708Y168898D02*
G03I-708J0D01*
G01X457795Y164173D02*
G03I-709J0D01*
G01X450708Y164567D02*
G03I-708J0D01*
G01Y159055D02*
G03I-708J0D01*
G01X457795Y159843D02*
G03I-709J0D01*
G01Y154331D02*
G03I-709J0D01*
G01X450708Y154724D02*
G03I-708J0D01*
G01X457795Y150000D02*
G03I-709J0D01*
G01X450708Y150394D02*
G03I-708J0D01*
G01X455232Y160650D02*
G03X458382I1575J0D01*
G01X448146D02*
G03X451295I1574J0D01*
G01X436535Y173228D02*
G03I-708J0D01*
G01X443622Y168504D02*
G03I-709J0D01*
G01X436535Y168898D02*
G03I-708J0D01*
G01X443622Y164173D02*
G03I-709J0D01*
G01X436535Y164567D02*
G03I-708J0D01*
G01Y159055D02*
G03I-708J0D01*
G01X443622Y159843D02*
G03I-709J0D01*
G01Y154331D02*
G03I-709J0D01*
G01X436535Y154724D02*
G03I-708J0D01*
G01X443622Y150000D02*
G03I-709J0D01*
G01X436535Y150394D02*
G03I-708J0D01*
G01X441059Y160650D02*
G03X444209I1575J0D01*
G01X457795Y145669D02*
G03I-709J0D01*
G01X450708Y144882D02*
G03I-708J0D01*
G01Y140551D02*
G03I-708J0D01*
G01X457795Y140157D02*
G03I-709J0D01*
G01Y135827D02*
G03I-709J0D01*
G01X450708Y136220D02*
G03I-708J0D01*
G01X458776Y140965D02*
G03I-1969J0D01*
G01X451689D02*
G03I-1968J0D01*
G01X443622Y145669D02*
G03I-709J0D01*
G01X436535Y144882D02*
G03I-708J0D01*
G01Y140551D02*
G03I-708J0D01*
G01X443622Y140157D02*
G03I-709J0D01*
G01Y135827D02*
G03I-709J0D01*
G01X436535Y136220D02*
G03I-708J0D01*
G01X444603Y140965D02*
G03I-1969J0D01*
G01X429449Y168504D02*
G03I-709J0D01*
G01Y164173D02*
G03I-709J0D01*
G01Y159843D02*
G03I-709J0D01*
G01Y154331D02*
G03I-709J0D01*
G01Y150000D02*
G03I-709J0D01*
G01X433973Y160650D02*
G03X437122I1575J0D01*
G01X426886D02*
G03X430036I1575J0D01*
G01X422362Y173228D02*
G03I-709J0D01*
G01Y168898D02*
G03I-709J0D01*
G01Y164567D02*
G03I-709J0D01*
G01X422910Y165420D02*
G03Y167200I-1300J890D01*
G01Y172743D02*
G03Y174523I-1300J890D01*
G01X419839D02*
G03Y172743I1299J-890D01*
G01Y167200D02*
G03Y165420I1299J-890D01*
G01X422362Y159055D02*
G03I-709J0D01*
G01Y154724D02*
G03I-709J0D01*
G01Y150394D02*
G03I-709J0D01*
G01X422752Y156142D02*
G03X423736Y157126I0J984D01*
G01X419012D02*
G03X419996Y156142I984J0D01*
G01X419799Y160650D02*
G03X422949I1575J0D01*
G01X414288Y159075D02*
G03X415862Y160650I0J1574D01*
G01X429449Y145669D02*
G03I-709J0D01*
G01Y140157D02*
G03I-709J0D01*
G01Y135827D02*
G03I-709J0D01*
G01X437516Y140965D02*
G03I-1969J0D01*
G01X430429D02*
G03I-1968J0D01*
G01X422362Y144882D02*
G03I-709J0D01*
G01Y140551D02*
G03I-709J0D01*
G01Y136220D02*
G03I-709J0D01*
G01X414288Y138996D02*
G03Y142933I0J1968D01*
G01X423343Y140965D02*
G03I-1969J0D01*
G01X465469Y177161D02*
X466847Y179547D01*
G01X458382Y177161D02*
X459760Y179547D01*
G01X451295Y177161D02*
X452673Y179547D01*
G01X444209Y177161D02*
X445587Y179547D01*
G01X437122Y177161D02*
X438500Y179547D01*
G01X422910Y163186D02*
X422122Y161822D01*
G01X430036Y177161D02*
X431414Y179547D01*
G01X422949Y177161D02*
X424327Y179547D01*
G01X417240D02*
X415862Y177161D01*
G01X468173Y196260D02*
X468248Y196994D01*
G01X467860Y197191D02*
X467786Y196457D01*
G01X454000Y196260D02*
X454075Y196994D01*
G01X453687Y197191D02*
X453612Y196457D01*
G01X471337Y196063D02*
Y200939D01*
G01X471140Y226338D02*
Y196063D01*
G01X470998Y226338D02*
Y196063D01*
G01X470610D02*
Y226338D01*
G01X469509Y195906D02*
Y191969D01*
G01X469445Y165841D02*
Y163607D01*
G01Y173164D02*
Y167621D01*
G01Y180551D02*
Y174944D01*
G01X469410Y197191D02*
Y191732D01*
G01X469406Y165902D02*
Y160650D01*
G01Y173224D02*
Y167561D01*
G01Y177161D02*
Y174884D01*
G01X469095Y200623D02*
Y190748D01*
G01X468899Y190833D02*
Y190157D01*
G01X468618Y180551D02*
Y157126D01*
G01X468248Y196994D02*
Y226338D01*
G01X468173Y196260D02*
Y196063D01*
G01X468130D02*
Y195669D01*
G01X469044Y199961D02*
X469048Y190754D01*
G01X439827Y196260D02*
X439902Y196994D01*
G01X439514Y197191D02*
X439439Y196457D01*
G01X425654Y196260D02*
X425729Y196994D01*
G01X425341Y197191D02*
X425266Y196457D01*
G01X457802Y195644D02*
X457803Y196063D01*
G01X443629Y195644D02*
X443630Y196063D01*
G01X429456Y195644D02*
Y196063D01*
G01X467860Y226338D02*
Y197191D01*
G01X467718Y196457D02*
Y226338D01*
G01X467482Y195694D02*
Y200939D01*
G01X467331Y196457D02*
Y226338D01*
G01X466719Y200939D02*
Y196457D01*
G01X465469Y160650D02*
Y177161D01*
G01X465395Y190157D02*
Y201804D01*
G01X465383D02*
X465385Y190882D01*
G01X465198Y201804D02*
Y190748D01*
G01X464883Y195669D02*
Y191732D01*
G01X462324Y195669D02*
Y191732D01*
G01X462319Y177161D02*
Y160650D01*
G01X462009Y201804D02*
Y190748D01*
G01X461812Y201804D02*
Y190157D01*
G01X460833Y190748D02*
Y225787D01*
G01X460647D02*
Y190882D01*
G01X460636D02*
Y190157D01*
G01X458382Y160650D02*
Y177161D01*
G01X458308Y190157D02*
Y201043D01*
G01X458111Y190748D02*
Y200623D01*
G01X457926Y196063D02*
Y200939D01*
G01X457796Y195669D02*
Y191732D01*
G01X457545Y201039D02*
Y196036D01*
G01X457355Y226338D02*
Y196063D01*
G01X457164D02*
Y200939D01*
G01X456967Y226338D02*
Y196063D01*
G01X456825Y226338D02*
Y196063D01*
G01X456437D02*
Y226338D01*
G01X455237Y197191D02*
Y191732D01*
G01X455232Y177161D02*
Y160650D01*
G01X454922Y200623D02*
Y190748D01*
G01X454725Y201043D02*
Y190157D01*
G01X454075Y196994D02*
Y226338D01*
G01X454000Y196260D02*
Y196063D01*
G01X453957D02*
Y195669D01*
G01X453687Y226338D02*
Y197191D01*
G01X453545Y196457D02*
Y226338D01*
G01X453309Y195694D02*
Y200939D01*
G01X453157Y196457D02*
Y226338D01*
G01X452546Y200939D02*
Y196457D01*
G01X451295Y160650D02*
Y177161D01*
G01X451221Y190157D02*
Y201804D01*
G01X451210D02*
X451212Y190882D01*
G01X451025Y201804D02*
Y190748D01*
G01X450710Y195669D02*
Y191732D01*
G01X448151Y195669D02*
Y191732D01*
G01X448146Y177161D02*
Y160650D01*
G01X447836Y201804D02*
Y190748D01*
G01X447639Y201804D02*
Y190157D01*
G01X446660Y190748D02*
Y225787D01*
G01X446473D02*
Y190882D01*
G01X446463D02*
Y190157D01*
G01X444209Y160650D02*
Y177161D01*
G01X444135Y190157D02*
Y201043D01*
G01X443938Y190748D02*
Y200623D01*
G01X443753Y196063D02*
Y200939D01*
G01X443623Y195669D02*
Y191732D01*
G01X443372Y201039D02*
Y196036D01*
G01X443181Y226338D02*
Y196063D01*
G01X442991D02*
Y200939D01*
G01X442794Y226338D02*
Y196063D01*
G01X442652Y226338D02*
Y196063D01*
G01X442264D02*
Y226338D01*
G01X441064Y197191D02*
Y191732D01*
G01X441059Y177161D02*
Y160650D01*
G01X440749Y200623D02*
Y190748D01*
G01X440552Y201043D02*
Y190157D01*
G01X439902Y196994D02*
Y226338D01*
G01X439827Y196260D02*
Y196063D01*
G01X439784D02*
Y195669D01*
G01X439514Y226338D02*
Y197191D01*
G01X439372Y196457D02*
Y226338D01*
G01X439135Y195694D02*
Y200939D01*
G01X438984Y196457D02*
Y226338D01*
G01X438373Y200939D02*
Y196457D01*
G01X437122Y160650D02*
Y177161D01*
G01X437048Y190157D02*
Y201804D01*
G01X437037D02*
X437038Y190882D01*
G01X436851Y201804D02*
Y190748D01*
G01X436536Y195669D02*
Y191732D01*
G01X433977Y195669D02*
Y191732D01*
G01X433973Y177161D02*
Y160650D01*
G01X433662Y201804D02*
Y190748D01*
G01X433465Y201804D02*
Y190157D01*
G01X432486Y190748D02*
Y225787D01*
G01X432300D02*
Y190882D01*
G01X432290D02*
Y190157D01*
G01X430036Y160650D02*
Y177161D01*
G01X429962Y190157D02*
Y201043D01*
G01X429765Y190748D02*
Y200623D01*
G01X429580Y196063D02*
Y200939D01*
G01X429450Y195669D02*
Y191732D01*
G01X429198Y201039D02*
X429199Y196036D01*
G01X429008Y226338D02*
Y196063D01*
G01X428818D02*
Y200939D01*
G01X428620Y226338D02*
Y196063D01*
G01X428478Y226338D02*
Y196063D01*
G01X428091D02*
Y226338D01*
G01X469056Y190157D02*
X469048Y190754D01*
G01X422725Y190755D02*
X422718Y190157D01*
G01X422729Y201804D02*
X422726Y190755D01*
G01X426891Y197191D02*
Y191732D01*
G01X426886Y177161D02*
Y160650D01*
G01X426576Y200623D02*
Y190748D01*
G01X426379Y201043D02*
Y190157D01*
G01X425729Y196994D02*
Y226338D01*
G01X425654Y196260D02*
Y196063D01*
G01X425611D02*
Y195669D01*
G01X425341Y226338D02*
Y197191D01*
G01X425199Y196457D02*
Y226338D01*
G01X424962Y195694D02*
Y200939D01*
G01X424811Y196457D02*
Y226338D01*
G01X424200Y200939D02*
Y196457D01*
G01X423736Y180551D02*
Y157126D01*
G01X422949Y174463D02*
Y177161D01*
G01Y167140D02*
Y172803D01*
G01Y160650D02*
Y165481D01*
G01X422910Y165420D02*
Y163186D01*
G01Y172743D02*
Y167200D01*
G01Y180551D02*
Y174523D01*
G01X422875Y190833D02*
Y190157D01*
G01X422678Y190748D02*
Y201804D01*
G01X422363Y195669D02*
Y191732D01*
G01X422265Y195906D02*
Y191969D01*
G01X419903Y195906D02*
Y191969D01*
G01X419839Y174523D02*
Y180551D01*
G01Y167200D02*
Y172743D01*
G01Y163186D02*
Y165420D01*
G01X419804Y195669D02*
Y191732D01*
G01X419799Y165481D02*
Y160650D01*
G01Y172803D02*
Y167140D01*
G01Y177161D02*
Y174463D01*
G01X419489Y201804D02*
Y190748D01*
G01X419292Y190833D02*
Y190157D01*
G01X419012Y180551D02*
Y157126D01*
G01X417329Y228740D02*
Y190157D01*
G01X415862Y160650D02*
Y177161D01*
G01X414288Y142933D02*
Y159075D01*
G01X419438Y201804D02*
X419442Y190755D01*
G01X419449Y190157D02*
X419442Y190755D01*
G01X468028Y179547D02*
X469406Y177161D01*
G01X460941Y179547D02*
X462319Y177161D01*
G01X469445Y163607D02*
X470232Y162243D01*
G01X453854Y179547D02*
X455232Y177161D01*
G01X446768Y179547D02*
X448146Y177161D01*
G01X439681Y179547D02*
X441059Y177161D01*
G01X432595Y179547D02*
X433973Y177161D01*
G01X425508Y179547D02*
X426886Y177161D01*
G01X418421Y179547D02*
X419799Y177161D01*
G01X419839Y163186D02*
X420626Y161822D01*
G01X467860Y197191D02*
X469410D01*
G01X453687D02*
X455237D01*
G01X439514D02*
X441064D01*
G01X425341D02*
X426891D01*
G01X468248Y196994D02*
X469410D01*
G01X454075D02*
X455237D01*
G01X439902D02*
X441064D01*
G01X425729D02*
X426891D01*
G01X424200Y196457D02*
X426891D01*
G01X441064D02*
X438373D01*
G01X455237D02*
X452546D01*
G01X469410D02*
X466719D01*
G01X468173Y196260D02*
X469410D01*
G01X454000D02*
X455237D01*
G01X439827D02*
X441064D01*
G01X425654D02*
X426891D01*
G01X467482Y196075D02*
X469410D01*
G01X453309D02*
X455237D01*
G01X439135D02*
X441064D01*
G01X424962D02*
X426891D01*
G01X469804Y196063D02*
X471576D01*
G01X421969D02*
X420198D01*
G01X429056D02*
X427284D01*
G01X426891D02*
X425611D01*
G01X429580D02*
X429450D01*
G01X436143D02*
X434371D01*
G01X441064D02*
X439784D01*
G01X443229D02*
X441458D01*
G01X443753D02*
X443623D01*
G01X450316D02*
X448544D01*
G01X455237D02*
X453957D01*
G01X457403D02*
X455631D01*
G01X457927D02*
X457796D01*
G01X464489D02*
X462717D01*
G01X469410D02*
X468130D01*
G01X422265Y195906D02*
X419903D01*
G01X471871D02*
X469509D01*
G01X467482Y195694D02*
X469410D01*
G01X453309D02*
X455237D01*
G01X439135D02*
X441064D01*
G01X424962D02*
X426891D01*
G01Y195669D02*
X425611D01*
G01X441064D02*
X439784D01*
G01X455237D02*
X453957D01*
G01X469410D02*
X468130D01*
G01X469509Y195048D02*
X471871D01*
G01X419804Y193567D02*
X417329D01*
G01X426891D02*
X422363D01*
G01X433977D02*
X429450D01*
G01X441064D02*
X436536D01*
G01X448151D02*
X443623D01*
G01X455237D02*
X450710D01*
G01X462324D02*
X457796D01*
G01X469410D02*
X464883D01*
G01X422265Y193543D02*
X419903D01*
G01X471871D02*
X469509D01*
G01X464883Y193370D02*
X469410D01*
G01X457796D02*
X462324D01*
G01X450710D02*
X455237D01*
G01X443623D02*
X448151D01*
G01X436536D02*
X441064D01*
G01X422363D02*
X426891D01*
G01X417329D02*
X419804D01*
G01X433977D02*
X429450D01*
G01X422265Y191969D02*
X419903D01*
G01X471871D02*
X469509D01*
G01X422363Y191732D02*
X419804D01*
G01X429450D02*
X426891D01*
G01X436536D02*
X433977D01*
G01X443623D02*
X441064D01*
G01X450710D02*
X448151D01*
G01X457796D02*
X455237D01*
G01X464883D02*
X462324D01*
G01X471969D02*
X469410D01*
G01X473628Y190748D02*
X417329D01*
G01X468899Y190236D02*
X472481D01*
G01X440552D02*
X444135D01*
G01X429962D02*
X426379D01*
G01X458308D02*
X454725D01*
G01X473956Y190157D02*
X417329D01*
G01X473956Y189370D02*
X417818D01*
G01X422910Y180551D02*
X469445D01*
G01X419839D02*
X417818D01*
G01X452673Y179547D02*
X453854D01*
G01X417240D02*
X418421D01*
G01X425508D02*
X424327D01*
G01X432595D02*
X431414D01*
G01X439681D02*
X438500D01*
G01X446768D02*
X445587D01*
G01X460941D02*
X459760D01*
G01X468028D02*
X466847D01*
G01X451492Y177502D02*
X455036D01*
G01X444406D02*
X447949D01*
G01X437319D02*
X440862D01*
G01X430232D02*
X433776D01*
G01X423146D02*
X426689D01*
G01X471728Y162243D02*
X470232D01*
G01X422122Y161822D02*
X420626D01*
G01X423736Y158665D02*
X419012D01*
G01X473343D02*
X468618D01*
G01X422752Y156142D02*
X419996D01*
G01X472358D02*
X469603D01*
G01X416142Y316929D02*
Y200787D01*
G01X471444Y202405D02*
X471483Y202464D01*
G01X471391Y202352D02*
X471444Y202405D01*
G01X471324Y202308D02*
X471391Y202352D01*
G01X471247Y202275D02*
X471324Y202308D01*
G01X471163Y202253D02*
X471247Y202275D01*
G01X457310Y202464D02*
X457330Y202525D01*
G01X457271Y202405D02*
X457310Y202464D01*
G01X457217Y202352D02*
X457271Y202405D01*
G01X457150Y202308D02*
X457217Y202352D01*
G01X457073Y202275D02*
X457150Y202308D01*
G01X456990Y202253D02*
X457073Y202275D01*
G01X443136Y202464D02*
X443156Y202525D01*
G01X443098Y202405D02*
X443136Y202464D01*
G01X443044Y202352D02*
X443098Y202405D01*
G01X442977Y202308D02*
X443044Y202352D01*
G01X442900Y202275D02*
X442977Y202308D01*
G01X442817Y202253D02*
X442900Y202275D01*
G01X458293Y200746D02*
X458308Y200820D01*
G01X458251Y200682D02*
X458293Y200746D01*
G01X458188Y200640D02*
X458251Y200682D01*
G01X458111Y200623D02*
X458188Y200640D01*
G01X444120Y200746D02*
X444135Y200820D01*
G01X444078Y200682D02*
X444120Y200746D01*
G01X444015Y200640D02*
X444078Y200682D01*
G01X443938Y200623D02*
X444015Y200640D01*
G01X429947Y200746D02*
X429962Y200820D01*
G01X429905Y200682D02*
X429947Y200746D01*
G01X429841Y200640D02*
X429905Y200682D01*
G01X429765Y200623D02*
X429841Y200640D01*
G01X471453Y201255D02*
X471523Y201289D01*
G01X471377Y201231D02*
X471453Y201255D01*
G01X471297Y201218D02*
X471377Y201231D01*
G01X429146Y201438D02*
X429165Y201496D01*
G01X429113Y201383D02*
X429146Y201438D01*
G01X429064Y201332D02*
X429113Y201383D01*
G01X429003Y201289D02*
X429064Y201332D01*
G01X428933Y201255D02*
X429003Y201289D01*
G01X428857Y201231D02*
X428933Y201255D01*
G01X428777Y201218D02*
X428857Y201231D01*
G01X471155Y202252D02*
X471163Y202253D01*
G01X471146Y202251D02*
X471155Y202252D01*
G01X471138Y202249D02*
X471146Y202251D01*
G01X471130Y202248D02*
X471138Y202249D01*
G01X471122Y202248D02*
X471130D01*
G01X471115Y202247D02*
X471122Y202248D01*
G01X456981Y202252D02*
X456990Y202253D01*
G01X456973Y202251D02*
X456981Y202252D01*
G01X456965Y202249D02*
X456973Y202251D01*
G01X456957Y202248D02*
X456965Y202249D01*
G01X456949Y202248D02*
X456957D01*
G01X456942Y202247D02*
X456949Y202248D01*
G01X442808Y202252D02*
X442817Y202253D01*
G01X442800Y202251D02*
X442808Y202252D01*
G01X442792Y202249D02*
X442800Y202251D01*
G01X442784Y202248D02*
X442792Y202249D01*
G01X442776Y202248D02*
X442784D01*
G01X442769Y202247D02*
X442776Y202248D01*
G01X428635Y202252D02*
X428643Y202253D01*
G01X428627Y202251D02*
X428635Y202252D01*
G01X428619Y202249D02*
X428627Y202251D01*
G01X428610Y202248D02*
X428619Y202249D01*
G01X428602Y202248D02*
X428610D01*
G01X428595Y202247D02*
X428602Y202248D01*
G01X426387Y200763D02*
X426379Y200820D01*
G01X426410Y200714D02*
X426387Y200763D01*
G01X426443Y200675D02*
X426410Y200714D01*
G01X426484Y200646D02*
X426443Y200675D01*
G01X426530Y200629D02*
X426484Y200646D01*
G01X426576Y200623D02*
X426530Y200629D01*
G01X440561Y200763D02*
X440552Y200820D01*
G01X440583Y200714D02*
X440561Y200763D01*
G01X440616Y200675D02*
X440583Y200714D01*
G01X440657Y200646D02*
X440616Y200675D01*
G01X440703Y200629D02*
X440657Y200646D01*
G01X440749Y200623D02*
X440703Y200629D01*
G01X454734Y200763D02*
X454725Y200820D01*
G01X454757Y200714D02*
X454734Y200763D01*
G01X454790Y200675D02*
X454757Y200714D01*
G01X454830Y200646D02*
X454790Y200675D01*
G01X454876Y200629D02*
X454830Y200646D01*
G01X454922Y200623D02*
X454876Y200629D01*
G01X468907Y200763D02*
X468899Y200820D01*
G01X468930Y200714D02*
X468907Y200763D01*
G01X468963Y200675D02*
X468930Y200714D01*
G01X469004Y200646D02*
X468963Y200675D01*
G01X469049Y200629D02*
X469004Y200646D01*
G01X469095Y200623D02*
X469049Y200629D01*
G01X438807Y201438D02*
X438788Y201496D01*
G01X438841Y201383D02*
X438807Y201438D01*
G01X438889Y201332D02*
X438841Y201383D01*
G01X438950Y201289D02*
X438889Y201332D01*
G01X439020Y201255D02*
X438950Y201289D01*
G01X439096Y201231D02*
X439020Y201255D01*
G01X439176Y201218D02*
X439096Y201231D01*
G01X452980Y201438D02*
X452962Y201496D01*
G01X453014Y201383D02*
X452980Y201438D01*
G01X453063Y201332D02*
X453014Y201383D01*
G01X453123Y201289D02*
X453063Y201332D01*
G01X453193Y201255D02*
X453123Y201289D01*
G01X453269Y201231D02*
X453193Y201255D01*
G01X453349Y201218D02*
X453269Y201231D01*
G01X467153Y201438D02*
X467135Y201496D01*
G01X467187Y201383D02*
X467153Y201438D01*
G01X467236Y201332D02*
X467187Y201383D01*
G01X467296Y201289D02*
X467236Y201332D01*
G01X467366Y201255D02*
X467296Y201289D01*
G01X467443Y201231D02*
X467366Y201255D01*
G01X467523Y201218D02*
X467443Y201231D01*
G01X425176Y202248D02*
X425184Y202247D01*
G01X425168Y202249D02*
X425176Y202248D01*
G01X425159Y202250D02*
X425168Y202249D01*
G01X425151Y202251D02*
X425159Y202250D01*
G01X425143Y202252D02*
X425151Y202251D01*
G01X425136Y202253D02*
X425143Y202252D01*
G01X439349Y202248D02*
X439358Y202247D01*
G01X439341Y202249D02*
X439349Y202248D01*
G01X439333Y202250D02*
X439341Y202249D01*
G01X439325Y202251D02*
X439333Y202250D01*
G01X439316Y202252D02*
X439325Y202251D01*
G01X439310Y202253D02*
X439316Y202252D01*
G01X453522Y202248D02*
X453531Y202247D01*
G01X453514Y202249D02*
X453522Y202248D01*
G01X453506Y202250D02*
X453514Y202249D01*
G01X453498Y202251D02*
X453506Y202250D01*
G01X453490Y202252D02*
X453498Y202251D01*
G01X453483Y202253D02*
X453490Y202252D01*
G01X467695Y202248D02*
X467704Y202247D01*
G01X467687Y202249D02*
X467695Y202248D01*
G01X467679Y202250D02*
X467687Y202249D01*
G01X467671Y202251D02*
X467679Y202250D01*
G01X467663Y202252D02*
X467671Y202251D01*
G01X467656Y202253D02*
X467663Y202252D01*
G01X428963Y202464D02*
X428983Y202525D01*
G01X428925Y202405D02*
X428963Y202464D01*
G01X428871Y202352D02*
X428925Y202405D01*
G01X428804Y202308D02*
X428871Y202352D01*
G01X428727Y202275D02*
X428804Y202308D01*
G01X428643Y202253D02*
X428727Y202275D01*
G01X471494Y228591D02*
X471466Y228533D01*
G01X471532Y228642D02*
X471494Y228591D01*
G01X458891D02*
X458863Y228533D01*
G01X458929Y228642D02*
X458891Y228591D01*
G01X458978Y228684D02*
X458929Y228642D01*
G01X459032Y228715D02*
X458978Y228684D01*
G01X459092Y228734D02*
X459032Y228715D01*
G01X459155Y228740D02*
X459092Y228734D01*
G01X457321Y228591D02*
X457293Y228533D01*
G01X457359Y228642D02*
X457321Y228591D01*
G01X457408Y228684D02*
X457359Y228642D01*
G01X457462Y228715D02*
X457408Y228684D01*
G01X457522Y228734D02*
X457462Y228715D01*
G01X457585Y228740D02*
X457522Y228734D01*
G01X444718Y228591D02*
X444690Y228533D01*
G01X444756Y228642D02*
X444718Y228591D01*
G01X444804Y228684D02*
X444756Y228642D01*
G01X444859Y228715D02*
X444804Y228684D01*
G01X444919Y228734D02*
X444859Y228715D01*
G01X444981Y228740D02*
X444919Y228734D01*
G01X443148Y228591D02*
X443120Y228533D01*
G01X443186Y228642D02*
X443148Y228591D01*
G01X443234Y228684D02*
X443186Y228642D01*
G01X443289Y228715D02*
X443234Y228684D01*
G01X443349Y228734D02*
X443289Y228715D01*
G01X443411Y228740D02*
X443349Y228734D01*
G01X430544Y228591D02*
X430517Y228533D01*
G01X430583Y228642D02*
X430544Y228591D01*
G01X430631Y228684D02*
X430583Y228642D01*
G01X430686Y228715D02*
X430631Y228684D01*
G01X430746Y228734D02*
X430686Y228715D01*
G01X430808Y228740D02*
X430746Y228734D01*
G01X428974Y228591D02*
X428947Y228533D01*
G01X429013Y228642D02*
X428974Y228591D01*
G01X429061Y228684D02*
X429013Y228642D01*
G01X429116Y228715D02*
X429061Y228684D01*
G01X429176Y228734D02*
X429116Y228715D01*
G01X429238Y228740D02*
X429176Y228734D01*
G01X428550Y226997D02*
X428580Y227011D01*
G01X428502Y226990D02*
X428550Y226997D01*
G01X428440Y226992D02*
X428502Y226990D01*
G01X442723Y226997D02*
X442754Y227011D01*
G01X442675Y226990D02*
X442723Y226997D01*
G01X442614Y226992D02*
X442675Y226990D01*
G01X456896Y226997D02*
X456927Y227011D01*
G01X456848Y226990D02*
X456896Y226997D01*
G01X456787Y226992D02*
X456848Y226990D01*
G01X471069Y226997D02*
X471100Y227011D01*
G01X471021Y226990D02*
X471069Y226997D01*
G01X470960Y226992D02*
X471021Y226990D01*
G01X423550Y228514D02*
X423927Y228425D01*
G01X423473Y228533D02*
X423550Y228514D01*
G01X437723D02*
X438100Y228425D01*
G01X437647Y228533D02*
X437723Y228514D01*
G01X451896D02*
X452274Y228425D01*
G01X451820Y228533D02*
X451896Y228514D01*
G01X466070D02*
X466447Y228425D01*
G01X465993Y228533D02*
X466070Y228514D01*
G01X425317Y226990D02*
X425379Y226992D01*
G01X425270Y226997D02*
X425317Y226990D01*
G01X425239Y227011D02*
X425270Y226997D01*
G01X439491Y226990D02*
X439552Y226992D01*
G01X439443Y226997D02*
X439491Y226990D01*
G01X439412Y227011D02*
X439443Y226997D01*
G01X453664Y226990D02*
X453725Y226992D01*
G01X453616Y226997D02*
X453664Y226990D01*
G01X453585Y227011D02*
X453616Y226997D01*
G01X467837Y226990D02*
X467899Y226992D01*
G01X467789Y226997D02*
X467837Y226990D01*
G01X467758Y227011D02*
X467789Y226997D01*
G01X428506Y227952D02*
X428343Y227395D01*
G01X428586Y228378D02*
X428506Y227952D01*
G01X428578Y228647D02*
X428586Y228378D01*
G01X428484Y228740D02*
X428578Y228647D01*
G01X428711Y228709D02*
X428484Y228740D01*
G01X428858Y228639D02*
X428711Y228709D01*
G01X428947Y228533D02*
X428858Y228639D01*
G01X442680Y227952D02*
X442516Y227395D01*
G01X442760Y228378D02*
X442680Y227952D01*
G01X442752Y228647D02*
X442760Y228378D01*
G01X442657Y228740D02*
X442752Y228647D01*
G01X456853Y227952D02*
X456689Y227395D01*
G01X456933Y228378D02*
X456853Y227952D01*
G01X456925Y228647D02*
X456933Y228378D01*
G01X456831Y228740D02*
X456925Y228647D01*
G01X471026Y227952D02*
X470862Y227395D01*
G01X471106Y228378D02*
X471026Y227952D01*
G01X471098Y228647D02*
X471106Y228378D01*
G01X471004Y228740D02*
X471098Y228647D01*
G01X442884Y228709D02*
X442657Y228740D01*
G01X443031Y228639D02*
X442884Y228709D01*
G01X443120Y228533D02*
X443031Y228639D01*
G01X457057Y228709D02*
X456831Y228740D01*
G01X457204Y228639D02*
X457057Y228709D01*
G01X457293Y228533D02*
X457204Y228639D01*
G01X471231Y228709D02*
X471004Y228740D01*
G01X471378Y228639D02*
X471231Y228709D01*
G01X471466Y228533D02*
X471378Y228639D01*
G01X425631Y226581D02*
X425728Y226378D01*
G01X425514Y226786D02*
X425631Y226581D01*
G01X425291Y227127D02*
X425514Y226786D01*
G01X439804Y226581D02*
X439901Y226378D01*
G01X439687Y226786D02*
X439804Y226581D01*
G01X439464Y227127D02*
X439687Y226786D01*
G01X453977Y226581D02*
X454075Y226378D01*
G01X453860Y226786D02*
X453977Y226581D01*
G01X453637Y227127D02*
X453860Y226786D01*
G01X425212Y227261D02*
X425291Y227127D01*
G01X425144Y227395D02*
X425212Y227261D01*
G01X439385D02*
X439464Y227127D01*
G01X439317Y227395D02*
X439385Y227261D01*
G01X423035Y228734D02*
X422972Y228740D01*
G01X423095Y228714D02*
X423035Y228734D01*
G01X423151Y228683D02*
X423095Y228714D01*
G01X423198Y228641D02*
X423151Y228683D01*
G01X423236Y228590D02*
X423198Y228641D01*
G01X423263Y228533D02*
X423236Y228590D01*
G01X423245Y228734D02*
X423182Y228740D01*
G01X423305Y228714D02*
X423245Y228734D01*
G01X423361Y228683D02*
X423305Y228714D01*
G01X423408Y228641D02*
X423361Y228683D01*
G01X423446Y228590D02*
X423408Y228641D01*
G01X423473Y228533D02*
X423446Y228590D01*
G01X424288Y228734D02*
X424225Y228740D01*
G01X424348Y228714D02*
X424288Y228734D01*
G01X424403Y228683D02*
X424348Y228714D01*
G01X424451Y228641D02*
X424403Y228683D01*
G01X424489Y228590D02*
X424451Y228641D01*
G01X424516Y228533D02*
X424489Y228590D01*
G01X424645Y228734D02*
X424581Y228740D01*
G01X424704Y228714D02*
X424645Y228734D01*
G01X424759Y228683D02*
X424704Y228714D01*
G01X424807Y228641D02*
X424759Y228683D01*
G01X424845Y228590D02*
X424807Y228641D01*
G01X424873Y228533D02*
X424845Y228590D01*
G01X437208Y228734D02*
X437145Y228740D01*
G01X437268Y228714D02*
X437208Y228734D01*
G01X437324Y228683D02*
X437268Y228714D01*
G01X437371Y228641D02*
X437324Y228683D01*
G01X437409Y228590D02*
X437371Y228641D01*
G01X437436Y228533D02*
X437409Y228590D01*
G01X437418Y228734D02*
X437355Y228740D01*
G01X437478Y228714D02*
X437418Y228734D01*
G01X437534Y228683D02*
X437478Y228714D01*
G01X437581Y228641D02*
X437534Y228683D01*
G01X437619Y228590D02*
X437581Y228641D01*
G01X437646Y228533D02*
X437619Y228590D01*
G01X438462Y228734D02*
X438398Y228740D01*
G01X438521Y228714D02*
X438462Y228734D01*
G01X438576Y228683D02*
X438521Y228714D01*
G01X438624Y228641D02*
X438576Y228683D01*
G01X438662Y228590D02*
X438624Y228641D01*
G01X438690Y228533D02*
X438662Y228590D01*
G01X438818Y228734D02*
X438754Y228740D01*
G01X438878Y228714D02*
X438818Y228734D01*
G01X438932Y228683D02*
X438878Y228714D01*
G01X438980Y228641D02*
X438932Y228683D01*
G01X439019Y228590D02*
X438980Y228641D01*
G01X439046Y228533D02*
X439019Y228590D01*
G01X425052Y202275D02*
X425136Y202253D01*
G01X424974Y202309D02*
X425052Y202275D01*
G01X424907Y202353D02*
X424974Y202309D01*
G01X424854Y202406D02*
X424907Y202353D01*
G01X424816Y202464D02*
X424854Y202406D01*
G01X424797Y202525D02*
X424816Y202464D01*
G01X424922Y201231D02*
X425003Y201218D01*
G01X424846Y201255D02*
X424922Y201231D01*
G01X424775Y201290D02*
X424846Y201255D01*
G01X424715Y201334D02*
X424775Y201290D01*
G01X424667Y201384D02*
X424715Y201334D01*
G01X424633Y201439D02*
X424667Y201384D01*
G01X424615Y201496D02*
X424633Y201439D01*
G01X425241Y228649D02*
X425335Y228740D01*
G01X425232Y228383D02*
X425241Y228649D01*
G01X425312Y227957D02*
X425232Y228383D01*
G01X425476Y227395D02*
X425312Y227957D01*
G01X428813Y201040D02*
X428818Y200939D01*
G01X428799Y201135D02*
X428813Y201040D01*
G01X428777Y201218D02*
X428799Y201135D01*
G01X424742Y225061D02*
X424675Y225280D01*
G01X424783Y224835D02*
X424742Y225061D01*
G01X424797Y224607D02*
X424783Y224835D01*
G01X425120Y225152D02*
X425040Y225415D01*
G01X425168Y224881D02*
X425120Y225152D01*
G01X425184Y224607D02*
X425168Y224881D01*
G01X424531Y225061D02*
X424465Y225280D01*
G01X424572Y224836D02*
X424531Y225061D01*
G01X424585Y224607D02*
X424572Y224836D01*
G01X425145Y226792D02*
X425079Y227011D01*
G01X425185Y226566D02*
X425145Y226792D01*
G01X425199Y226338D02*
X425185Y226566D01*
G01X424199Y201037D02*
X424200Y200939D01*
G01X424199Y201137D02*
Y201037D01*
G01X424197Y201241D02*
X424199Y201137D01*
G01X429197Y201141D02*
X429195Y201241D01*
G01X429198Y201039D02*
X429197Y201141D01*
G01X468151Y226581D02*
X468248Y226378D01*
G01X468033Y226786D02*
X468151Y226581D01*
G01X467810Y227127D02*
X468033Y226786D01*
G01X453558Y227261D02*
X453637Y227127D01*
G01X453490Y227395D02*
X453558Y227261D01*
G01X467731D02*
X467810Y227127D01*
G01X467663Y227395D02*
X467731Y227261D01*
G01X451382Y228734D02*
X451318Y228740D01*
G01X451441Y228714D02*
X451382Y228734D01*
G01X451497Y228683D02*
X451441Y228714D01*
G01X451544Y228641D02*
X451497Y228683D01*
G01X451582Y228590D02*
X451544Y228641D01*
G01X451610Y228533D02*
X451582Y228590D01*
G01X451592Y228734D02*
X451528Y228740D01*
G01X451651Y228714D02*
X451592Y228734D01*
G01X451707Y228683D02*
X451651Y228714D01*
G01X451754Y228641D02*
X451707Y228683D01*
G01X451792Y228590D02*
X451754Y228641D01*
G01X451820Y228533D02*
X451792Y228590D01*
G01X452635Y228734D02*
X452571Y228740D01*
G01X452695Y228714D02*
X452635Y228734D01*
G01X452749Y228683D02*
X452695Y228714D01*
G01X452798Y228641D02*
X452749Y228683D01*
G01X452836Y228590D02*
X452798Y228641D01*
G01X452863Y228533D02*
X452836Y228590D01*
G01X452991Y228734D02*
X452928Y228740D01*
G01X453051Y228714D02*
X452991Y228734D01*
G01X453105Y228683D02*
X453051Y228714D01*
G01X453154Y228641D02*
X453105Y228683D01*
G01X453192Y228590D02*
X453154Y228641D01*
G01X453219Y228533D02*
X453192Y228590D01*
G01X465555Y228734D02*
X465491Y228740D01*
G01X465615Y228714D02*
X465555Y228734D01*
G01X465670Y228683D02*
X465615Y228714D01*
G01X465717Y228641D02*
X465670Y228683D01*
G01X465756Y228590D02*
X465717Y228641D01*
G01X465783Y228533D02*
X465756Y228590D01*
G01X465765Y228734D02*
X465701Y228740D01*
G01X465825Y228714D02*
X465765Y228734D01*
G01X465880Y228683D02*
X465825Y228714D01*
G01X465928Y228641D02*
X465880Y228683D01*
G01X465966Y228590D02*
X465928Y228641D01*
G01X465993Y228533D02*
X465966Y228590D01*
G01X466808Y228734D02*
X466745Y228740D01*
G01X466868Y228714D02*
X466808Y228734D01*
G01X466923Y228683D02*
X466868Y228714D01*
G01X466971Y228641D02*
X466923Y228683D01*
G01X467009Y228590D02*
X466971Y228641D01*
G01X467036Y228533D02*
X467009Y228590D01*
G01X467164Y228734D02*
X467101Y228740D01*
G01X467224Y228714D02*
X467164Y228734D01*
G01X467279Y228683D02*
X467224Y228714D01*
G01X467327Y228641D02*
X467279Y228683D01*
G01X467365Y228590D02*
X467327Y228641D01*
G01X467392Y228533D02*
X467365Y228590D01*
G01X439226Y202275D02*
X439310Y202253D01*
G01X439147Y202309D02*
X439226Y202275D01*
G01X439081Y202353D02*
X439147Y202309D01*
G01X439027Y202406D02*
X439081Y202353D01*
G01X438990Y202464D02*
X439027Y202406D01*
G01X438970Y202525D02*
X438990Y202464D01*
G01X453399Y202275D02*
X453483Y202253D01*
G01X453321Y202309D02*
X453399Y202275D01*
G01X453254Y202353D02*
X453321Y202309D01*
G01X453200Y202406D02*
X453254Y202353D01*
G01X453163Y202464D02*
X453200Y202406D01*
G01X453143Y202525D02*
X453163Y202464D01*
G01X467572Y202275D02*
X467656Y202253D01*
G01X467494Y202309D02*
X467572Y202275D01*
G01X467427Y202353D02*
X467494Y202309D01*
G01X467374Y202406D02*
X467427Y202353D01*
G01X467336Y202464D02*
X467374Y202406D01*
G01X467316Y202525D02*
X467336Y202464D01*
G01X439415Y228649D02*
X439508Y228740D01*
G01X439405Y228383D02*
X439415Y228649D01*
G01X439485Y227957D02*
X439405Y228383D01*
G01X439650Y227395D02*
X439485Y227957D01*
G01X453588Y228649D02*
X453682Y228740D01*
G01X453579Y228383D02*
X453588Y228649D01*
G01X453658Y227957D02*
X453579Y228383D01*
G01X453823Y227395D02*
X453658Y227957D01*
G01X467761Y228649D02*
X467855Y228740D01*
G01X467752Y228383D02*
X467761Y228649D01*
G01X467831Y227957D02*
X467752Y228383D01*
G01X467996Y227395D02*
X467831Y227957D01*
G01X442986Y201040D02*
X442991Y200939D01*
G01X442972Y201135D02*
X442986Y201040D01*
G01X442950Y201218D02*
X442972Y201135D01*
G01X457159Y201040D02*
X457164Y200939D01*
G01X457146Y201135D02*
X457159Y201040D01*
G01X457123Y201218D02*
X457146Y201135D01*
G01X425327Y226585D02*
X425341Y226371D01*
G01X425293Y226800D02*
X425327Y226585D01*
G01X425239Y227011D02*
X425293Y226800D01*
G01X439500Y226585D02*
X439514Y226371D01*
G01X439466Y226800D02*
X439500Y226585D01*
G01X439412Y227011D02*
X439466Y226800D01*
G01X453673Y226585D02*
X453687Y226371D01*
G01X453640Y226800D02*
X453673Y226585D01*
G01X453585Y227011D02*
X453640Y226800D01*
G01X425057Y227630D02*
X425239Y227011D01*
G01X424941Y228112D02*
X425057Y227630D01*
G01X424873Y228533D02*
X424941Y228112D01*
G01X439230Y227630D02*
X439412Y227011D01*
G01X439115Y228112D02*
X439230Y227630D01*
G01X439046Y228533D02*
X439115Y228112D01*
G01X429187Y201333D02*
X429195Y201241D01*
G01X429177Y201419D02*
X429187Y201333D01*
G01X429165Y201496D02*
X429177Y201419D01*
G01X443350D02*
X443338Y201496D01*
G01X443360Y201333D02*
X443350Y201419D01*
G01X443368Y201241D02*
X443360Y201333D01*
G01X457523Y201419D02*
X457511Y201496D01*
G01X457533Y201333D02*
X457523Y201419D01*
G01X457541Y201241D02*
X457533Y201333D01*
G01X438916Y225061D02*
X438849Y225280D01*
G01X438956Y224835D02*
X438916Y225061D01*
G01X438970Y224607D02*
X438956Y224835D01*
G01X453089Y225061D02*
X453022Y225280D01*
G01X453129Y224835D02*
X453089Y225061D01*
G01X453143Y224607D02*
X453129Y224835D01*
G01X467262Y225061D02*
X467195Y225280D01*
G01X467303Y224835D02*
X467262Y225061D01*
G01X467316Y224607D02*
X467303Y224835D01*
G01X439293Y225152D02*
X439213Y225415D01*
G01X439341Y224881D02*
X439293Y225152D01*
G01X439358Y224607D02*
X439341Y224881D01*
G01X453466Y225152D02*
X453386Y225415D01*
G01X453515Y224881D02*
X453466Y225152D01*
G01X453531Y224607D02*
X453515Y224881D01*
G01X467639Y225152D02*
X467559Y225415D01*
G01X467688Y224881D02*
X467639Y225152D01*
G01X467704Y224607D02*
X467688Y224881D01*
G01X438705Y225061D02*
X438638Y225280D01*
G01X438745Y224836D02*
X438705Y225061D01*
G01X438758Y224607D02*
X438745Y224836D01*
G01X452878Y225061D02*
X452812Y225280D01*
G01X452918Y224836D02*
X452878Y225061D01*
G01X452932Y224607D02*
X452918Y224836D01*
G01X467051Y225061D02*
X466985Y225280D01*
G01X467091Y224836D02*
X467051Y225061D01*
G01X467105Y224607D02*
X467091Y224836D01*
G01X439318Y226792D02*
X439252Y227011D01*
G01X439358Y226566D02*
X439318Y226792D01*
G01X439372Y226338D02*
X439358Y226566D01*
G01X453492Y226792D02*
X453425Y227011D01*
G01X453532Y226566D02*
X453492Y226792D01*
G01X453545Y226338D02*
X453532Y226566D01*
G01X467665Y226792D02*
X467599Y227011D01*
G01X467705Y226566D02*
X467665Y226792D01*
G01X467718Y226338D02*
X467705Y226566D01*
G01X471319Y201135D02*
X471297Y201218D01*
G01X471333Y201040D02*
X471319Y201135D01*
G01X471337Y200939D02*
X471333Y201040D01*
G01X438372Y201037D02*
X438373Y200939D01*
G01X438372Y201137D02*
Y201037D01*
G01X438371Y201241D02*
X438372Y201137D01*
G01X443370Y201141D02*
X443368Y201241D01*
G01X443372Y201039D02*
X443370Y201141D01*
G01X452545Y201037D02*
X452546Y200939D01*
G01X452545Y201137D02*
Y201037D01*
G01X452544Y201241D02*
X452545Y201137D01*
G01X457544Y201141D02*
X457541Y201241D01*
G01X457545Y201039D02*
X457544Y201141D01*
G01X466718Y201037D02*
X466719Y200939D01*
G01X466718Y201137D02*
Y201037D01*
G01X466717Y201241D02*
X466718Y201137D01*
G01X424583Y201144D02*
X424581Y201043D01*
G01X424585Y201241D02*
X424583Y201144D01*
G01X438756D02*
X438755Y201043D01*
G01X438758Y201241D02*
X438756Y201144D01*
G01X452929D02*
X452928Y201043D01*
G01X452932Y201241D02*
X452929Y201144D01*
G01X424981Y201135D02*
X425003Y201218D01*
G01X424967Y201040D02*
X424981Y201135D01*
G01X424962Y200939D02*
X424967Y201040D01*
G01X439154Y201135D02*
X439176Y201218D01*
G01X439140Y201040D02*
X439154Y201135D01*
G01X439135Y200939D02*
X439140Y201040D01*
G01X453327Y201135D02*
X453349Y201218D01*
G01X453313Y201040D02*
X453327Y201135D01*
G01X453309Y200939D02*
X453313Y201040D01*
G01X429248Y225061D02*
X429315Y225280D01*
G01X429208Y224836D02*
X429248Y225061D01*
G01X429195Y224607D02*
X429208Y224836D01*
G01X443422Y225061D02*
X443488Y225280D01*
G01X443381Y224836D02*
X443422Y225061D01*
G01X443368Y224607D02*
X443381Y224836D01*
G01X457595Y225061D02*
X457661Y225280D01*
G01X457555Y224836D02*
X457595Y225061D01*
G01X457541Y224607D02*
X457555Y224836D01*
G01X428526Y226800D02*
X428580Y227011D01*
G01X428492Y226585D02*
X428526Y226800D01*
G01X428479Y226371D02*
X428492Y226585D01*
G01X442699Y226800D02*
X442754Y227011D01*
G01X442665Y226585D02*
X442699Y226800D01*
G01X442652Y226371D02*
X442665Y226585D01*
G01X456872Y226800D02*
X456927Y227011D01*
G01X456839Y226585D02*
X456872Y226800D01*
G01X456825Y226371D02*
X456839Y226585D01*
G01X424603Y201419D02*
X424615Y201496D01*
G01X424593Y201333D02*
X424603Y201419D01*
G01X424585Y201241D02*
X424593Y201333D01*
G01X438766D02*
X438758Y201241D01*
G01X438776Y201419D02*
X438766Y201333D01*
G01X438788Y201496D02*
X438776Y201419D01*
G01X428761Y227626D02*
X428580Y227011D01*
G01X428877Y228109D02*
X428761Y227626D01*
G01X428947Y228533D02*
X428877Y228109D01*
G01X442935Y227626D02*
X442754Y227011D01*
G01X443050Y228109D02*
X442935Y227626D01*
G01X443120Y228533D02*
X443050Y228109D01*
G01X467847Y226585D02*
X467860Y226371D01*
G01X467813Y226800D02*
X467847Y226585D01*
G01X467758Y227011D02*
X467813Y226800D01*
G01X453403Y227630D02*
X453585Y227011D01*
G01X453288Y228112D02*
X453403Y227630D01*
G01X453219Y228533D02*
X453288Y228112D01*
G01X467576Y227630D02*
X467758Y227011D01*
G01X467461Y228112D02*
X467576Y227630D01*
G01X467392Y228533D02*
X467461Y228112D01*
G01X469000Y199978D02*
X469044Y199961D01*
G01X468961Y200007D02*
X469000Y199978D01*
G01X468929Y200046D02*
X468961Y200007D01*
G01X468907Y200094D02*
X468929Y200046D01*
G01X468899Y200151D02*
X468907Y200094D01*
G01X467102Y201144D02*
X467101Y201043D01*
G01X467105Y201241D02*
X467102Y201144D01*
G01X467500Y201135D02*
X467523Y201218D01*
G01X467487Y201040D02*
X467500Y201135D01*
G01X467482Y200939D02*
X467487Y201040D01*
G01X471046Y226800D02*
X471100Y227011D01*
G01X471012Y226585D02*
X471046Y226800D01*
G01X470998Y226371D02*
X471012Y226585D01*
G01X452940Y201333D02*
X452932Y201241D01*
G01X452950Y201419D02*
X452940Y201333D01*
G01X452962Y201496D02*
X452950Y201419D01*
G01X467113Y201333D02*
X467105Y201241D01*
G01X467123Y201419D02*
X467113Y201333D01*
G01X467135Y201496D02*
X467123Y201419D01*
G01X457108Y227626D02*
X456927Y227011D01*
G01X457224Y228109D02*
X457108Y227626D01*
G01X457293Y228533D02*
X457224Y228109D01*
G01X471281Y227626D02*
X471100Y227011D01*
G01X471397Y228109D02*
X471281Y227626D01*
G01X471466Y228533D02*
X471397Y228109D01*
G01X428634Y226566D02*
X428620Y226338D01*
G01X428674Y226792D02*
X428634Y226566D01*
G01X428740Y227011D02*
X428674Y226792D01*
G01X442807Y226566D02*
X442794Y226338D01*
G01X442847Y226792D02*
X442807Y226566D01*
G01X442914Y227011D02*
X442847Y226792D01*
G01X456980Y226566D02*
X456967Y226338D01*
G01X457020Y226792D02*
X456980Y226566D01*
G01X457087Y227011D02*
X457020Y226792D01*
G01X428612Y224881D02*
X428595Y224607D01*
G01X428660Y225152D02*
X428612Y224881D01*
G01X428740Y225415D02*
X428660Y225152D01*
G01X442785Y224881D02*
X442769Y224607D01*
G01X442833Y225152D02*
X442785Y224881D01*
G01X442913Y225415D02*
X442833Y225152D01*
G01X456958Y224881D02*
X456942Y224607D01*
G01X457007Y225152D02*
X456958Y224881D01*
G01X457087Y225415D02*
X457007Y225152D01*
G01X428997Y224835D02*
X428983Y224607D01*
G01X429037Y225061D02*
X428997Y224835D01*
G01X429104Y225280D02*
X429037Y225061D01*
G01X443170Y224835D02*
X443156Y224607D01*
G01X443211Y225061D02*
X443170Y224835D01*
G01X443278Y225280D02*
X443211Y225061D01*
G01X457343Y224835D02*
X457330Y224607D01*
G01X457384Y225061D02*
X457343Y224835D01*
G01X457451Y225280D02*
X457384Y225061D01*
G01X443031Y201231D02*
X442950Y201218D01*
G01X443108Y201255D02*
X443031Y201231D01*
G01X443178Y201290D02*
X443108Y201255D01*
G01X443238Y201334D02*
X443178Y201290D01*
G01X443286Y201384D02*
X443238Y201334D01*
G01X443320Y201439D02*
X443286Y201384D01*
G01X443338Y201496D02*
X443320Y201439D01*
G01X457204Y201231D02*
X457123Y201218D01*
G01X457281Y201255D02*
X457204Y201231D01*
G01X457352Y201290D02*
X457281Y201255D01*
G01X457412Y201334D02*
X457352Y201290D01*
G01X457460Y201384D02*
X457412Y201334D01*
G01X457493Y201439D02*
X457460Y201384D01*
G01X457511Y201496D02*
X457493Y201439D01*
G01X429531Y228734D02*
X429594Y228740D01*
G01X429471Y228714D02*
X429531Y228734D01*
G01X429415Y228683D02*
X429471Y228714D01*
G01X429368Y228641D02*
X429415Y228683D01*
G01X429330Y228590D02*
X429368Y228641D01*
G01X429303Y228533D02*
X429330Y228590D01*
G01X430535Y228734D02*
X430598Y228740D01*
G01X430475Y228714D02*
X430535Y228734D01*
G01X430419Y228683D02*
X430475Y228714D01*
G01X430372Y228641D02*
X430419Y228683D01*
G01X430334Y228590D02*
X430372Y228641D01*
G01X430307Y228533D02*
X430334Y228590D01*
G01X443704Y228734D02*
X443767Y228740D01*
G01X443644Y228714D02*
X443704Y228734D01*
G01X443589Y228683D02*
X443644Y228714D01*
G01X443541Y228641D02*
X443589Y228683D01*
G01X443503Y228590D02*
X443541Y228641D01*
G01X443476Y228533D02*
X443503Y228590D01*
G01X444708Y228734D02*
X444771Y228740D01*
G01X444648Y228714D02*
X444708Y228734D01*
G01X444592Y228683D02*
X444648Y228714D01*
G01X444545Y228641D02*
X444592Y228683D01*
G01X444507Y228590D02*
X444545Y228641D01*
G01X444480Y228533D02*
X444507Y228590D01*
G01X428188Y226581D02*
X428305Y226785D01*
G01X428091Y226378D02*
X428188Y226581D01*
G01X442361D02*
X442479Y226785D01*
G01X442264Y226378D02*
X442361Y226581D01*
G01X471154Y226566D02*
X471140Y226338D01*
G01X471194Y226792D02*
X471154Y226566D01*
G01X471260Y227011D02*
X471194Y226792D01*
G01X471131Y224881D02*
X471115Y224607D01*
G01X471180Y225152D02*
X471131Y224881D01*
G01X471260Y225415D02*
X471180Y225152D01*
G01X457877Y228734D02*
X457941Y228740D01*
G01X457817Y228714D02*
X457877Y228734D01*
G01X457762Y228683D02*
X457817Y228714D01*
G01X457715Y228641D02*
X457762Y228683D01*
G01X457676Y228590D02*
X457715Y228641D01*
G01X457649Y228533D02*
X457676Y228590D01*
G01X458881Y228734D02*
X458944Y228740D01*
G01X458821Y228714D02*
X458881Y228734D01*
G01X458766Y228683D02*
X458821Y228714D01*
G01X458718Y228641D02*
X458766Y228683D01*
G01X458680Y228590D02*
X458718Y228641D01*
G01X458653Y228533D02*
X458680Y228590D01*
G01X456535Y226581D02*
X456652Y226785D01*
G01X456437Y226378D02*
X456535Y226581D01*
G01X470708D02*
X470825Y226785D01*
G01X470611Y226378D02*
X470708Y226581D01*
G01X428607Y227261D02*
X428676Y227395D01*
G01X428529Y227127D02*
X428607Y227261D01*
G01X428305Y226785D02*
X428529Y227127D01*
G01X442781Y227261D02*
X442849Y227395D01*
G01X442702Y227127D02*
X442781Y227261D01*
G01X442479Y226785D02*
X442702Y227127D01*
G01X456954Y227261D02*
X457022Y227395D01*
G01X456875Y227127D02*
X456954Y227261D01*
G01X456652Y226785D02*
X456875Y227127D01*
G01X471127Y227261D02*
X471195Y227395D01*
G01X471048Y227127D02*
X471127Y227261D01*
G01X470825Y226785D02*
X471048Y227127D01*
G01X425112Y228710D02*
X425335Y228740D01*
G01X424954Y228633D02*
X425112Y228710D01*
G01X424873Y228533D02*
X424954Y228633D01*
G01X439285Y228710D02*
X439508Y228740D01*
G01X439127Y228633D02*
X439285Y228710D01*
G01X439046Y228533D02*
X439127Y228633D01*
G01X453458Y228710D02*
X453682Y228740D01*
G01X453300Y228633D02*
X453458Y228710D01*
G01X453219Y228533D02*
X453300Y228633D01*
G01X467632Y228710D02*
X467855Y228740D01*
G01X467474Y228633D02*
X467632Y228710D01*
G01X467392Y228533D02*
X467474Y228633D01*
G01X466699Y224607D02*
G03X466604Y225140I-1535J1D01*
G01X467312Y226338D02*
G03X467217Y226870I-1535J0D01*
G01X457468D02*
G03X457372Y226338I1440J-535D01*
G01X443295Y226870D02*
G03X443199Y226338I1440J-535D01*
G01X438353Y224607D02*
G03X438257Y225140I-1536J-1D01*
G01X452526Y224607D02*
G03X452431Y225140I-1536J1D01*
G01X453139Y226338D02*
G03X453044Y226870I-1535J0D01*
G01X438966Y226338D02*
G03X438871Y226870I-1535J0D01*
G01X443869Y225139D02*
G03X443774Y224607I1440J-532D01*
G01X458043Y225139D02*
G03X457947Y224607I1440J-535D01*
G01X429121Y226870D02*
G03X429026Y226338I1440J-532D01*
G01X424179Y224607D02*
G03X424084Y225140I-1535J1D01*
G01X424793Y226338D02*
G03X424697Y226870I-1536J-3D01*
G01X429696Y225139D02*
G03X429601Y224607I1440J-532D01*
G01X467036Y228533D02*
X466662Y228425D01*
G01X465409D02*
X465783Y228533D01*
G01X452863D02*
X452489Y228425D01*
G01X451235D02*
X451610Y228533D01*
G01X438690D02*
X438315Y228425D01*
G01X437062D02*
X437436Y228533D01*
G01X467559Y225415D02*
X467195Y225280D01*
G01X466985D02*
X466621Y225146D01*
G01X467599Y227011D02*
X467234Y226876D01*
G01X453386Y225415D02*
X453022Y225280D01*
G01X452812D02*
X452447Y225146D01*
G01X453425Y227011D02*
X453061Y226876D01*
G01X439213Y225415D02*
X438849Y225280D01*
G01X438638D02*
X438274Y225146D01*
G01X424516Y228533D02*
X424142Y228425D01*
G01X422889D02*
X423263Y228533D01*
G01X439252Y227011D02*
X438888Y226876D01*
G01X425040Y225415D02*
X424675Y225280D01*
G01X424465D02*
X424101Y225146D01*
G01X425079Y227011D02*
X424715Y226876D01*
G01X466738Y228740D02*
X465393Y227395D01*
G01X459652Y228740D02*
X458307Y227395D01*
G01X452565Y228740D02*
X451220Y227395D01*
G01X445478Y228740D02*
X444133Y227395D01*
G01X438392Y228740D02*
X437047Y227395D01*
G01X431305Y228740D02*
X429960Y227395D01*
G01X424219Y228740D02*
X422874Y227395D01*
G01X471260Y225415D02*
X472372Y228425D01*
G01X471822Y228533D02*
X471260Y227011D01*
G01X459237Y228425D02*
X458025Y225146D01*
G01X457661Y225280D02*
X458863Y228533D01*
G01X458653D02*
X457451Y225280D01*
G01X457087Y225415D02*
X458199Y228425D01*
G01X457451Y226877D02*
X458012Y228394D01*
G01X457649Y228533D02*
X457087Y227011D01*
G01X445064Y228425D02*
X443852Y225146D01*
G01X443488Y225280D02*
X444690Y228533D01*
G01X444480D02*
X443278Y225280D01*
G01X442913Y225415D02*
X444026Y228425D01*
G01X443278Y226877D02*
X443839Y228394D01*
G01X443476Y228533D02*
X442914Y227011D01*
G01X430891Y228425D02*
X429679Y225146D01*
G01X429315Y225280D02*
X430517Y228533D01*
G01X430307D02*
X429104Y225280D01*
G01X428740Y225415D02*
X429853Y228425D01*
G01X429105Y226877D02*
X429665Y228394D01*
G01X429303Y228533D02*
X428740Y227011D01*
G01X467704Y202247D02*
X467523Y201218D01*
G01X467135Y201496D02*
X467316Y202525D01*
G01X453531Y202247D02*
X453349Y201218D01*
G01X452962Y201496D02*
X453143Y202525D01*
G01X439358Y202247D02*
X439176Y201218D01*
G01X438788Y201496D02*
X438970Y202525D01*
G01X470998Y226371D02*
Y226338D01*
G01X470610D02*
X470611Y226378D01*
G01X471115Y202247D02*
Y224607D01*
G01X468899Y201043D02*
Y200151D01*
G01X471297Y201218D02*
X471115Y202247D01*
G01X457330Y202525D02*
X457511Y201496D01*
G01X457123Y201218D02*
X456942Y202247D01*
G01X425184D02*
X425003Y201218D01*
G01X424615Y201496D02*
X424797Y202525D01*
G01X456825Y226371D02*
Y226338D01*
G01X456437D02*
Y226378D01*
G01X442652Y226371D02*
Y226338D01*
G01X442264D02*
Y226378D01*
G01X428479Y226371D02*
X428478Y226338D01*
G01X428091D02*
Y226378D01*
G01X457927Y200939D02*
X457929Y201241D01*
G01X443753Y200939D02*
X443755Y201241D01*
G01X429580Y200939D02*
X429582Y201241D01*
G01X467704Y202247D02*
Y224607D01*
G01X467316Y202525D02*
Y224607D01*
G01X467105D02*
Y201241D01*
G01X466717Y224607D02*
Y201241D01*
G01X466662Y228740D02*
Y228425D01*
G01X466447D02*
Y228740D01*
G01X465409D02*
Y228425D01*
G01X465262Y228740D02*
Y220866D01*
G01X464573Y225787D02*
Y201804D01*
G01X460734Y220866D02*
Y228740D01*
G01X460374D02*
Y220866D01*
G01X459237Y228425D02*
Y228740D01*
G01X458199Y228425D02*
Y228740D01*
G01X458012D02*
Y220866D01*
G01X457929Y201241D02*
Y224607D01*
G01X457541Y201241D02*
Y224607D01*
G01X457330D02*
Y202525D01*
G01X456942Y202247D02*
Y224607D01*
G01X453531Y202247D02*
Y224607D01*
G01X453143Y202525D02*
Y224607D01*
G01X452932D02*
Y201241D01*
G01X452544Y224607D02*
Y201241D01*
G01X452489Y228740D02*
Y228425D01*
G01X452274D02*
Y228740D01*
G01X451235D02*
Y228425D01*
G01X451089Y228740D02*
Y220866D01*
G01X450400Y225787D02*
Y201804D01*
G01X446561Y220866D02*
Y228740D01*
G01X446201D02*
Y220866D01*
G01X445064Y228425D02*
Y228740D01*
G01X444026Y228425D02*
Y228740D01*
G01X443839D02*
Y220866D01*
G01X443756Y201241D02*
Y224607D01*
G01X443368Y201241D02*
Y224607D01*
G01X443156D02*
Y202525D01*
G01X442769Y202247D02*
Y224607D01*
G01X439358Y202247D02*
Y224607D01*
G01X438970Y202525D02*
Y224607D01*
G01X438758D02*
Y201241D01*
G01X438371Y224607D02*
Y201241D01*
G01X438315Y228740D02*
Y228425D01*
G01X438100D02*
Y228740D01*
G01X437062D02*
Y228425D01*
G01X436915Y228740D02*
Y220866D01*
G01X436227Y225787D02*
Y201804D01*
G01X432388Y220866D02*
Y228740D01*
G01X432028D02*
Y220866D01*
G01X430891Y228425D02*
Y228740D01*
G01X429853Y228425D02*
Y228740D01*
G01X429665D02*
Y220866D01*
G01X429582Y201241D02*
Y224607D01*
G01X429195Y201241D02*
Y224607D01*
G01X428983Y202525D02*
Y224607D01*
G01X428595Y202247D02*
Y224607D01*
G01X467860Y226371D02*
Y226338D01*
G01X453687Y226371D02*
Y226338D01*
G01X439514Y226371D02*
Y226338D01*
G01X468248Y226378D02*
Y226338D01*
G01X454075Y226378D02*
Y226338D01*
G01X439901Y226378D02*
X439902Y226338D01*
G01X443156Y202525D02*
X443338Y201496D01*
G01X442950Y201218D02*
X442769Y202247D01*
G01X428983Y202525D02*
X429165Y201496D01*
G01X428777Y201218D02*
X428595Y202247D01*
G01X467599Y227011D02*
X467036Y228533D01*
G01X466662Y228425D02*
X467234Y226876D01*
G01X466447Y228425D02*
X467559Y225415D01*
G01X467195Y225280D02*
X465993Y228533D01*
G01X465783D02*
X466985Y225280D01*
G01X466621Y225146D02*
X465409Y228425D01*
G01X453425Y227011D02*
X452863Y228533D01*
G01X452489Y228425D02*
X453061Y226876D01*
G01X452274Y228425D02*
X453386Y225415D01*
G01X453022Y225280D02*
X451820Y228533D01*
G01X451610D02*
X452812Y225280D01*
G01X452447Y225146D02*
X451235Y228425D01*
G01X439252Y227011D02*
X438690Y228533D01*
G01X438315Y228425D02*
X438888Y226876D01*
G01X438100Y228425D02*
X439213Y225415D01*
G01X438849Y225280D02*
X437646Y228533D01*
G01X437436D02*
X438638Y225280D01*
G01X438274Y225146D02*
X437062Y228425D01*
G01X425184Y202247D02*
Y224607D01*
G01X424797Y202525D02*
Y224607D01*
G01X424585D02*
Y201241D01*
G01X424197Y224607D02*
Y201241D01*
G01X424142Y228425D02*
Y228740D01*
G01X423927Y228425D02*
Y228740D01*
G01X422889D02*
Y228425D01*
G01X422742Y228740D02*
Y220866D01*
G01X425341Y226371D02*
Y226338D01*
G01X425728Y226378D02*
X425729Y226338D01*
G01X425079Y227011D02*
X424516Y228533D01*
G01X424142Y228425D02*
X424715Y226876D01*
G01X423927Y228425D02*
X425040Y225415D01*
G01X424675Y225280D02*
X423473Y228533D01*
G01X423263D02*
X424465Y225280D01*
G01X424101Y225146D02*
X422889Y228425D01*
G01X467919Y228740D02*
X469265Y227395D01*
G01X460833Y228740D02*
X462178Y227395D01*
G01X455091D02*
X453746Y228740D01*
G01X448005Y227395D02*
X446660Y228740D01*
G01X440918Y227395D02*
X439573Y228740D01*
G01X433831Y227395D02*
X432486Y228740D01*
G01X426745Y227395D02*
X425400Y228740D01*
G01X419658Y227395D02*
X418313Y228740D01*
G01X471260Y227011D02*
X471624Y226876D01*
G01Y225280D02*
X471260Y225415D01*
G01X457087Y227011D02*
X457451Y226876D01*
G01X458025Y225146D02*
X457661Y225280D01*
G01X457451D02*
X457087Y225415D01*
G01X442914Y227011D02*
X443278Y226876D01*
G01X443852Y225146D02*
X443488Y225280D01*
G01X443278D02*
X442913Y225415D01*
G01X428740Y227011D02*
X429105Y226876D01*
G01X429315Y225280D02*
X429679Y225146D01*
G01X429104Y225280D02*
X428740Y225415D01*
G01X458863Y228533D02*
X459237Y228425D01*
G01X457649Y228533D02*
X458012Y228429D01*
G01X444690Y228533D02*
X445064Y228425D01*
G01X443476Y228533D02*
X443839Y228429D01*
G01X430517Y228533D02*
X430891Y228425D01*
G01X429303Y228533D02*
X429665Y228429D01*
G01X470611Y226378D02*
X470998Y226371D01*
G01X456437Y226378D02*
X456825Y226371D01*
G01X442264Y226378D02*
X442652Y226371D01*
G01X428091Y226378D02*
X428479Y226371D01*
G01X417329Y228740D02*
X473628D01*
G01X424516Y228533D02*
X424873D01*
G01X467036D02*
X467392D01*
G01X457293D02*
X457649D01*
G01X452863D02*
X453219D01*
G01X443120D02*
X443476D01*
G01X438690D02*
X439046D01*
G01X428947D02*
X429303D01*
G01X423473D02*
X423263D01*
G01X430517D02*
X430307D01*
G01X437646D02*
X437436D01*
G01X444690D02*
X444480D01*
G01X451820D02*
X451610D01*
G01X458863D02*
X458653D01*
G01X465993D02*
X465783D01*
G01X417329Y228425D02*
X429853D01*
G01X444026D02*
X430891D01*
G01X458199D02*
X445064D01*
G01X472372D02*
X459237D01*
G01X422742Y228252D02*
X417329D01*
G01X432028D02*
X429665D01*
G01X436915D02*
X432388D01*
G01X446201D02*
X443839D01*
G01X451089D02*
X446561D01*
G01X465262D02*
X460734D01*
G01X460374D02*
X458012D01*
G01X422874Y227395D02*
X419658D01*
G01X429960D02*
X425144D01*
G01X437047D02*
X433831D01*
G01X444133D02*
X439317D01*
G01X451220D02*
X448005D01*
G01X458307D02*
X453490D01*
G01X465393D02*
X462178D01*
G01X471889D02*
X467663D01*
G01X471100Y227011D02*
X471260D01*
G01X456927D02*
X457087D01*
G01X442754D02*
X442914D01*
G01X428580D02*
X428740D01*
G01X425239D02*
X425079D01*
G01X439412D02*
X439252D01*
G01X453585D02*
X453425D01*
G01X467758D02*
X467599D01*
G01X470610Y226338D02*
X471528D01*
G01X467331D02*
X468248D01*
G01X456437D02*
X457355D01*
G01X453157D02*
X454075D01*
G01X442264D02*
X443181D01*
G01X438984D02*
X439902D01*
G01X428091D02*
X429008D01*
G01X424811D02*
X425729D01*
G01X436227Y225787D02*
X432301D01*
G01X450400D02*
X446474D01*
G01X464573D02*
X460647D01*
G01X424675Y225280D02*
X424465D01*
G01X438849D02*
X438638D01*
G01X453022D02*
X452812D01*
G01X457661D02*
X457451D01*
G01X429315D02*
X429104D01*
G01X443488D02*
X443278D01*
G01X467195D02*
X466985D01*
G01X466717Y224607D02*
X467704D01*
G01X456942D02*
X457929D01*
G01X452544D02*
X453531D01*
G01X442769D02*
X443756D01*
G01X438371D02*
X439358D01*
G01X428595D02*
X429582D01*
G01X424197D02*
X425184D01*
G01X472102D02*
X471115D01*
G01X422742Y220866D02*
X417329D01*
G01X432028D02*
X429665D01*
G01X436915D02*
X432388D01*
G01X446201D02*
X443839D01*
G01X451089D02*
X446561D01*
G01X465262D02*
X460734D01*
G01X460374D02*
X458012D01*
G01X425728Y226378D02*
X425341Y226371D01*
G01X439901Y226378D02*
X439514Y226371D01*
G01X454075Y226378D02*
X453687Y226371D01*
G01X468248Y226378D02*
X467860Y226371D01*
G01X429853Y228425D02*
X430230Y228514D01*
G01X444026Y228425D02*
X444403Y228514D01*
G01X458199Y228425D02*
X458576Y228514D01*
G01X430230D02*
X430307Y228533D01*
G01X444403Y228514D02*
X444480Y228533D01*
G01X458576Y228514D02*
X458653Y228533D01*
G01X467316Y202525D02*
X471503D01*
G01X453143D02*
X457330D01*
G01X438970D02*
X443156D01*
G01X424797D02*
X428983D01*
G01X428595Y202247D02*
X425184D01*
G01X442769D02*
X439358D01*
G01X456942D02*
X453531D01*
G01X471115D02*
X467704D01*
G01X419438Y201804D02*
X422729D01*
G01X417818D02*
X417329D01*
G01X437048D02*
X433465D01*
G01X451221D02*
X447639D01*
G01X465395D02*
X461812D01*
G01X457541Y201241D02*
X457929D01*
G01X443368D02*
X443756D01*
G01X429195D02*
X429582D01*
G01X424585D02*
X424197D01*
G01X438758D02*
X438371D01*
G01X452932D02*
X452544D01*
G01X467105D02*
X466717D01*
G01X467523Y201218D02*
X471297D01*
G01X453349D02*
X457123D01*
G01X439176D02*
X442950D01*
G01X425003D02*
X428777D01*
G01X429962Y201043D02*
X426379D01*
G01X444135D02*
X440552D01*
G01X458308D02*
X454725D01*
G01X472481D02*
X468899D01*
G01X466719Y200939D02*
X472100D01*
G01X452546D02*
X457926D01*
G01X438373D02*
X443753D01*
G01X424200D02*
X429580D01*
G01X429765Y200623D02*
X426576D01*
G01X443938D02*
X440749D01*
G01X458111D02*
X454922D01*
G01X472284D02*
X469095D01*
G01X468899Y200374D02*
X472481D01*
G01X469044Y199961D02*
X472336D01*
G01X416142Y316929D02*
G03X408268I-3937J0D01*
G01X416142D02*
G03X408268I-3937J0D01*
G01X416142Y347638D02*
Y690803D01*
G01X408268Y347638D02*
G03X416142I3937J0D01*
G01X408268D02*
G03X416142I3937J0D01*
G01Y721512D02*
Y723481D01*
G01Y723482D02*
G03X414894Y728764I-11811J-2D01*
G01X408268Y723480D02*
G03X407852Y725241I-3937J0D01*
G01X408268Y721512D02*
G03X416142I3937J0D01*
G01Y690803D02*
G03X408268I-3937J0D01*
G01Y721512D02*
G03X416142I3937J0D01*
G01Y690803D02*
G03X408268I-3937J0D01*
G01X435970Y763780D02*
X572622D01*
G01X432033D02*
X430688D01*
G01X432033D02*
X433706D01*
G01X463528Y762380D02*
Y765180D01*
G01X432033Y762380D02*
Y765180D01*
G01X428096Y763780D02*
G03X435970I3937J0D01*
G01X483800Y137224D02*
G03X493878I5039J0D01*
G01X497622Y122163D02*
X497697Y122539D01*
G01X497409Y121843D02*
X497622Y122163D01*
G01X497090Y121630D02*
X497409Y121843D01*
G01X496713Y121555D02*
X497090Y121630D01*
G01X480055Y128822D02*
X479980Y128445D01*
G01X480269Y129141D02*
X480055Y128822D01*
G01X480588Y129354D02*
X480269Y129141D01*
G01X480965Y129429D02*
X480588Y129354D01*
G01X497448Y122542D02*
X497473Y122763D01*
G01X497375Y122335D02*
X497448Y122542D01*
G01X497258Y122149D02*
X497375Y122335D01*
G01X497101Y121992D02*
X497258Y122149D01*
G01X496914Y121875D02*
X497101Y121992D01*
G01X496707Y121803D02*
X496914Y121875D01*
G01X496489Y121779D02*
X496707Y121803D01*
G01X488274Y132039D02*
X487992Y132042D01*
G01X488556Y132037D02*
X488274Y132039D01*
G01X489121Y132037D02*
X488556D01*
G01X480229Y122542D02*
X480204Y122763D01*
G01X480302Y122335D02*
X480229Y122542D01*
G01X480419Y122149D02*
X480302Y122335D01*
G01X480577Y121992D02*
X480419Y122149D01*
G01X480763Y121875D02*
X480577Y121992D01*
G01X480970Y121803D02*
X480763Y121875D01*
G01X481188Y121779D02*
X480970Y121803D01*
G01X497448Y128442D02*
X497473Y128221D01*
G01X497375Y128649D02*
X497448Y128442D01*
G01X497258Y128835D02*
X497375Y128649D01*
G01X497101Y128992D02*
X497258Y128835D01*
G01X496914Y129109D02*
X497101Y128992D01*
G01X496707Y129181D02*
X496914Y129109D01*
G01X496489Y129205D02*
X496707Y129181D01*
G01X479522Y122058D02*
X479603Y121821D01*
G01X479393Y122273D02*
X479522Y122058D01*
G01X479224Y122459D02*
X479393Y122273D01*
G01X479023Y122614D02*
X479224Y122459D01*
G01X478794Y122736D02*
X479023Y122614D01*
G01X500781Y122058D02*
X500862Y121821D01*
G01X500653Y122273D02*
X500781Y122058D01*
G01X500484Y122459D02*
X500653Y122273D01*
G01X500282Y122614D02*
X500484Y122459D01*
G01X500054Y122736D02*
X500282Y122614D01*
G01X472516Y121385D02*
X472545Y121021D01*
G01X472433Y121735D02*
X472516Y121385D01*
G01X472300Y122056D02*
X472433Y121735D01*
G01X472128Y122334D02*
X472300Y122056D01*
G01X471926Y122562D02*
X472128Y122334D01*
G01X471708Y122736D02*
X471926Y122562D01*
G01X479603Y121385D02*
X479632Y121021D01*
G01X479519Y121735D02*
X479603Y121385D01*
G01X479387Y122056D02*
X479519Y121735D01*
G01X479214Y122334D02*
X479387Y122056D01*
G01X479013Y122562D02*
X479214Y122334D01*
G01X478794Y122736D02*
X479013Y122562D01*
G01X486690Y121385D02*
X486719Y121021D01*
G01X486606Y121735D02*
X486690Y121385D01*
G01X486474Y122056D02*
X486606Y121735D01*
G01X486301Y122334D02*
X486474Y122056D01*
G01X486099Y122562D02*
X486301Y122334D01*
G01X485881Y122736D02*
X486099Y122562D01*
G01X493776Y121385D02*
X493805Y121021D01*
G01X493693Y121735D02*
X493776Y121385D01*
G01X493560Y122056D02*
X493693Y121735D01*
G01X493387Y122334D02*
X493560Y122056D01*
G01X493186Y122562D02*
X493387Y122334D01*
G01X492968Y122736D02*
X493186Y122562D01*
G01X500863Y121385D02*
X500892Y121021D01*
G01X500779Y121735D02*
X500863Y121385D01*
G01X500647Y122056D02*
X500779Y121735D01*
G01X500474Y122334D02*
X500647Y122056D01*
G01X500273Y122562D02*
X500474Y122334D01*
G01X500054Y122736D02*
X500273Y122562D01*
G01X507949Y121385D02*
X507978Y121021D01*
G01X507866Y121735D02*
X507949Y121385D01*
G01X507733Y122056D02*
X507866Y121735D01*
G01X507561Y122334D02*
X507733Y122056D01*
G01X507359Y122562D02*
X507561Y122334D01*
G01X507141Y122736D02*
X507359Y122562D01*
G01X515036Y121385D02*
X515065Y121021D01*
G01X514952Y121735D02*
X515036Y121385D01*
G01X514820Y122056D02*
X514952Y121735D01*
G01X514647Y122334D02*
X514820Y122056D01*
G01X514446Y122562D02*
X514647Y122334D01*
G01X514228Y122736D02*
X514446Y122562D01*
G01X522123Y121385D02*
X522152Y121021D01*
G01X522039Y121735D02*
X522123Y121385D01*
G01X521907Y122056D02*
X522039Y121735D01*
G01X521734Y122334D02*
X521907Y122056D01*
G01X521532Y122562D02*
X521734Y122334D01*
G01X521314Y122736D02*
X521532Y122562D01*
G01X529209Y121385D02*
X529238Y121021D01*
G01X529126Y121735D02*
X529209Y121385D01*
G01X528993Y122056D02*
X529126Y121735D01*
G01X528820Y122334D02*
X528993Y122056D01*
G01X528619Y122562D02*
X528820Y122334D01*
G01X528401Y122736D02*
X528619Y122562D01*
G01X536296Y121385D02*
X536325Y121021D01*
G01X536212Y121735D02*
X536296Y121385D01*
G01X536080Y122056D02*
X536212Y121735D01*
G01X535907Y122334D02*
X536080Y122056D01*
G01X535706Y122562D02*
X535907Y122334D01*
G01X535487Y122736D02*
X535706Y122562D01*
G01X479625Y121716D02*
X479603Y121838D01*
G01X479632Y121593D02*
X479625Y121716D01*
G01X480588Y121630D02*
X480965Y121555D01*
G01X480269Y121843D02*
X480588Y121630D01*
G01X480055Y122163D02*
X480269Y121843D01*
G01X479980Y122539D02*
X480055Y122163D01*
G01X497090Y129354D02*
X496713Y129429D01*
G01X497409Y129141D02*
X497090Y129354D01*
G01X497622Y128822D02*
X497409Y129141D01*
G01X497697Y128445D02*
X497622Y128822D01*
G01X472074Y122514D02*
X471708Y122736D01*
G01X472336Y122234D02*
X472074Y122514D01*
G01X472493Y121920D02*
X472336Y122234D01*
G01X472545Y121593D02*
X472493Y121920D01*
G01X486247Y122514D02*
X485881Y122736D01*
G01X486509Y122234D02*
X486247Y122514D01*
G01X486666Y121920D02*
X486509Y122234D01*
G01X486719Y121593D02*
X486666Y121920D01*
G01X493333Y122514D02*
X492968Y122736D01*
G01X493596Y122234D02*
X493333Y122514D01*
G01X493753Y121920D02*
X493596Y122234D01*
G01X493805Y121593D02*
X493753Y121920D01*
G01X507507Y122514D02*
X507141Y122736D01*
G01X507769Y122234D02*
X507507Y122514D01*
G01X507926Y121920D02*
X507769Y122234D01*
G01X507978Y121593D02*
X507926Y121920D01*
G01X500884Y121716D02*
X500862Y121838D01*
G01X500892Y121593D02*
X500884Y121716D01*
G01X487990Y132178D02*
X487992Y132042D01*
G01X487989Y132313D02*
X487990Y132178D01*
G01X489687D02*
X489686Y132042D01*
G01X489688Y132313D02*
X489687Y132178D01*
G01X489689Y133724D02*
X489688Y132313D01*
G01X476510Y121717D02*
X476532Y121838D01*
G01X476502Y121593D02*
X476510Y121717D01*
G01X477121Y122562D02*
X477340Y122736D01*
G01X476920Y122334D02*
X477121Y122562D01*
G01X476747Y122056D02*
X476920Y122334D01*
G01X476615Y121735D02*
X476747Y122056D01*
G01X476531Y121385D02*
X476615Y121735D01*
G01X476502Y121021D02*
X476531Y121385D01*
G01X484208Y122562D02*
X484426Y122736D01*
G01X484007Y122334D02*
X484208Y122562D01*
G01X483834Y122056D02*
X484007Y122334D01*
G01X483701Y121735D02*
X483834Y122056D01*
G01X483618Y121385D02*
X483701Y121735D01*
G01X483589Y121021D02*
X483618Y121385D01*
G01X480967Y129180D02*
X481188Y129205D01*
G01X480760Y129107D02*
X480967Y129180D01*
G01X480574Y128990D02*
X480760Y129107D01*
G01X480417Y128833D02*
X480574Y128990D01*
G01X480301Y128647D02*
X480417Y128833D01*
G01X480229Y128439D02*
X480301Y128647D01*
G01X480204Y128221D02*
X480229Y128439D01*
G01X514593Y122514D02*
X514228Y122736D01*
G01X514856Y122234D02*
X514593Y122514D01*
G01X515012Y121920D02*
X514856Y122234D01*
G01X515065Y121593D02*
X515012Y121920D01*
G01X521680Y122514D02*
X521314Y122736D01*
G01X521942Y122234D02*
X521680Y122514D01*
G01X522099Y121920D02*
X521942Y122234D01*
G01X522152Y121593D02*
X522099Y121920D01*
G01X528767Y122514D02*
X528401Y122736D01*
G01X529029Y122234D02*
X528767Y122514D01*
G01X529186Y121920D02*
X529029Y122234D01*
G01X529238Y121593D02*
X529186Y121920D01*
G01X535853Y122514D02*
X535487Y122736D01*
G01X536116Y122234D02*
X535853Y122514D01*
G01X536272Y121920D02*
X536116Y122234D01*
G01X536325Y121593D02*
X536272Y121920D01*
G01X497770Y121717D02*
X497791Y121838D01*
G01X497762Y121593D02*
X497770Y121717D01*
G01X491295Y122562D02*
X491513Y122736D01*
G01X491093Y122334D02*
X491295Y122562D01*
G01X490920Y122056D02*
X491093Y122334D01*
G01X490788Y121735D02*
X490920Y122056D01*
G01X490704Y121385D02*
X490788Y121735D01*
G01X490675Y121021D02*
X490704Y121385D01*
G01X498381Y122562D02*
X498599Y122736D01*
G01X498180Y122334D02*
X498381Y122562D01*
G01X498007Y122056D02*
X498180Y122334D01*
G01X497875Y121735D02*
X498007Y122056D01*
G01X497791Y121385D02*
X497875Y121735D01*
G01X497762Y121021D02*
X497791Y121385D01*
G01X505468Y122562D02*
X505686Y122736D01*
G01X505266Y122334D02*
X505468Y122562D01*
G01X505094Y122056D02*
X505266Y122334D01*
G01X504961Y121735D02*
X505094Y122056D01*
G01X504878Y121385D02*
X504961Y121735D01*
G01X504849Y121021D02*
X504878Y121385D01*
G01X512554Y122562D02*
X512773Y122736D01*
G01X512353Y122334D02*
X512554Y122562D01*
G01X512180Y122056D02*
X512353Y122334D01*
G01X512048Y121735D02*
X512180Y122056D01*
G01X511964Y121385D02*
X512048Y121735D01*
G01X511935Y121021D02*
X511964Y121385D01*
G01X519641Y122562D02*
X519859Y122736D01*
G01X519440Y122334D02*
X519641Y122562D01*
G01X519267Y122056D02*
X519440Y122334D01*
G01X519134Y121735D02*
X519267Y122056D01*
G01X519051Y121385D02*
X519134Y121735D01*
G01X519022Y121021D02*
X519051Y121385D01*
G01X526728Y122562D02*
X526946Y122736D01*
G01X526526Y122334D02*
X526728Y122562D01*
G01X526353Y122056D02*
X526526Y122334D01*
G01X526221Y121735D02*
X526353Y122056D01*
G01X526137Y121385D02*
X526221Y121735D01*
G01X526108Y121021D02*
X526137Y121385D01*
G01X483964Y122429D02*
X484426Y122736D01*
G01X483683Y122029D02*
X483964Y122429D01*
G01X483589Y121593D02*
X483683Y122029D01*
G01X491051Y122429D02*
X491513Y122736D01*
G01X490769Y122029D02*
X491051Y122429D01*
G01X490675Y121593D02*
X490769Y122029D01*
G01X533814Y122562D02*
X534033Y122736D01*
G01X533613Y122334D02*
X533814Y122562D01*
G01X533440Y122056D02*
X533613Y122334D01*
G01X533308Y121735D02*
X533440Y122056D01*
G01X533224Y121385D02*
X533308Y121735D01*
G01X533195Y121021D02*
X533224Y121385D01*
G01X505224Y122429D02*
X505686Y122736D01*
G01X504943Y122029D02*
X505224Y122429D01*
G01X504849Y121593D02*
X504943Y122029D01*
G01X512311Y122429D02*
X512773Y122736D01*
G01X512029Y122029D02*
X512311Y122429D01*
G01X511935Y121593D02*
X512029Y122029D01*
G01X519397Y122429D02*
X519859Y122736D01*
G01X519116Y122029D02*
X519397Y122429D01*
G01X519022Y121593D02*
X519116Y122029D01*
G01X526484Y122429D02*
X526946Y122736D01*
G01X526203Y122029D02*
X526484Y122429D01*
G01X526108Y121593D02*
X526203Y122029D01*
G01X533571Y122429D02*
X534033Y122736D01*
G01X533289Y122029D02*
X533571Y122429D01*
G01X533195Y121593D02*
X533289Y122029D01*
G01X477114Y122615D02*
X477340Y122736D01*
G01X476913Y122461D02*
X477114Y122615D01*
G01X476743Y122276D02*
X476913Y122461D01*
G01X476614Y122060D02*
X476743Y122276D01*
G01X476532Y121821D02*
X476614Y122060D01*
G01X498374Y122615D02*
X498599Y122736D01*
G01X498173Y122461D02*
X498374Y122615D01*
G01X498003Y122276D02*
X498173Y122461D01*
G01X497874Y122060D02*
X498003Y122276D01*
G01X497791Y121821D02*
X497874Y122060D01*
G01X535748Y130709D02*
G03I-709J0D01*
G01Y126378D02*
G03I-709J0D01*
G01X528661Y131496D02*
G03I-708J0D01*
G01X514488D02*
G03I-709J0D01*
G01Y125984D02*
G03I-709J0D01*
G01Y121654D02*
G03I-709J0D01*
G01X521575Y130709D02*
G03I-709J0D01*
G01Y126378D02*
G03I-709J0D01*
G01X528661Y125984D02*
G03I-708J0D01*
G01Y121654D02*
G03I-708J0D01*
G01X514232Y122745D02*
G03X512768I-732J-1394D01*
G01X521319D02*
G03X519855I-732J-1394D01*
G01X528405D02*
G03X526941I-732J-1394D01*
G01X535492D02*
G03X534028I-732J-1394D01*
G01X492530Y137224D02*
G03I-3691J0D01*
G01X493139D02*
G03I-4300J0D01*
G01X493268D02*
G03I-4429J0D01*
G01X484071Y136376D02*
G03X487990Y132457I4768J849D01*
G01X489687D02*
G03X493606Y136376I-848J4767D01*
G01X493858Y137224D02*
G03I-5019J0D01*
G01X497189D02*
G03I-8350J0D01*
G01X507401Y130709D02*
G03I-708J0D01*
G01Y126378D02*
G03I-708J0D01*
G01X492972Y122745D02*
G03X491508I-732J-1394D01*
G01X500059D02*
G03X498595I-732J-1394D01*
G01X507146D02*
G03X505681I-732J-1394D01*
G01X478799D02*
G03X477335I-732J-1394D01*
G01X485886D02*
G03X484422I-732J-1394D01*
G01X507949Y115256D02*
X506768Y114075D01*
G01X500862Y115256D02*
X499681Y114075D01*
G01X497697Y128445D02*
X497473Y128221D01*
G01X496489Y129205D02*
X496713Y129429D01*
G01X479603Y115256D02*
X478421Y114075D01*
G01X481188Y121779D02*
X480965Y121555D01*
G01X479980Y122539D02*
X480204Y122763D01*
G01X490659Y135404D02*
X489689Y133724D01*
G01X487989D02*
X489689Y140724D01*
G01X487992Y132042D02*
X489686Y142407D01*
G01X536325Y121593D02*
Y115650D01*
G01X533195Y121593D02*
Y115650D01*
G01X529238Y121593D02*
Y115650D01*
G01X526108Y121593D02*
Y115650D01*
G01X522152Y121593D02*
Y115650D01*
G01X519022Y121593D02*
Y115650D01*
G01X515065Y121593D02*
Y115650D01*
G01X511935Y121593D02*
Y115650D01*
G01X482909Y187911D02*
X481689Y118012D01*
G01X481925Y187911D02*
X480705Y118012D01*
G01X507978Y121593D02*
Y115650D01*
G01X507949Y115256D02*
Y118012D01*
G01X504878D02*
Y115256D01*
G01X504849Y121593D02*
Y115650D01*
G01X502857Y201804D02*
Y113091D01*
G01X501516D02*
Y209646D01*
G01X500892Y121593D02*
Y115650D01*
G01X500862Y125886D02*
Y115256D01*
G01X497791D02*
Y125886D01*
G01X497762Y115650D02*
Y121593D01*
G01X497697Y122539D02*
Y128445D01*
G01X497473Y122763D02*
Y128221D01*
G01X496489Y121779D02*
Y129205D01*
G01X493805Y121593D02*
Y115650D01*
G01X490675D02*
Y121593D01*
G01X487989Y133724D02*
Y132313D01*
G01X486719Y121593D02*
Y115650D01*
G01X483589D02*
Y121593D01*
G01X481188Y121779D02*
Y129205D01*
G01X480204Y128221D02*
Y122763D01*
G01X479980Y128445D02*
Y122539D01*
G01X479632Y121593D02*
Y115650D01*
G01X479603Y125886D02*
Y115256D01*
G01X476532D02*
Y125886D01*
G01X476502Y115650D02*
Y121593D01*
G01X475138Y209646D02*
Y113091D01*
G01X473956Y201804D02*
Y113091D01*
G01X472545Y121593D02*
Y115650D01*
G01X472516Y118012D02*
Y115256D01*
G01X495233Y187911D02*
X496453Y118012D01*
G01X495469D02*
X494249Y187911D01*
G01X489686Y132042D02*
X487992Y142407D01*
G01X489689Y133724D02*
X487989Y140724D01*
G01Y133724D02*
X487019Y135404D01*
G01X497473Y122763D02*
X497697Y122539D01*
G01X504878Y115256D02*
X506059Y114075D01*
G01X496713Y121555D02*
X496489Y121779D01*
G01X497791Y115256D02*
X498973Y114075D01*
G01X480965Y129429D02*
X481188Y129205D01*
G01X480204Y128221D02*
X479980Y128445D01*
G01X476532Y115256D02*
X477713Y114075D01*
G01X496713Y129429D02*
X480965D01*
G01X496489Y129205D02*
X481188D01*
G01X480204Y128221D02*
X497473D01*
G01X558995Y126536D02*
X502857D01*
G01X500862Y125886D02*
X501516D01*
G01X479603D02*
X497791D01*
G01X475138D02*
X476532D01*
G01X497473Y122763D02*
X480204D01*
G01X500054Y122736D02*
X505686D01*
G01X492968D02*
X498599D01*
G01X478794D02*
X484426D01*
G01X471708D02*
X477340D01*
G01X491513D02*
X485881D01*
G01X512773D02*
X507141D01*
G01X519859D02*
X514228D01*
G01X526946D02*
X521314D01*
G01X534033D02*
X528401D01*
G01X541119D02*
X535487D01*
G01X496489Y121779D02*
X481188D01*
G01X480965Y121555D02*
X496713D01*
G01X558995Y120492D02*
X502857D01*
G01X558995Y120020D02*
X502857D01*
G01X476502Y118084D02*
X475138D01*
G01X483589D02*
X479632D01*
G01X490675D02*
X486719D01*
G01X497762D02*
X493805D01*
G01X501516D02*
X500892D01*
G01X501516Y116437D02*
X475138D01*
G01X558995D02*
X502857D01*
G01X479603Y115256D02*
X476532D01*
G01X500862D02*
X497791D01*
G01X507949D02*
X504878D01*
G01X477713Y114075D02*
X478421D01*
G01X499681D02*
X498973D01*
G01X506768D02*
X506059D01*
G01X475138Y113091D02*
X501516D01*
G01X558995D02*
X502857D01*
G01X489686Y132042D02*
X489121Y132037D01*
G01X493563Y164744D02*
G03X484115I-4724J0D01*
G01D02*
G03X493563I4724J0D01*
G01X493878Y137224D02*
G03X483800I-5039J0D01*
G01X497622Y146178D02*
X497697Y146555D01*
G01X497409Y145859D02*
X497622Y146178D01*
G01X497090Y145646D02*
X497409Y145859D01*
G01X496713Y145571D02*
X497090Y145646D01*
G01X480055Y152837D02*
X479980Y152461D01*
G01X480269Y153157D02*
X480055Y152837D01*
G01X480588Y153370D02*
X480269Y153157D01*
G01X480965Y153445D02*
X480588Y153370D01*
G01X497448Y146558D02*
X497473Y146779D01*
G01X497375Y146351D02*
X497448Y146558D01*
G01X497258Y146165D02*
X497375Y146351D01*
G01X497101Y146008D02*
X497258Y146165D01*
G01X496914Y145891D02*
X497101Y146008D01*
G01X496707Y145819D02*
X496914Y145891D01*
G01X496489Y145795D02*
X496707Y145819D01*
G01X480229Y152458D02*
X480204Y152237D01*
G01X480302Y152665D02*
X480229Y152458D01*
G01X480419Y152851D02*
X480302Y152665D01*
G01X480577Y153008D02*
X480419Y152851D01*
G01X480763Y153125D02*
X480577Y153008D01*
G01X480970Y153197D02*
X480763Y153125D01*
G01X481188Y153221D02*
X480970Y153197D01*
G01X493886Y136376D02*
X493750Y136375D01*
G01X494021Y136377D02*
X493886Y136376D01*
G01X483792Y138073D02*
X483656Y138072D01*
G01X483928Y138074D02*
X483792Y138073D01*
G01X489404Y142410D02*
X489686Y142407D01*
G01X489121Y142411D02*
X489404Y142410D01*
G01X488556Y142411D02*
X489121D01*
G01X483928Y136375D02*
X485339Y136374D01*
G01X483792Y136376D02*
X483928Y136375D01*
G01X483656Y136377D02*
X483792Y136376D01*
G01X493750Y138074D02*
X492339D01*
G01X493886Y138073D02*
X493750Y138074D01*
G01X494021Y138072D02*
X493886Y138073D01*
G01X497448Y152458D02*
X497473Y152237D01*
G01X497375Y152665D02*
X497448Y152458D01*
G01X497258Y152851D02*
X497375Y152665D01*
G01X497101Y153008D02*
X497258Y152851D01*
G01X496914Y153125D02*
X497101Y153008D01*
G01X496707Y153197D02*
X496914Y153125D01*
G01X496489Y153221D02*
X496707Y153197D01*
G01X507733Y190749D02*
X507717Y190748D01*
G01X507749Y190751D02*
X507733Y190749D01*
G01X507765Y190755D02*
X507749Y190751D01*
G01X472300Y190749D02*
X472284Y190748D01*
G01X472316Y190751D02*
X472300Y190749D01*
G01X472332Y190754D02*
X472316Y190751D01*
G01X497110Y195194D02*
X497185Y195571D01*
G01X496897Y194875D02*
X497110Y195194D01*
G01X496578Y194662D02*
X496897Y194875D01*
G01X496201Y194587D02*
X496578Y194662D01*
G01X482005Y188282D02*
X481925Y187911D01*
G01X482219Y188596D02*
X482005Y188282D01*
G01X482536Y188805D02*
X482219Y188596D01*
G01X482909Y188878D02*
X482536Y188805D01*
G01X489248Y199225D02*
X489335Y199409D01*
G01X489160Y199061D02*
X489248Y199225D01*
G01X489069Y198919D02*
X489160Y199061D01*
G01X488975Y198798D02*
X489069Y198919D01*
G01X488877Y198700D02*
X488975Y198798D01*
G01X488777Y198629D02*
X488877Y198700D01*
G01X488675Y198586D02*
X488777Y198629D01*
G01X488579Y198573D02*
X488675Y198586D01*
G01X497005Y195505D02*
X497030Y195726D01*
G01X496932Y195298D02*
X497005Y195505D01*
G01X496815Y195112D02*
X496932Y195298D01*
G01X496657Y194955D02*
X496815Y195112D01*
G01X496471Y194838D02*
X496657Y194955D01*
G01X496264Y194766D02*
X496471Y194838D01*
G01X496046Y194742D02*
X496264Y194766D01*
G01X482022Y187917D02*
X482138Y187918D01*
G01X481949Y187914D02*
X482022Y187917D01*
G01X482295Y187918D02*
X482481Y187917D01*
G01X482138Y187918D02*
X482295D01*
G01X495208Y187914D02*
X495233Y187911D01*
G01X495135Y187917D02*
X495208Y187914D01*
G01X495018Y187918D02*
X495135Y187917D01*
G01X479649Y195505D02*
X479624Y195726D01*
G01X479722Y195298D02*
X479649Y195505D01*
G01X479839Y195112D02*
X479722Y195298D01*
G01X479996Y194955D02*
X479839Y195112D01*
G01X480182Y194838D02*
X479996Y194955D01*
G01X480390Y194766D02*
X480182Y194838D01*
G01X480608Y194742D02*
X480390Y194766D01*
G01X517362Y190836D02*
X517334Y190882D01*
G01X517395Y190797D02*
X517362Y190836D01*
G01X517436Y190770D02*
X517395Y190797D01*
G01X517481Y190753D02*
X517436Y190770D01*
G01X517526Y190748D02*
X517481Y190753D01*
G01X531535Y190836D02*
X531507Y190882D01*
G01X531569Y190797D02*
X531535Y190836D01*
G01X531609Y190770D02*
X531569Y190797D01*
G01X531654Y190753D02*
X531609Y190770D01*
G01X531699Y190748D02*
X531654Y190753D01*
G01X488483Y198586D02*
X488381Y198629D01*
G01X488579Y198573D02*
X488483Y198586D01*
G01X495180Y188211D02*
X495233Y187911D01*
G01X495039Y188481D02*
X495180Y188211D01*
G01X494822Y188694D02*
X495039Y188481D01*
G01X494550Y188831D02*
X494822Y188694D01*
G01X494249Y188878D02*
X494550Y188831D01*
G01X509908Y196164D02*
X509850Y196457D01*
G01X510079Y195905D02*
X509908Y196164D01*
G01X510343Y195730D02*
X510079Y195905D01*
G01X510650Y195669D02*
X510343Y195730D01*
G01X524081Y196164D02*
X524024Y196457D01*
G01X524253Y195905D02*
X524081Y196164D01*
G01X524516Y195730D02*
X524253Y195905D01*
G01X524823Y195669D02*
X524516Y195730D01*
G01X510291Y196264D02*
X510238Y196457D01*
G01X510441Y196117D02*
X510291Y196264D01*
G01X510650Y196063D02*
X510441Y196117D01*
G01X504513Y190749D02*
X504528Y190748D01*
G01X504497Y190751D02*
X504513Y190749D01*
G01X504481Y190755D02*
X504497Y190751D01*
G01X524464Y196264D02*
X524411Y196457D01*
G01X524615Y196117D02*
X524464Y196264D01*
G01X524823Y196063D02*
X524615Y196117D01*
G01X504440Y190761D02*
X504481Y190755D01*
G01X504400Y190776D02*
X504440Y190761D01*
G01X504363Y190800D02*
X504400Y190776D01*
G01X504332Y190833D02*
X504363Y190800D01*
G01X484545Y198803D02*
X484596Y198922D01*
G01X484490Y198705D02*
X484545Y198803D01*
G01X484430Y198634D02*
X484490Y198705D01*
G01X484366Y198589D02*
X484430Y198634D01*
G01X484299Y198573D02*
X484366Y198589D01*
G01X484226Y198585D02*
X484299Y198573D01*
G01X484148Y198626D02*
X484226Y198585D01*
G01X484068Y198698D02*
X484148Y198626D01*
G01X483986Y198795D02*
X484068Y198698D01*
G01X483904Y198916D02*
X483986Y198795D01*
G01X487998Y199061D02*
X487910Y199225D01*
G01X488089Y198919D02*
X487998Y199061D01*
G01X488483Y198586D02*
X488579Y198573D01*
G01X488381Y198629D02*
X488483Y198586D01*
G01X488281Y198700D02*
X488381Y198629D01*
G01X488183Y198798D02*
X488281Y198700D01*
G01X488089Y198919D02*
X488183Y198798D01*
G01X487998Y199061D02*
X488089Y198919D01*
G01X487910Y199225D02*
X487998Y199061D01*
G01X487823Y199409D02*
X487910Y199225D01*
G01X510613Y196270D02*
X510693Y196260D01*
G01X510538Y196288D02*
X510613Y196270D01*
G01X510468Y196312D02*
X510538Y196288D01*
G01X510408Y196343D02*
X510468Y196312D01*
G01X510360Y196378D02*
X510408Y196343D01*
G01X510325Y196417D02*
X510360Y196378D01*
G01X510305Y196457D02*
X510325Y196417D01*
G01X510688Y197005D02*
X510768Y196994D01*
G01X510612Y197022D02*
X510688Y197005D01*
G01X510543Y197047D02*
X510612Y197022D01*
G01X510483Y197078D02*
X510543Y197047D01*
G01X510435Y197113D02*
X510483Y197078D01*
G01X510400Y197151D02*
X510435Y197113D01*
G01X510380Y197191D02*
X510400Y197151D01*
G01X524786Y196270D02*
X524866Y196260D01*
G01X524711Y196288D02*
X524786Y196270D01*
G01X524642Y196312D02*
X524711Y196288D01*
G01X524582Y196343D02*
X524642Y196312D01*
G01X524533Y196378D02*
X524582Y196343D01*
G01X524498Y196417D02*
X524533Y196378D01*
G01X524479Y196457D02*
X524498Y196417D01*
G01X524861Y197005D02*
X524941Y196994D01*
G01X524786Y197022D02*
X524861Y197005D01*
G01X524716Y197047D02*
X524786Y197022D01*
G01X524656Y197078D02*
X524716Y197047D01*
G01X524608Y197113D02*
X524656Y197078D01*
G01X524573Y197151D02*
X524608Y197113D01*
G01X524553Y197191D02*
X524573Y197151D01*
G01X493423Y199226D02*
X493508Y199409D01*
G01X493340Y199064D02*
X493423Y199226D01*
G01X493258Y198923D02*
X493340Y199064D01*
G01X493178Y198803D02*
X493258Y198923D01*
G01X493098Y198706D02*
X493178Y198803D01*
G01X493020Y198634D02*
X493098Y198706D01*
G01X492945Y198590D02*
X493020Y198634D01*
G01X492873Y198573D02*
X492945Y198590D01*
G01X492803Y198585D02*
X492873Y198573D01*
G01X492737Y198626D02*
X492803Y198585D01*
G01X492674Y198697D02*
X492737Y198626D01*
G01X492616Y198794D02*
X492674Y198697D01*
G01X492565Y198915D02*
X492616Y198794D01*
G01X492518Y199058D02*
X492565Y198915D01*
G01X492476Y199223D02*
X492518Y199058D01*
G01X492438Y199409D02*
X492476Y199223D01*
G01X480588Y145646D02*
X480965Y145571D01*
G01X480269Y145859D02*
X480588Y145646D01*
G01X480055Y146178D02*
X480269Y145859D01*
G01X479980Y146555D02*
X480055Y146178D01*
G01X480076Y194662D02*
X480453Y194587D01*
G01X479757Y194875D02*
X480076Y194662D01*
G01X479544Y195194D02*
X479757Y194875D01*
G01X479469Y195571D02*
X479544Y195194D01*
G01X497090Y153370D02*
X496713Y153445D01*
G01X497409Y153157D02*
X497090Y153370D01*
G01X497622Y152837D02*
X497409Y153157D01*
G01X497697Y152461D02*
X497622Y152837D01*
G01X480967Y145820D02*
X481188Y145795D01*
G01X480760Y145893D02*
X480967Y145820D01*
G01X480574Y146010D02*
X480760Y145893D01*
G01X480417Y146167D02*
X480574Y146010D01*
G01X480301Y146353D02*
X480417Y146167D01*
G01X480229Y146561D02*
X480301Y146353D01*
G01X480204Y146779D02*
X480229Y146561D01*
G01X483652Y137507D02*
X483656Y138072D01*
G01X483652Y136942D02*
Y137507D01*
G01X483656Y136377D02*
X483652Y136942D01*
G01X494026D02*
X494021Y136377D01*
G01X494026Y137507D02*
Y136942D01*
G01X494021Y138072D02*
X494026Y137507D01*
G01X489687Y142271D02*
X489686Y142407D01*
G01X489688Y142135D02*
X489687Y142271D01*
G01X487989Y142135D02*
Y140724D01*
G01X487990Y142271D02*
X487989Y142135D01*
G01X487992Y142407D02*
X487990Y142271D01*
G01X511540Y190764D02*
X511615Y190748D01*
G01X511476Y190806D02*
X511540Y190764D01*
G01X511433Y190871D02*
X511476Y190806D01*
G01X511418Y190945D02*
X511433Y190871D01*
G01X518627Y190764D02*
X518702Y190748D01*
G01X518562Y190806D02*
X518627Y190764D01*
G01X518520Y190871D02*
X518562Y190806D01*
G01X518505Y190945D02*
X518520Y190871D01*
G01X525713Y190764D02*
X525788Y190748D01*
G01X525649Y190806D02*
X525713Y190764D01*
G01X525607Y190871D02*
X525649Y190806D01*
G01X525591Y190945D02*
X525607Y190871D01*
G01X532800Y190764D02*
X532875Y190748D01*
G01X532736Y190806D02*
X532800Y190764D01*
G01X532693Y190871D02*
X532736Y190806D01*
G01X532678Y190945D02*
X532693Y190871D01*
G01X510606Y196073D02*
X510693Y196063D01*
G01X510524Y196102D02*
X510606Y196073D01*
G01X510451Y196149D02*
X510524Y196102D01*
G01X510389Y196212D02*
X510451Y196149D01*
G01X510343Y196287D02*
X510389Y196212D01*
G01X510315Y196369D02*
X510343Y196287D01*
G01X510305Y196457D02*
X510315Y196369D01*
G01X524779Y196073D02*
X524866Y196063D01*
G01X524698Y196102D02*
X524779Y196073D01*
G01X524624Y196149D02*
X524698Y196102D01*
G01X524562Y196212D02*
X524624Y196149D01*
G01X524517Y196287D02*
X524562Y196212D01*
G01X524488Y196369D02*
X524517Y196287D01*
G01X524479Y196457D02*
X524488Y196369D01*
G01X509621Y201043D02*
X509620Y196457D01*
G01X523794Y201043D02*
Y196457D01*
G01X514880Y190764D02*
X514804Y190748D01*
G01X514944Y190806D02*
X514880Y190764D01*
G01X514986Y190871D02*
X514944Y190806D01*
G01X515001Y190945D02*
X514986Y190871D01*
G01X483980Y198803D02*
X483899Y198922D01*
G01X484060Y198705D02*
X483980Y198803D01*
G01X484138Y198634D02*
X484060Y198705D01*
G01X484213Y198589D02*
X484138Y198634D01*
G01X484285Y198573D02*
X484213Y198589D01*
G01X484355Y198585D02*
X484285Y198573D01*
G01X484422Y198626D02*
X484355Y198585D01*
G01X484484Y198698D02*
X484422Y198626D01*
G01X484541Y198795D02*
X484484Y198698D01*
G01X484593Y198916D02*
X484541Y198795D01*
G01X484641Y199064D02*
X484593Y198916D01*
G01X521966Y190764D02*
X521891Y190748D01*
G01X522030Y190806D02*
X521966Y190764D01*
G01X522073Y190871D02*
X522030Y190806D01*
G01X522088Y190945D02*
X522073Y190871D01*
G01X529053Y190764D02*
X528977Y190748D01*
G01X529117Y190806D02*
X529053Y190764D01*
G01X529160Y190871D02*
X529117Y190806D01*
G01X529174Y190945D02*
X529160Y190871D01*
G01X536139Y190764D02*
X536064Y190748D01*
G01X536204Y190806D02*
X536139Y190764D01*
G01X536246Y190871D02*
X536204Y190806D01*
G01X536261Y190945D02*
X536246Y190871D01*
G01X493340Y199064D02*
X493423Y199226D01*
G01X493258Y198922D02*
X493340Y199064D01*
G01X521975Y190766D02*
X521891Y190748D01*
G01X522039Y190815D02*
X521975Y190766D01*
G01X522083Y190882D02*
X522039Y190815D01*
G01X536149Y190766D02*
X536064Y190748D01*
G01X536212Y190815D02*
X536149Y190766D01*
G01X536256Y190882D02*
X536212Y190815D01*
G01X507806Y190761D02*
X507765Y190755D01*
G01X507846Y190776D02*
X507806Y190761D01*
G01X507883Y190800D02*
X507846Y190776D01*
G01X507914Y190833D02*
X507883Y190800D01*
G01X472372Y190761D02*
X472331Y190754D01*
G01X472413Y190776D02*
X472372Y190761D01*
G01X472450Y190800D02*
X472413Y190776D01*
G01X472481Y190833D02*
X472450Y190800D01*
G01X533584Y196063D02*
G03X533190Y195669I0J-394D01*
G01X535749D02*
G03X535355Y196063I-394J0D01*
G01X535748Y183071D02*
G03I-709J0D01*
G01Y178740D02*
G03I-709J0D01*
G01Y173228D02*
G03I-709J0D01*
G01Y168898D02*
G03I-709J0D01*
G01X509608Y196457D02*
G03X510002Y196063I394J0D01*
G01X523781Y196457D02*
G03X524175Y196063I394J0D01*
G01X519410D02*
G03X519017Y195669I0J-393D01*
G01X521576D02*
G03X521182Y196063I-394J0D01*
G01X512324D02*
G03X511930Y195669I0J-394D01*
G01X514489D02*
G03X514095Y196063I-394J0D01*
G01X526497D02*
G03X526103Y195669I0J-394D01*
G01X528662D02*
G03X528269Y196063I-394J0D01*
G01X521575Y183071D02*
G03I-709J0D01*
G01X509254Y196457D02*
G03X510002Y195709I748J0D01*
G01X523427Y196457D02*
G03X524175Y195709I748J0D01*
G01X514488Y174016D02*
G03I-709J0D01*
G01Y168504D02*
G03I-709J0D01*
G01X521575Y178740D02*
G03I-709J0D01*
G01Y173228D02*
G03I-709J0D01*
G01X528661Y174016D02*
G03I-708J0D01*
G01Y168504D02*
G03I-708J0D01*
G01X521575Y168898D02*
G03I-709J0D01*
G01X507403Y195669D02*
G03X507009Y196063I-394J0D01*
G01X505237D02*
G03X504843Y195669I0J-394D01*
G01X507401Y183071D02*
G03I-708J0D01*
G01X495233Y187911D02*
G03X494249Y188878I-984J-17D01*
G01X507401Y178740D02*
G03I-708J0D01*
G01Y173228D02*
G03I-708J0D01*
G01Y168898D02*
G03I-708J0D01*
G01X507949Y165420D02*
G03Y167200I-1299J890D01*
G01Y172743D02*
G03Y174523I-1299J890D01*
G01X504878D02*
G03Y172743I1299J-890D01*
G01Y167200D02*
G03Y165420I1299J-890D01*
G01X471969Y195669D02*
G03X471576Y196063I-394J0D01*
G01X482909Y188878D02*
G03X481925Y187911I0J-984D01*
G01X472516Y173164D02*
G03Y174944I-1299J890D01*
G01Y165841D02*
G03Y167621I-1299J890D01*
G01X528661Y164173D02*
G03I-708J0D01*
G01Y159843D02*
G03I-708J0D01*
G01X535748Y164567D02*
G03I-709J0D01*
G01X533185Y160650D02*
G03X536335I1575J0D01*
G01X526099D02*
G03X529248I1574J0D01*
G01X535748Y159055D02*
G03I-709J0D01*
G01Y154724D02*
G03I-709J0D01*
G01X514488Y164173D02*
G03I-709J0D01*
G01Y159843D02*
G03I-709J0D01*
G01X521575Y164567D02*
G03I-709J0D01*
G01X519012Y160650D02*
G03X522162I1575J0D01*
G01X511925D02*
G03X515075I1575J0D01*
G01X521575Y159055D02*
G03I-709J0D01*
G01Y154724D02*
G03I-709J0D01*
G01X528661Y154331D02*
G03I-708J0D01*
G01Y150000D02*
G03I-708J0D01*
G01X535748Y150394D02*
G03I-709J0D01*
G01X528661Y145669D02*
G03I-708J0D01*
G01X535748Y144882D02*
G03I-709J0D01*
G01X514488Y154331D02*
G03I-709J0D01*
G01Y150000D02*
G03I-709J0D01*
G01X521575Y150394D02*
G03I-709J0D01*
G01X514488Y145669D02*
G03I-709J0D01*
G01X521575Y144882D02*
G03I-709J0D01*
G01X535748Y140551D02*
G03I-709J0D01*
G01Y136220D02*
G03I-709J0D01*
G01X528661Y140157D02*
G03I-708J0D01*
G01X536728Y140965D02*
G03I-1968J0D01*
G01X529642D02*
G03I-1969J0D01*
G01X528661Y135827D02*
G03I-708J0D01*
G01X514488Y140157D02*
G03I-709J0D01*
G01X521575Y140551D02*
G03I-709J0D01*
G01X522555Y140965D02*
G03I-1968J0D01*
G01X515469D02*
G03I-1969J0D01*
G01X514488Y135827D02*
G03I-709J0D01*
G01X521575Y136220D02*
G03I-709J0D01*
G01X500532Y156673D02*
G03X501122Y157264I0J590D01*
G01X507401Y164567D02*
G03I-708J0D01*
G01Y159055D02*
G03I-708J0D01*
G01X500532Y156280D02*
G03X501516Y157264I0J984D01*
G01X507791Y156142D02*
G03X508776Y157126I0J985D01*
G01X504051D02*
G03X505036Y156142I984J0D01*
G01X497752Y160650D02*
G03X500902I1575J0D01*
G01X490665D02*
G03X493815I1575J0D01*
G01X504839D02*
G03X507988I1574J0D01*
G01X493583Y164744D02*
G03I-4744J0D01*
G01X496713D02*
G03I-7874J0D01*
G01X507401Y154724D02*
G03I-708J0D01*
G01Y150394D02*
G03I-708J0D01*
G01Y144882D02*
G03I-708J0D01*
G01X475532Y157264D02*
G03X476122Y156673I591J0D01*
G01X475138Y157264D02*
G03X476122Y156280I984J0D01*
G01X472358Y156142D02*
G03X473343Y157126I0J985D01*
G01X483579Y160650D02*
G03X486728I1574J0D01*
G01X476492D02*
G03X479642I1575J0D01*
G01X507401Y140551D02*
G03I-708J0D01*
G01X501295Y140965D02*
G03I-1968J0D01*
G01X508382D02*
G03I-1968J0D01*
G01X507401Y136220D02*
G03I-708J0D01*
G01X494209Y140965D02*
G03I-1969J0D01*
G01X487990Y141992D02*
G03X484071Y138073I849J-4768D01*
G01X493606D02*
G03X489687Y141992I-4768J-849D01*
G01X487122Y140965D02*
G03I-1968J0D01*
G01X480036D02*
G03I-1969J0D01*
G01X492339Y136374D02*
X490659Y135404D01*
G01X489749Y136314D02*
X490589Y136799D01*
G01X487929Y138134D02*
X487089Y137649D01*
G01X485339Y138074D02*
X487019Y139044D01*
G01X500961Y162718D02*
X500173Y162264D01*
G01X493776Y162718D02*
X492988Y162264D01*
G01X486689Y162718D02*
X485902Y162264D01*
G01X479701Y162718D02*
X478914Y162264D01*
G01X487019Y135404D02*
X490659Y139044D01*
G01X497697Y152461D02*
X497473Y152237D01*
G01X496489Y153221D02*
X496713Y153445D01*
G01X481188Y145795D02*
X480965Y145571D01*
G01X479980Y146555D02*
X480204Y146779D01*
G01X494674Y164744D02*
X488839Y158909D01*
G01X493839Y164744D02*
X488839Y159744D01*
G01X488877Y198700D02*
X488777Y198629D01*
G01X488839Y163169D02*
X490414Y164744D01*
G01X488839Y166319D02*
X487264Y164744D01*
G01X488839Y169744D02*
X483839Y164744D01*
G01X483004D02*
X488839Y170579D01*
G01X480608Y194742D02*
X480453Y194587D01*
G01X479469Y195571D02*
X479624Y195726D01*
G01X536335Y177161D02*
X537713Y179547D01*
G01X529248Y177161D02*
X530626Y179547D01*
G01X522162Y177161D02*
X523540Y179547D01*
G01X507949Y163186D02*
X507162Y161822D01*
G01X515075Y177161D02*
X516453Y179547D01*
G01X489749Y136314D02*
X489264Y135474D01*
G01X487929Y138134D02*
X488414Y138974D01*
G01X487019Y139044D02*
X487989Y140724D01*
G01X507988Y177161D02*
X509366Y179547D01*
G01X500961Y177263D02*
X502280Y179547D01*
G01X493815Y177161D02*
X495193Y179547D01*
G01X486728Y177161D02*
X488106Y179547D01*
G01X472516Y163607D02*
X471728Y162243D01*
G01X479701Y177263D02*
X481020Y179547D01*
G01X472555Y177161D02*
X473945Y179567D01*
G01X484682Y199226D02*
X484640Y199059D01*
G01X493264Y192717D02*
X494642Y198574D01*
G01X484720Y199409D02*
X484682Y199223D01*
G01X494793Y199409D02*
X494730Y199064D01*
G01X494759Y199223D02*
X494642Y198573D01*
G01X524866Y196260D02*
X524941Y196994D01*
G01X524553Y197191D02*
X524479Y196457D01*
G01X510693Y196260D02*
X510768Y196994D01*
G01X510380Y197191D02*
X510305Y196457D01*
G01X507765Y190755D02*
X507757Y190157D01*
G01X528668Y195644D02*
X528669Y196063D01*
G01X514495Y195644D02*
X514496Y196063D01*
G01X536335Y160650D02*
Y177161D01*
G01X536261Y190157D02*
Y201804D01*
G01X536250D02*
X536251Y190882D01*
G01X536064Y201804D02*
Y190748D01*
G01X535749Y195669D02*
Y191732D01*
G01X533190Y195669D02*
Y191732D01*
G01X533185Y177161D02*
Y160650D01*
G01X532875Y201804D02*
Y190748D01*
G01X532678Y201804D02*
Y190157D01*
G01X531699Y190748D02*
Y225787D01*
G01X531513D02*
Y190882D01*
G01X531502D02*
Y190157D01*
G01X529248Y160650D02*
Y177161D01*
G01X529174Y190157D02*
Y201043D01*
G01X528977Y190748D02*
Y200623D01*
G01X528793Y196063D02*
Y200939D01*
G01X528662Y195669D02*
Y191732D01*
G01X528411Y201039D02*
Y196036D01*
G01X528221Y226338D02*
Y196063D01*
G01X528030D02*
Y200939D01*
G01X527833Y226338D02*
Y196063D01*
G01X527691Y226338D02*
Y196063D01*
G01X527303D02*
Y226338D01*
G01X526103Y197191D02*
Y191732D01*
G01X526099Y177161D02*
Y160650D01*
G01X525788Y200623D02*
Y190748D01*
G01X525591Y201043D02*
Y190157D01*
G01X524941Y196994D02*
Y226338D01*
G01X524866Y196260D02*
Y196063D01*
G01X524823D02*
Y195669D01*
G01X524553Y226338D02*
Y197191D01*
G01X524411Y196457D02*
Y226338D01*
G01X524175Y195694D02*
Y200939D01*
G01X524024Y196457D02*
Y226338D01*
G01X523412Y200939D02*
Y196457D01*
G01X522162Y160650D02*
Y177161D01*
G01X522088Y190157D02*
Y201804D01*
G01X522076D02*
X522078Y190882D01*
G01X521891Y201804D02*
Y190748D01*
G01X521576Y195669D02*
Y191732D01*
G01X519017Y195669D02*
Y191732D01*
G01X519012Y177161D02*
Y160650D01*
G01X518702Y201804D02*
Y190748D01*
G01X518505Y201804D02*
Y190157D01*
G01X517526Y190748D02*
Y225787D01*
G01X517339D02*
Y190882D01*
G01X517329D02*
Y190157D01*
G01X515075Y160650D02*
Y177161D01*
G01X515001Y190157D02*
Y201043D01*
G01X514804Y190748D02*
Y200623D01*
G01X514619Y196063D02*
Y200939D01*
G01X514489Y195669D02*
Y191732D01*
G01X514238Y201039D02*
Y196036D01*
G01X514048Y226338D02*
Y196063D01*
G01X513857D02*
Y200939D01*
G01X513660Y226338D02*
Y196063D01*
G01X513518Y226338D02*
Y196063D01*
G01X513130D02*
Y226338D01*
G01X511930Y197191D02*
Y191732D01*
G01X511925Y177161D02*
Y160650D01*
G01X511615Y200623D02*
Y190748D01*
G01X511418Y201043D02*
Y190157D01*
G01X510768Y196994D02*
Y226338D01*
G01X510693Y196260D02*
Y196063D01*
G01X510650D02*
Y195669D01*
G01X510380Y226338D02*
Y197191D01*
G01X510238Y196457D02*
Y226338D01*
G01X510002Y195694D02*
Y200939D01*
G01X509850Y196457D02*
Y226338D01*
G01X509239Y200939D02*
Y196457D01*
G01X508776Y180551D02*
Y157126D01*
G01X472331Y190754D02*
X472324Y190157D01*
G01X471975Y195644D02*
X471976Y196063D01*
G01X472336Y199961D02*
X472332Y190754D01*
G01X507768Y201804D02*
X507765Y190755D01*
G01X507988Y174463D02*
Y177161D01*
G01Y167140D02*
Y172803D01*
G01Y160650D02*
Y165481D01*
G01X507949Y165420D02*
Y163186D01*
G01Y172743D02*
Y167200D01*
G01Y180551D02*
Y174523D01*
G01X507914Y190833D02*
Y190157D01*
G01X507717Y190748D02*
Y201804D01*
G01X507403Y195669D02*
Y191732D01*
G01X507304Y195906D02*
Y191969D01*
G01X504942Y195906D02*
Y191969D01*
G01X504878Y174523D02*
Y180551D01*
G01Y167200D02*
Y172743D01*
G01Y163186D02*
Y165420D01*
G01X504843Y195669D02*
Y191732D01*
G01X504839Y165481D02*
Y160650D01*
G01Y172803D02*
Y167140D01*
G01Y177161D02*
Y174463D01*
G01X504528Y201804D02*
Y190748D01*
G01X504332Y190833D02*
Y190157D01*
G01X504051Y180551D02*
Y157126D01*
G01X502368Y228740D02*
Y190157D01*
G01X501122Y209646D02*
Y157264D01*
G01X500961Y162718D02*
Y180728D01*
G01X500902Y160650D02*
Y162684D01*
G01X500728Y189862D02*
Y210433D01*
G01X500532Y156673D02*
Y156280D01*
G01X497752Y162684D02*
Y160650D01*
G01X497697Y146555D02*
Y152461D01*
G01X497693Y180728D02*
Y162718D01*
G01X497473Y146779D02*
Y152237D01*
G01X497185Y195571D02*
Y205414D01*
G01X497030Y195726D02*
Y205259D01*
G01X496489Y145795D02*
Y153221D01*
G01X496046Y194742D02*
Y206243D01*
G01X494856Y230906D02*
Y184646D01*
G01X494850Y230906D02*
Y184646D01*
G01X494820Y230906D02*
Y184646D01*
G01X494793Y230906D02*
Y199409D01*
G01X494642Y184646D02*
Y198574D01*
G01X494249Y188878D02*
Y187911D01*
G01X493815Y160650D02*
Y177161D01*
G01X493776Y180728D02*
Y162718D01*
G01X493754Y230906D02*
Y184646D01*
G01X493571Y230906D02*
Y184646D01*
G01X493520Y188878D02*
Y222874D01*
G01X493508Y199409D02*
Y230906D01*
G01X492438Y231299D02*
Y199409D01*
G01X492413Y230906D02*
Y184646D01*
G01X492273Y230906D02*
Y184646D01*
G01X491439Y137649D02*
Y136799D01*
G01X490705Y180728D02*
Y162718D01*
G01X490665Y177161D02*
Y160650D01*
G01X489689Y140724D02*
X489688Y142135D01*
G01X489626Y230905D02*
Y184646D01*
G01X489397Y230906D02*
Y184646D01*
G01X489335Y199409D02*
Y230906D01*
G01X489264Y138974D02*
Y139824D01*
G01Y134624D02*
Y135474D01*
G01X488839Y166319D02*
Y170579D01*
G01Y163169D02*
Y158909D01*
G01X488414Y135474D02*
Y134624D01*
G01Y139824D02*
Y138974D01*
G01X487823Y230906D02*
Y199409D01*
G01X487760Y230906D02*
Y184646D01*
G01X487532D02*
Y230905D01*
G01X486728Y160650D02*
Y177161D01*
G01X486689Y162718D02*
Y180728D01*
G01X486239Y137649D02*
Y136799D01*
G01X484885Y230906D02*
Y184646D01*
G01X484744Y230906D02*
Y184646D01*
G01X484720Y231299D02*
Y199409D01*
G01X483650Y230906D02*
Y199409D01*
G01X483638Y188878D02*
Y222874D01*
G01X483618Y180728D02*
Y162718D01*
G01X483587Y230906D02*
Y184646D01*
G01X483579Y177161D02*
Y160650D01*
G01X483404Y230906D02*
Y184646D01*
G01X482909Y188878D02*
Y187911D01*
G01X482516Y184646D02*
Y198574D01*
G01X482365Y230906D02*
Y199409D01*
G01X482338Y184646D02*
Y230906D01*
G01X482307D02*
Y184646D01*
G01X482302Y230906D02*
Y184646D01*
G01X481188Y145795D02*
Y153221D01*
G01X480608Y194742D02*
Y206243D01*
G01X480204Y146779D02*
Y152237D01*
G01X479980Y152461D02*
Y146555D01*
G01X479701Y162718D02*
Y180728D01*
G01X479642Y160650D02*
Y162684D01*
G01X479624Y205259D02*
Y195726D01*
G01X479469Y205414D02*
Y195571D01*
G01X476492Y162684D02*
Y160650D01*
G01X476433Y180728D02*
Y162718D01*
G01X476122Y156673D02*
Y156280D01*
G01X475925Y189862D02*
Y210433D01*
G01X475532Y157264D02*
Y209646D01*
G01X473628Y190157D02*
Y228740D01*
G01X473343Y180551D02*
Y157126D01*
G01X472555Y174884D02*
Y177161D01*
G01Y167561D02*
Y173224D01*
G01Y160650D02*
Y165902D01*
G01X472516Y165841D02*
Y163607D01*
G01Y173164D02*
Y167621D01*
G01Y180551D02*
Y174944D01*
G01X472481Y190833D02*
Y190157D01*
G01X472284Y190748D02*
Y200623D01*
G01X472100Y196063D02*
Y200939D01*
G01X471969Y195669D02*
Y191732D01*
G01X471871Y195906D02*
Y191969D01*
G01X471719Y196036D02*
X471718Y201039D01*
G01X471528Y226338D02*
Y196063D01*
G01X504478Y201804D02*
X504481Y190755D01*
G01X504489Y190157D02*
X504481Y190755D01*
G01X482516Y198573D02*
X482494Y198697D01*
G01X482505Y198634D02*
X482365Y199409D01*
G01X483894Y192717D02*
X482516Y198574D01*
G01X492476Y199223D02*
X492518Y199059D01*
G01X483650Y199409D02*
X483736Y199223D01*
G01X483821Y199059D02*
X483735Y199226D01*
G01X531807Y179547D02*
X533185Y177161D01*
G01X524721Y179547D02*
X526099Y177161D01*
G01X517634Y179547D02*
X519012Y177161D01*
G01X510547Y179547D02*
X511925Y177161D01*
G01X503461Y179547D02*
X504839Y177161D01*
G01X496374Y179547D02*
X497693Y177263D01*
G01X504878Y163186D02*
X505665Y161822D01*
G01X489288Y179547D02*
X490665Y177161D01*
G01X483904Y198916D02*
X483818Y199064D01*
G01X482201Y179547D02*
X483579Y177161D01*
G01X475114Y179547D02*
X476433Y177263D01*
G01X489689Y140724D02*
X490659Y139044D01*
G01X489749Y138134D02*
X489264Y138974D01*
G01X487929Y136314D02*
X488414Y135474D01*
G01X497030Y195726D02*
X497185Y195571D01*
G01X496201Y194587D02*
X496046Y194742D01*
G01X488839Y170579D02*
X494674Y164744D01*
G01X488839Y169744D02*
X493839Y164744D01*
G01X490414D02*
X488839Y166319D01*
G01X487264Y164744D02*
X488839Y163169D01*
G01X483839Y164744D02*
X488839Y159744D01*
G01Y158909D02*
X483004Y164744D01*
G01X497473Y146779D02*
X497697Y146555D01*
G01X496713Y145571D02*
X496489Y145795D01*
G01X480965Y153445D02*
X481188Y153221D01*
G01X480204Y152237D02*
X479980Y152461D01*
G01X490659Y135404D02*
X487019Y139044D01*
G01X498480Y162264D02*
X497693Y162718D01*
G01X491492Y162264D02*
X490705Y162718D01*
G01X484406Y162264D02*
X483618Y162718D01*
G01X477221Y162264D02*
X476433Y162718D01*
G01X490659Y139044D02*
X492339Y138074D01*
G01X490589Y137649D02*
X489749Y138134D01*
G01X487929Y136314D02*
X487089Y136799D01*
G01X487019Y135404D02*
X485339Y136374D01*
G01X482481Y187917D02*
X482909Y187911D01*
G01X495020Y187918D02*
X494860D01*
G01X483650Y199409D02*
X482365D01*
G01X487823D02*
X484720D01*
G01X492438D02*
X489335D01*
G01X494793D02*
X493508D01*
G01X524553Y197191D02*
X526103D01*
G01X510380D02*
X511930D01*
G01X524941Y196994D02*
X526103D01*
G01X510768D02*
X511930D01*
G01X509239Y196457D02*
X511930D01*
G01X526103D02*
X523412D01*
G01X524866Y196260D02*
X526103D01*
G01X510693D02*
X511930D01*
G01X524175Y196075D02*
X526103D01*
G01X510002D02*
X511930D01*
G01X472100Y196063D02*
X471969D01*
G01X507009D02*
X505237D01*
G01X511930D02*
X510650D01*
G01X514095D02*
X512324D01*
G01X514619D02*
X514489D01*
G01X521182D02*
X519410D01*
G01X528269D02*
X526497D01*
G01X526103D02*
X524823D01*
G01X528793D02*
X528662D01*
G01X535355D02*
X533584D01*
G01X507304Y195906D02*
X504942D01*
G01X497030Y195726D02*
X479624D01*
G01X524175Y195694D02*
X526103D01*
G01X510002D02*
X511930D01*
G01Y195669D02*
X510650D01*
G01X526103D02*
X524823D01*
G01X496046Y194742D02*
X480608D01*
G01X480453Y194587D02*
X496201D01*
G01X471969Y193567D02*
X473628D01*
G01X504843D02*
X502368D01*
G01X511930D02*
X507403D01*
G01X519017D02*
X514489D01*
G01X526103D02*
X521576D01*
G01X533190D02*
X528662D01*
G01X540277D02*
X535749D01*
G01X507304Y193543D02*
X504942D01*
G01X535749Y193370D02*
X540277D01*
G01X528662D02*
X533190D01*
G01X521576D02*
X526103D01*
G01X507403D02*
X511930D01*
G01X502368D02*
X504843D01*
G01X471969D02*
X473628D01*
G01X519017D02*
X514489D01*
G01X483894Y192717D02*
X493264D01*
G01X507304Y191969D02*
X504942D01*
G01X507403Y191732D02*
X504843D01*
G01X514489D02*
X511930D01*
G01X521576D02*
X519017D01*
G01X528662D02*
X526103D01*
G01X535749D02*
X533190D01*
G01X558667Y190748D02*
X502368D01*
G01X525591Y190236D02*
X529174D01*
G01X515001D02*
X511418D01*
G01X558995Y190157D02*
X502368D01*
G01X501516Y189862D02*
X475138D01*
G01X558995Y189370D02*
X502857D01*
G01X475138Y189075D02*
X501516D01*
G01X494249Y188878D02*
X482909D01*
G01X494249Y187911D02*
X482909D01*
G01X494856Y184646D02*
X482302D01*
G01X476433Y180728D02*
X475138D01*
G01X483618D02*
X479701D01*
G01X490705D02*
X486689D01*
G01X497693D02*
X493776D01*
G01X501516D02*
X500961D01*
G01X507949Y180551D02*
X554484D01*
G01X473956D02*
X472516D01*
G01X504878D02*
X502857D01*
G01X502280Y179547D02*
X503461D01*
G01X473933D02*
X475114D01*
G01X482201D02*
X481020D01*
G01X489288D02*
X488106D01*
G01X496374D02*
X495193D01*
G01X510547D02*
X509366D01*
G01X517634D02*
X516453D01*
G01X524721D02*
X523540D01*
G01X531807D02*
X530626D01*
G01X494862Y187918D02*
X494674Y187917D01*
G01X494677D02*
X494249Y187911D01*
G01X481925D02*
X481949Y187914D01*
G01X485339Y138074D02*
X492339Y136374D01*
G01X483656Y138072D02*
X494021Y136377D01*
G01X490414Y164744D02*
X494674D01*
G01X483004D02*
X487264D01*
G01X478914Y162264D02*
X477221D01*
G01X485902D02*
X484406D01*
G01X492988D02*
X491492D01*
G01X500173D02*
X498480D01*
G01X507162Y161822D02*
X505665D01*
G01X475138Y158803D02*
X501516D01*
G01X508776Y158665D02*
X504051D01*
G01X501122Y157264D02*
X501516D01*
G01X475138D02*
X475532D01*
G01X476122Y156673D02*
X500532D01*
G01Y156280D02*
X476122D01*
G01X507791Y156142D02*
X505036D01*
G01X496713Y153445D02*
X480965D01*
G01X481188Y153221D02*
X496489D01*
G01X480204Y152237D02*
X497473D01*
G01Y146779D02*
X480204D01*
G01X496489Y145795D02*
X481188D01*
G01X480965Y145571D02*
X496713D01*
G01X489264Y139824D02*
X488414D01*
G01X485339Y138074D02*
X483928D01*
G01X487089Y137649D02*
X486239D01*
G01X491439D02*
X490589D01*
G01Y136799D02*
X491439D01*
G01X486239D02*
X487089D01*
G01X492339Y136374D02*
X493750Y136375D01*
G01X488414Y134624D02*
X489264D01*
G01X487992Y142407D02*
X488556Y142411D01*
G01X483656Y136377D02*
X494021Y138072D01*
G01X485339Y136374D02*
X492339Y138074D01*
G01X493622Y245605D02*
G03I-4291J0D01*
G01X528176Y202464D02*
X528196Y202525D01*
G01X528137Y202405D02*
X528176Y202464D01*
G01X528084Y202352D02*
X528137Y202405D01*
G01X528017Y202308D02*
X528084Y202352D01*
G01X527939Y202275D02*
X528017Y202308D01*
G01X527856Y202253D02*
X527939Y202275D01*
G01X514003Y202464D02*
X514023Y202525D01*
G01X513964Y202405D02*
X514003Y202464D01*
G01X513910Y202352D02*
X513964Y202405D01*
G01X513843Y202308D02*
X513910Y202352D01*
G01X513766Y202275D02*
X513843Y202308D01*
G01X513683Y202253D02*
X513766Y202275D01*
G01X471483Y202464D02*
X471503Y202525D01*
G01X529160Y200746D02*
X529174Y200820D01*
G01X529117Y200682D02*
X529160Y200746D01*
G01X529054Y200640D02*
X529117Y200682D01*
G01X528977Y200623D02*
X529054Y200640D01*
G01X514986Y200746D02*
X515001Y200820D01*
G01X514944Y200682D02*
X514986Y200746D01*
G01X514881Y200640D02*
X514944Y200682D01*
G01X514804Y200623D02*
X514881Y200640D01*
G01X479544Y205790D02*
X479469Y205414D01*
G01X479757Y206109D02*
X479544Y205790D01*
G01X480076Y206323D02*
X479757Y206109D01*
G01X480453Y206398D02*
X480076Y206323D01*
G01X475167Y209858D02*
X475138Y209646D01*
G01X475257Y210062D02*
X475167Y209858D01*
G01X475412Y210242D02*
X475257Y210062D01*
G01X475635Y210378D02*
X475412Y210242D01*
G01X475925Y210433D02*
X475635Y210378D01*
G01X514186Y201438D02*
X514204Y201496D01*
G01X514152Y201383D02*
X514186Y201438D01*
G01X514103Y201332D02*
X514152Y201383D01*
G01X514043Y201289D02*
X514103Y201332D01*
G01X513973Y201255D02*
X514043Y201289D01*
G01X513896Y201231D02*
X513973Y201255D01*
G01X513816Y201218D02*
X513896Y201231D01*
G01X471666Y201438D02*
X471684Y201496D01*
G01X471632Y201383D02*
X471666Y201438D01*
G01X471583Y201332D02*
X471632Y201383D01*
G01X471523Y201289D02*
X471583Y201332D01*
G01X527848Y202252D02*
X527856Y202253D01*
G01X527839Y202251D02*
X527848Y202252D01*
G01X527831Y202249D02*
X527839Y202251D01*
G01X527823Y202248D02*
X527831Y202249D01*
G01X527815Y202248D02*
X527823D01*
G01X527808Y202247D02*
X527815Y202248D01*
G01X513674Y202252D02*
X513683Y202253D01*
G01X513666Y202251D02*
X513674Y202252D01*
G01X513658Y202249D02*
X513666Y202251D01*
G01X513650Y202248D02*
X513658Y202249D01*
G01X513642Y202248D02*
X513650D01*
G01X513635Y202247D02*
X513642Y202248D01*
G01X478419Y211395D02*
X478344Y211400D01*
G01X478633Y211394D02*
X478419Y211395D01*
G01X497005Y205480D02*
X497030Y205259D01*
G01X496932Y205687D02*
X497005Y205480D01*
G01X496815Y205872D02*
X496932Y205687D01*
G01X496657Y206030D02*
X496815Y205872D01*
G01X496471Y206146D02*
X496657Y206030D01*
G01X496264Y206218D02*
X496471Y206146D01*
G01X496046Y206243D02*
X496264Y206218D01*
G01X511427Y200763D02*
X511418Y200820D01*
G01X511449Y200714D02*
X511427Y200763D01*
G01X511482Y200675D02*
X511449Y200714D01*
G01X511523Y200646D02*
X511482Y200675D01*
G01X511569Y200629D02*
X511523Y200646D01*
G01X511615Y200623D02*
X511569Y200629D01*
G01X525600Y200763D02*
X525591Y200820D01*
G01X525623Y200714D02*
X525600Y200763D01*
G01X525656Y200675D02*
X525623Y200714D01*
G01X525697Y200646D02*
X525656Y200675D01*
G01X525742Y200629D02*
X525697Y200646D01*
G01X525788Y200623D02*
X525742Y200629D01*
G01X523846Y201438D02*
X523828Y201496D01*
G01X523880Y201383D02*
X523846Y201438D01*
G01X523929Y201332D02*
X523880Y201383D01*
G01X523989Y201289D02*
X523929Y201332D01*
G01X524059Y201255D02*
X523989Y201289D01*
G01X524136Y201231D02*
X524059Y201255D01*
G01X524215Y201218D02*
X524136Y201231D01*
G01X510215Y202248D02*
X510224Y202247D01*
G01X510207Y202249D02*
X510215Y202248D01*
G01X510199Y202250D02*
X510207Y202249D01*
G01X510191Y202251D02*
X510199Y202250D01*
G01X510183Y202252D02*
X510191Y202251D01*
G01X510176Y202253D02*
X510183Y202252D01*
G01X483901Y231055D02*
X483650Y230906D01*
G01X484153Y231102D02*
X483901Y231055D01*
G01X493005Y231102D02*
X493256Y231055D01*
G01X492739D02*
X493005Y231102D01*
G01X478727Y230632D02*
X478674Y230332D01*
G01X478868Y230902D02*
X478727Y230632D01*
G01X479085Y231115D02*
X478868Y230902D01*
G01X479357Y231252D02*
X479085Y231115D01*
G01X479658Y231299D02*
X479357Y231252D01*
G01X479045Y230339D02*
X479230Y230338D01*
G01X478887Y230339D02*
X479045D01*
G01X478771Y230338D02*
X478887Y230339D01*
G01X478699Y230336D02*
X478771Y230338D01*
G01X478674Y230332D02*
X478699Y230336D01*
G01X529757Y228591D02*
X529729Y228533D01*
G01X529795Y228642D02*
X529757Y228591D01*
G01X529844Y228684D02*
X529795Y228642D01*
G01X529899Y228715D02*
X529844Y228684D01*
G01X529958Y228734D02*
X529899Y228715D01*
G01X530021Y228740D02*
X529958Y228734D01*
G01X528187Y228591D02*
X528159Y228533D01*
G01X528225Y228642D02*
X528187Y228591D01*
G01X528274Y228684D02*
X528225Y228642D01*
G01X528328Y228715D02*
X528274Y228684D01*
G01X528388Y228734D02*
X528328Y228715D01*
G01X528451Y228740D02*
X528388Y228734D01*
G01X515584Y228591D02*
X515556Y228533D01*
G01X515622Y228642D02*
X515584Y228591D01*
G01X515670Y228684D02*
X515622Y228642D01*
G01X515725Y228715D02*
X515670Y228684D01*
G01X515785Y228734D02*
X515725Y228715D01*
G01X515847Y228740D02*
X515785Y228734D01*
G01X514014Y228591D02*
X513986Y228533D01*
G01X514052Y228642D02*
X514014Y228591D01*
G01X514100Y228684D02*
X514052Y228642D01*
G01X514155Y228715D02*
X514100Y228684D01*
G01X514215Y228734D02*
X514155Y228715D01*
G01X514277Y228740D02*
X514215Y228734D01*
G01X473064Y228591D02*
X473036Y228533D01*
G01X473102Y228642D02*
X473064Y228591D01*
G01X473151Y228684D02*
X473102Y228642D01*
G01X473206Y228715D02*
X473151Y228684D01*
G01X473265Y228734D02*
X473206Y228715D01*
G01X473328Y228740D02*
X473265Y228734D01*
G01X471581Y228684D02*
X471532Y228642D01*
G01X471636Y228715D02*
X471581Y228684D01*
G01X471695Y228734D02*
X471636Y228715D01*
G01X471758Y228740D02*
X471695Y228734D01*
G01X498511Y230338D02*
X498584Y230336D01*
G01X498394Y230339D02*
X498511Y230338D01*
G01X498237Y230339D02*
X498394D01*
G01X498051Y230338D02*
X498237Y230339D01*
G01X497625Y230332D02*
X498051Y230338D01*
G01X513589Y226997D02*
X513620Y227011D01*
G01X513541Y226990D02*
X513589Y226997D01*
G01X513480Y226992D02*
X513541Y226990D01*
G01X527762Y226997D02*
X527793Y227011D01*
G01X527714Y226990D02*
X527762Y226997D01*
G01X527653Y226992D02*
X527714Y226990D01*
G01X498993Y211100D02*
X498940Y211400D01*
G01X499134Y210830D02*
X498993Y211100D01*
G01X499351Y210617D02*
X499134Y210830D01*
G01X499624Y210480D02*
X499351Y210617D01*
G01X499924Y210433D02*
X499624Y210480D01*
G01X498557Y230632D02*
X498609Y230332D01*
G01X498416Y230902D02*
X498557Y230632D01*
G01X498198Y231115D02*
X498416Y230902D01*
G01X497926Y231252D02*
X498198Y231115D01*
G01X497625Y231299D02*
X497926Y231252D01*
G01X524388Y202248D02*
X524397Y202247D01*
G01X524380Y202249D02*
X524388Y202248D01*
G01X524372Y202250D02*
X524380Y202249D01*
G01X524364Y202251D02*
X524372Y202250D01*
G01X524356Y202252D02*
X524364Y202251D01*
G01X524349Y202253D02*
X524356Y202252D01*
G01X508589Y228514D02*
X508967Y228425D01*
G01X508513Y228533D02*
X508589Y228514D01*
G01X522762D02*
X523140Y228425D01*
G01X522686Y228533D02*
X522762Y228514D01*
G01X536936D02*
X537313Y228425D01*
G01X536859Y228533D02*
X536936Y228514D01*
G01X510357Y226990D02*
X510418Y226992D01*
G01X510309Y226997D02*
X510357Y226990D01*
G01X510278Y227011D02*
X510309Y226997D01*
G01X524530Y226990D02*
X524591Y226992D01*
G01X524482Y226997D02*
X524530Y226990D01*
G01X524451Y227011D02*
X524482Y226997D01*
G01X513546Y227952D02*
X513382Y227395D01*
G01X513626Y228378D02*
X513546Y227952D01*
G01X513618Y228647D02*
X513626Y228378D01*
G01X513523Y228740D02*
X513618Y228647D01*
G01X527719Y227952D02*
X527555Y227395D01*
G01X527799Y228378D02*
X527719Y227952D01*
G01X527791Y228647D02*
X527799Y228378D01*
G01X527697Y228740D02*
X527791Y228647D01*
G01X513750Y228709D02*
X513523Y228740D01*
G01X513897Y228639D02*
X513750Y228709D01*
G01X513986Y228533D02*
X513897Y228639D01*
G01X527924Y228709D02*
X527697Y228740D01*
G01X528071Y228639D02*
X527924Y228709D01*
G01X528159Y228533D02*
X528071Y228639D01*
G01X510670Y226581D02*
X510768Y226378D01*
G01X510553Y226786D02*
X510670Y226581D01*
G01X510330Y227127D02*
X510553Y226786D01*
G01X471696Y201419D02*
X471684Y201496D01*
G01X471706Y201333D02*
X471696Y201419D01*
G01X471714Y201241D02*
X471706Y201333D01*
G01X524843Y226581D02*
X524941Y226378D01*
G01X524726Y226786D02*
X524843Y226581D01*
G01X524503Y227127D02*
X524726Y226786D01*
G01X510251Y227261D02*
X510330Y227127D01*
G01X510183Y227395D02*
X510251Y227261D01*
G01X524424D02*
X524503Y227127D01*
G01X524356Y227395D02*
X524424Y227261D01*
G01X508075Y228734D02*
X508011Y228740D01*
G01X508134Y228714D02*
X508075Y228734D01*
G01X508190Y228683D02*
X508134Y228714D01*
G01X508237Y228641D02*
X508190Y228683D01*
G01X508275Y228590D02*
X508237Y228641D01*
G01X508303Y228533D02*
X508275Y228590D01*
G01X508285Y228734D02*
X508221Y228740D01*
G01X508344Y228714D02*
X508285Y228734D01*
G01X508400Y228683D02*
X508344Y228714D01*
G01X508447Y228641D02*
X508400Y228683D01*
G01X508485Y228590D02*
X508447Y228641D01*
G01X508513Y228533D02*
X508485Y228590D01*
G01X509328Y228734D02*
X509264Y228740D01*
G01X509388Y228714D02*
X509328Y228734D01*
G01X509442Y228683D02*
X509388Y228714D01*
G01X509490Y228641D02*
X509442Y228683D01*
G01X509529Y228590D02*
X509490Y228641D01*
G01X509556Y228533D02*
X509529Y228590D01*
G01X509684Y228734D02*
X509620Y228740D01*
G01X509744Y228714D02*
X509684Y228734D01*
G01X509798Y228683D02*
X509744Y228714D01*
G01X509847Y228641D02*
X509798Y228683D01*
G01X509885Y228590D02*
X509847Y228641D01*
G01X509912Y228533D02*
X509885Y228590D01*
G01X522248Y228734D02*
X522184Y228740D01*
G01X522307Y228714D02*
X522248Y228734D01*
G01X522363Y228683D02*
X522307Y228714D01*
G01X522410Y228641D02*
X522363Y228683D01*
G01X522448Y228590D02*
X522410Y228641D01*
G01X522476Y228533D02*
X522448Y228590D01*
G01X522458Y228734D02*
X522394Y228740D01*
G01X522518Y228714D02*
X522458Y228734D01*
G01X522573Y228683D02*
X522518Y228714D01*
G01X522621Y228641D02*
X522573Y228683D01*
G01X522659Y228590D02*
X522621Y228641D01*
G01X522686Y228533D02*
X522659Y228590D01*
G01X523501Y228734D02*
X523438Y228740D01*
G01X523561Y228714D02*
X523501Y228734D01*
G01X523615Y228683D02*
X523561Y228714D01*
G01X523664Y228641D02*
X523615Y228683D01*
G01X523702Y228590D02*
X523664Y228641D01*
G01X523729Y228533D02*
X523702Y228590D01*
G01X523857Y228734D02*
X523794Y228740D01*
G01X523917Y228714D02*
X523857Y228734D01*
G01X523972Y228683D02*
X523917Y228714D01*
G01X524020Y228641D02*
X523972Y228683D01*
G01X524058Y228590D02*
X524020Y228641D01*
G01X524085Y228533D02*
X524058Y228590D01*
G01X510092Y202275D02*
X510176Y202253D01*
G01X510014Y202309D02*
X510092Y202275D01*
G01X509947Y202353D02*
X510014Y202309D01*
G01X509893Y202406D02*
X509947Y202353D01*
G01X509856Y202464D02*
X509893Y202406D01*
G01X509836Y202525D02*
X509856Y202464D01*
G01X509961Y201231D02*
X510042Y201218D01*
G01X509885Y201255D02*
X509961Y201231D01*
G01X509814Y201290D02*
X509885Y201255D01*
G01X509754Y201334D02*
X509814Y201290D01*
G01X509706Y201384D02*
X509754Y201334D01*
G01X509673Y201439D02*
X509706Y201384D01*
G01X509655Y201496D02*
X509673Y201439D01*
G01X482339Y231015D02*
X482365Y230906D01*
G01X482324Y231080D02*
X482339Y231015D01*
G01X482319Y231102D02*
X482324Y231080D01*
G01X496578Y206323D02*
X496201Y206398D01*
G01X496897Y206109D02*
X496578Y206323D01*
G01X497110Y205790D02*
X496897Y206109D01*
G01X497185Y205414D02*
X497110Y205790D01*
G01X487488Y231168D02*
X487532Y230906D01*
G01X487466Y231299D02*
X487488Y231168D01*
G01X500887Y210365D02*
X500728Y210433D01*
G01X501013Y210182D02*
X500887Y210365D01*
G01X501094Y209929D02*
X501013Y210182D01*
G01X501122Y209646D02*
X501094Y209929D01*
G01X509782Y225061D02*
X509715Y225280D01*
G01X509822Y224835D02*
X509782Y225061D01*
G01X509836Y224607D02*
X509822Y224835D01*
G01X510159Y225152D02*
X510079Y225415D01*
G01X510207Y224881D02*
X510159Y225152D01*
G01X510224Y224607D02*
X510207Y224881D01*
G01X509571Y225061D02*
X509505Y225280D01*
G01X509611Y224836D02*
X509571Y225061D01*
G01X509624Y224607D02*
X509611Y224836D01*
G01X510185Y226792D02*
X510118Y227011D01*
G01X510225Y226566D02*
X510185Y226792D01*
G01X510238Y226338D02*
X510225Y226566D01*
G01X471717Y201141D02*
X471714Y201241D01*
G01X471718Y201039D02*
X471717Y201141D01*
G01X509238Y201037D02*
X509239Y200939D01*
G01X509238Y201137D02*
Y201037D01*
G01X509237Y201241D02*
X509238Y201137D01*
G01X471768Y225061D02*
X471834Y225280D01*
G01X471728Y224836D02*
X471768Y225061D01*
G01X471714Y224607D02*
X471728Y224836D01*
G01X480387Y206217D02*
X480608Y206243D01*
G01X480180Y206145D02*
X480387Y206217D01*
G01X479994Y206028D02*
X480180Y206145D01*
G01X479837Y205870D02*
X479994Y206028D01*
G01X479720Y205684D02*
X479837Y205870D01*
G01X479648Y205477D02*
X479720Y205684D01*
G01X479624Y205259D02*
X479648Y205477D01*
G01X477932Y210617D02*
X477660Y210480D01*
G01X478149Y210830D02*
X477932Y210617D01*
G01X478291Y211100D02*
X478149Y210830D01*
G01X478344Y211400D02*
X478291Y211100D01*
G01X472359Y200639D02*
X472284Y200623D01*
G01X472424Y200681D02*
X472359Y200639D01*
G01X472466Y200746D02*
X472424Y200681D01*
G01X472481Y200820D02*
X472466Y200746D01*
G01X479286Y231226D02*
X479658Y231299D01*
G01X478968Y231017D02*
X479286Y231226D01*
G01X478754Y230703D02*
X478968Y231017D01*
G01X478674Y230332D02*
X478754Y230703D01*
G01X536421Y228734D02*
X536358Y228740D01*
G01X536481Y228714D02*
X536421Y228734D01*
G01X536536Y228683D02*
X536481Y228714D01*
G01X536584Y228641D02*
X536536Y228683D01*
G01X536622Y228590D02*
X536584Y228641D01*
G01X536649Y228533D02*
X536622Y228590D01*
G01X536631Y228734D02*
X536568Y228740D01*
G01X536691Y228714D02*
X536631Y228734D01*
G01X536746Y228683D02*
X536691Y228714D01*
G01X536794Y228641D02*
X536746Y228683D01*
G01X536832Y228590D02*
X536794Y228641D01*
G01X536859Y228533D02*
X536832Y228590D01*
G01X524265Y202275D02*
X524349Y202253D01*
G01X524187Y202309D02*
X524265Y202275D01*
G01X524120Y202353D02*
X524187Y202309D01*
G01X524067Y202406D02*
X524120Y202353D01*
G01X524029Y202464D02*
X524067Y202406D01*
G01X524009Y202525D02*
X524029Y202464D01*
G01X510281Y228649D02*
X510374Y228740D01*
G01X510272Y228383D02*
X510281Y228649D01*
G01X510351Y227957D02*
X510272Y228383D01*
G01X510516Y227395D02*
X510351Y227957D01*
G01X524454Y228649D02*
X524548Y228740D01*
G01X524445Y228383D02*
X524454Y228649D01*
G01X524524Y227957D02*
X524445Y228383D01*
G01X524689Y227395D02*
X524524Y227957D01*
G01X513852Y201040D02*
X513857Y200939D01*
G01X513838Y201135D02*
X513852Y201040D01*
G01X513816Y201218D02*
X513838Y201135D01*
G01X528025Y201040D02*
X528030Y200939D01*
G01X528012Y201135D02*
X528025Y201040D01*
G01X527990Y201218D02*
X528012Y201135D01*
G01X510366Y226585D02*
X510380Y226371D01*
G01X510333Y226800D02*
X510366Y226585D01*
G01X510278Y227011D02*
X510333Y226800D01*
G01X524540Y226585D02*
X524553Y226371D01*
G01X524506Y226800D02*
X524540Y226585D01*
G01X524451Y227011D02*
X524506Y226800D01*
G01X497998Y231226D02*
X497625Y231299D01*
G01X498315Y231017D02*
X497998Y231226D01*
G01X498530Y230703D02*
X498315Y231017D01*
G01X498609Y230332D02*
X498530Y230703D01*
G01X510096Y227630D02*
X510278Y227011D01*
G01X509981Y228112D02*
X510096Y227630D01*
G01X509912Y228533D02*
X509981Y228112D01*
G01X524269Y227630D02*
X524451Y227011D01*
G01X524154Y228112D02*
X524269Y227630D01*
G01X524085Y228533D02*
X524154Y228112D01*
G01X514226Y201333D02*
X514234Y201241D01*
G01X514216Y201419D02*
X514226Y201333D01*
G01X514204Y201496D02*
X514216Y201419D01*
G01X501018Y210378D02*
X500729Y210433D01*
G01X501240Y210244D02*
X501018Y210378D01*
G01X501395Y210065D02*
X501240Y210244D01*
G01X501486Y209861D02*
X501395Y210065D01*
G01X501516Y209646D02*
X501486Y209861D01*
G01X528389Y201419D02*
X528377Y201496D01*
G01X528399Y201333D02*
X528389Y201419D01*
G01X528407Y201241D02*
X528399Y201333D01*
G01X523955Y225061D02*
X523888Y225280D01*
G01X523996Y224835D02*
X523955Y225061D01*
G01X524009Y224607D02*
X523996Y224835D01*
G01X524332Y225152D02*
X524252Y225415D01*
G01X524381Y224881D02*
X524332Y225152D01*
G01X524397Y224607D02*
X524381Y224881D01*
G01X523744Y225061D02*
X523678Y225280D01*
G01X523784Y224836D02*
X523744Y225061D01*
G01X523798Y224607D02*
X523784Y224836D01*
G01X524358Y226792D02*
X524291Y227011D01*
G01X524398Y226566D02*
X524358Y226792D01*
G01X524411Y226338D02*
X524398Y226566D01*
G01X514237Y201141D02*
X514234Y201241D01*
G01X514238Y201039D02*
X514237Y201141D01*
G01X523411Y201037D02*
X523412Y200939D01*
G01X523411Y201137D02*
Y201037D01*
G01X523410Y201241D02*
X523411Y201137D01*
G01X528410Y201141D02*
X528407Y201241D01*
G01X528411Y201039D02*
X528410Y201141D01*
G01X509622Y201144D02*
X509621Y201043D01*
G01X509624Y201241D02*
X509622Y201144D01*
G01X523795D02*
X523794Y201043D01*
G01X523798Y201241D02*
X523795Y201144D01*
G01X510020Y201135D02*
X510042Y201218D01*
G01X510006Y201040D02*
X510020Y201135D01*
G01X510002Y200939D02*
X510006Y201040D01*
G01X524193Y201135D02*
X524215Y201218D01*
G01X524180Y201040D02*
X524193Y201135D01*
G01X524175Y200939D02*
X524180Y201040D01*
G01X514288Y225061D02*
X514354Y225280D01*
G01X514248Y224836D02*
X514288Y225061D01*
G01X514234Y224607D02*
X514248Y224836D01*
G01X528461Y225061D02*
X528527Y225280D01*
G01X528421Y224836D02*
X528461Y225061D01*
G01X528407Y224607D02*
X528421Y224836D01*
G01X513565Y226800D02*
X513620Y227011D01*
G01X513532Y226585D02*
X513565Y226800D01*
G01X513518Y226371D02*
X513532Y226585D01*
G01X527739Y226800D02*
X527793Y227011D01*
G01X527705Y226585D02*
X527739Y226800D01*
G01X527691Y226371D02*
X527705Y226585D01*
G01X509643Y201419D02*
X509655Y201496D01*
G01X509632Y201333D02*
X509643Y201419D01*
G01X509624Y201241D02*
X509632Y201333D01*
G01X513801Y227626D02*
X513620Y227011D01*
G01X513916Y228109D02*
X513801Y227626D01*
G01X513986Y228533D02*
X513916Y228109D01*
G01X494834Y231081D02*
X494839Y231102D01*
G01X494819Y231016D02*
X494834Y231081D01*
G01X494793Y230906D02*
X494819Y231016D01*
G01X471516Y224835D02*
X471503Y224607D01*
G01X471557Y225061D02*
X471516Y224835D01*
G01X471624Y225280D02*
X471557Y225061D01*
G01X472050Y228734D02*
X472114Y228740D01*
G01X471991Y228714D02*
X472050Y228734D01*
G01X471935Y228683D02*
X471991Y228714D01*
G01X471888Y228641D02*
X471935Y228683D01*
G01X471850Y228590D02*
X471888Y228641D01*
G01X471822Y228533D02*
X471850Y228590D01*
G01X473054Y228734D02*
X473118Y228740D01*
G01X472995Y228714D02*
X473054Y228734D01*
G01X472939Y228683D02*
X472995Y228714D01*
G01X472892Y228641D02*
X472939Y228683D01*
G01X472854Y228590D02*
X472892Y228641D01*
G01X472826Y228533D02*
X472854Y228590D01*
G01X523806Y201333D02*
X523798Y201241D01*
G01X523816Y201419D02*
X523806Y201333D01*
G01X523828Y201496D02*
X523816Y201419D01*
G01X527974Y227626D02*
X527793Y227011D01*
G01X528090Y228109D02*
X527974Y227626D01*
G01X528159Y228533D02*
X528090Y228109D01*
G01X513673Y226566D02*
X513660Y226338D01*
G01X513713Y226792D02*
X513673Y226566D01*
G01X513780Y227011D02*
X513713Y226792D01*
G01X527847Y226566D02*
X527833Y226338D01*
G01X527887Y226792D02*
X527847Y226566D01*
G01X527953Y227011D02*
X527887Y226792D01*
G01X513651Y224881D02*
X513635Y224607D01*
G01X513700Y225152D02*
X513651Y224881D01*
G01X513780Y225415D02*
X513700Y225152D01*
G01X527824Y224881D02*
X527808Y224607D01*
G01X527873Y225152D02*
X527824Y224881D01*
G01X527953Y225415D02*
X527873Y225152D01*
G01X514036Y224835D02*
X514023Y224607D01*
G01X514077Y225061D02*
X514036Y224835D01*
G01X514144Y225280D02*
X514077Y225061D01*
G01X528209Y224835D02*
X528196Y224607D01*
G01X528250Y225061D02*
X528209Y224835D01*
G01X528317Y225280D02*
X528250Y225061D01*
G01X528070Y201231D02*
X527990Y201218D01*
G01X528147Y201255D02*
X528070Y201231D01*
G01X528218Y201290D02*
X528147Y201255D01*
G01X528278Y201334D02*
X528218Y201290D01*
G01X528326Y201384D02*
X528278Y201334D01*
G01X528359Y201439D02*
X528326Y201384D01*
G01X528377Y201496D02*
X528359Y201439D01*
G01X514570Y228734D02*
X514634Y228740D01*
G01X514510Y228714D02*
X514570Y228734D01*
G01X514455Y228683D02*
X514510Y228714D01*
G01X514407Y228641D02*
X514455Y228683D01*
G01X514369Y228590D02*
X514407Y228641D01*
G01X514342Y228533D02*
X514369Y228590D01*
G01X515574Y228734D02*
X515637Y228740D01*
G01X515514Y228714D02*
X515574Y228734D01*
G01X515459Y228683D02*
X515514Y228714D01*
G01X515411Y228641D02*
X515459Y228683D01*
G01X515373Y228590D02*
X515411Y228641D01*
G01X515346Y228533D02*
X515373Y228590D01*
G01X528743Y228734D02*
X528807Y228740D01*
G01X528684Y228714D02*
X528743Y228734D01*
G01X528628Y228683D02*
X528684Y228714D01*
G01X528581Y228641D02*
X528628Y228683D01*
G01X528543Y228590D02*
X528581Y228641D01*
G01X528515Y228533D02*
X528543Y228590D01*
G01X529747Y228734D02*
X529811Y228740D01*
G01X529687Y228714D02*
X529747Y228734D01*
G01X529632Y228683D02*
X529687Y228714D01*
G01X529585Y228641D02*
X529632Y228683D01*
G01X529546Y228590D02*
X529585Y228641D01*
G01X529519Y228533D02*
X529546Y228590D01*
G01X513228Y226581D02*
X513345Y226785D01*
G01X513130Y226378D02*
X513228Y226581D01*
G01X527401D02*
X527518Y226785D01*
G01X527304Y226378D02*
X527401Y226581D01*
G01X513647Y227261D02*
X513715Y227395D01*
G01X513568Y227127D02*
X513647Y227261D01*
G01X513345Y226785D02*
X513568Y227127D01*
G01X510151Y228710D02*
X510374Y228740D01*
G01X509993Y228633D02*
X510151Y228710D01*
G01X509912Y228533D02*
X509993Y228633D01*
G01X527820Y227261D02*
X527888Y227395D01*
G01X527741Y227127D02*
X527820Y227261D01*
G01X527518Y226785D02*
X527741Y227127D01*
G01X524325Y228710D02*
X524548Y228740D01*
G01X524166Y228633D02*
X524325Y228710D01*
G01X524085Y228533D02*
X524166Y228633D01*
G01X475560Y209930D02*
X475532Y209646D01*
G01X475642Y210184D02*
X475560Y209930D01*
G01X475768Y210366D02*
X475642Y210184D01*
G01X475925Y210433D02*
X475768Y210366D01*
G01X472473Y200094D02*
X472481Y200151D01*
G01X472451Y200046D02*
X472473Y200094D01*
G01X472419Y200007D02*
X472451Y200046D01*
G01X472379Y199978D02*
X472419Y200007D01*
G01X472336Y199961D02*
X472379Y199978D01*
G01X528334Y226870D02*
G03X528239Y226338I1440J-532D01*
G01X514161Y226870D02*
G03X514065Y226338I1440J-535D01*
G01X523392Y224607D02*
G03X523297Y225140I-1535J1D01*
G01X524005Y226338D02*
G03X523910Y226870I-1535J0D01*
G01X514735Y225139D02*
G03X514640Y224607I1442J-532D01*
G01X528909Y225139D02*
G03X528813Y224607I1440J-535D01*
G01X501516Y209646D02*
G03X500728Y210433I-787J0D01*
G01X475925D02*
G03X475138Y209646I0J-787D01*
G01X477360Y210433D02*
G03X478344Y211400I0J984D01*
G01X498940D02*
G03X499924Y210433I984J17D01*
G01X498609Y230332D02*
G03X497625Y231299I-984J-17D01*
G01X479658D02*
G03X478674Y230332I0J-984D01*
G01X471641Y226870D02*
G03X471546Y226338I1440J-532D01*
G01X509219Y224607D02*
G03X509123Y225140I-1536J-1D01*
G01X509832Y226338D02*
G03X509737Y226870I-1535J0D01*
G01X472216Y225139D02*
G03X472120Y224607I1440J-535D01*
G01X536275Y228425D02*
X536649Y228533D01*
G01X523729D02*
X523355Y228425D01*
G01X522101D02*
X522476Y228533D01*
G01X509556D02*
X509182Y228425D01*
G01X507928D02*
X508303Y228533D01*
G01X524252Y225415D02*
X523888Y225280D01*
G01X523678D02*
X523314Y225146D01*
G01X524291Y227011D02*
X523927Y226876D01*
G01X510079Y225415D02*
X509715Y225280D01*
G01X509505D02*
X509140Y225146D01*
G01X510118Y227011D02*
X509754Y226876D01*
G01X487823Y230906D02*
X488086Y231016D01*
G01X492739Y231055D02*
X492438Y230906D01*
G01X537604Y228740D02*
X536259Y227395D01*
G01X530518Y228740D02*
X529173Y227395D01*
G01X523431Y228740D02*
X522086Y227395D01*
G01X497185Y205414D02*
X497030Y205259D01*
G01X496046Y206243D02*
X496201Y206398D01*
G01X516345Y228740D02*
X515000Y227395D01*
G01X509258Y228740D02*
X507913Y227395D01*
G01X493520Y222874D02*
X494307Y223661D01*
G01X494856Y230906D02*
X495249Y231299D01*
G01X495036D02*
X494839Y231102D01*
G01X473234Y228740D02*
X471889Y227395D01*
G01X494850Y230906D02*
X495239Y231299D01*
G01X492413Y230906D02*
X492782Y231299D01*
G01X494820Y230906D02*
X495178Y231299D01*
G01X493754Y230906D02*
X494074Y231299D01*
G01X492273Y230906D02*
X492501Y231299D01*
G01X530104Y228425D02*
X528891Y225146D01*
G01X528527Y225280D02*
X529729Y228533D01*
G01X529519D02*
X528317Y225280D01*
G01X527953Y225415D02*
X529065Y228425D01*
G01X528317Y226877D02*
X528878Y228394D01*
G01X528515Y228533D02*
X527953Y227011D01*
G01X515930Y228425D02*
X514718Y225146D01*
G01X514354Y225280D02*
X515556Y228533D01*
G01X515346D02*
X514144Y225280D01*
G01X513780Y225415D02*
X514892Y228425D01*
G01X514144Y226877D02*
X514705Y228394D01*
G01X514342Y228533D02*
X513780Y227011D01*
G01X524397Y202247D02*
X524215Y201218D01*
G01X523828Y201496D02*
X524009Y202525D01*
G01X487760Y230906D02*
X487924Y231299D01*
G01X473411Y228425D02*
X472199Y225146D01*
G01X471834Y225280D02*
X473036Y228533D01*
G01X472826D02*
X471624Y225280D01*
G01Y226877D02*
X472185Y228394D01*
G01X493571Y230906D02*
X493708Y231299D01*
G01X494834Y231081D02*
X494819Y231015D01*
G01X510224Y202247D02*
X510042Y201218D01*
G01X509655Y201496D02*
X509836Y202525D01*
G01X489669Y231168D02*
X489692Y231299D01*
G01X489626Y230906D02*
X489692Y231299D01*
G01X527691Y226371D02*
Y226338D01*
G01X527303D02*
X527304Y226378D01*
G01X513518Y226371D02*
Y226338D01*
G01X513130D02*
Y226378D01*
G01X528793Y200939D02*
X528795Y201241D01*
G01X514620Y200939D02*
X514622Y201241D01*
G01X536275Y228740D02*
Y228425D01*
G01X536128Y228740D02*
Y220866D01*
G01X535439Y225787D02*
Y201804D01*
G01X531601Y220866D02*
Y228740D01*
G01X531240D02*
Y220866D01*
G01X530104Y228425D02*
Y228740D01*
G01X529065Y228425D02*
Y228740D01*
G01X528878D02*
Y220866D01*
G01X528795Y201241D02*
Y224607D01*
G01X528407Y201241D02*
Y224607D01*
G01X528196D02*
Y202525D01*
G01X527808Y202247D02*
Y224607D01*
G01X524397Y202247D02*
Y224607D01*
G01X524009Y202525D02*
Y224607D01*
G01X523798D02*
Y201241D01*
G01X523410Y224607D02*
Y201241D01*
G01X523355Y228740D02*
Y228425D01*
G01X523140D02*
Y228740D01*
G01X522101D02*
Y228425D01*
G01X521955Y228740D02*
Y220866D01*
G01X521266Y225787D02*
Y201804D01*
G01X517427Y220866D02*
Y228740D01*
G01X517067D02*
Y220866D01*
G01X515930Y228425D02*
Y228740D01*
G01X514892Y228425D02*
Y228740D01*
G01X514705D02*
Y220866D01*
G01X514622Y201241D02*
Y224607D01*
G01X514234Y201241D02*
Y224607D01*
G01X514023Y202525D02*
Y224607D01*
G01X513635Y202247D02*
Y224607D01*
G01X510224Y202247D02*
Y224607D01*
G01X509836Y202525D02*
Y224607D01*
G01X509624D02*
Y201241D01*
G01X509237Y224607D02*
Y201241D01*
G01X509182Y228425D02*
Y228740D01*
G01X508967Y228425D02*
Y228740D01*
G01X524553Y226371D02*
Y226338D01*
G01X510380Y226371D02*
Y226338D01*
G01X524941Y226378D02*
Y226338D01*
G01X510768Y226378D02*
Y226338D01*
G01X528196Y202525D02*
X528377Y201496D01*
G01X527990Y201218D02*
X527808Y202247D01*
G01X514023Y202525D02*
X514204Y201496D01*
G01X513816Y201218D02*
X513635Y202247D01*
G01X538061Y225280D02*
X536859Y228533D01*
G01X536649D02*
X537851Y225280D01*
G01X537487Y225146D02*
X536275Y228425D01*
G01X524291Y227011D02*
X523729Y228533D01*
G01X523355Y228425D02*
X523927Y226876D01*
G01X523140Y228425D02*
X524252Y225415D01*
G01X523888Y225280D02*
X522686Y228533D01*
G01X522476D02*
X523678Y225280D01*
G01X523313Y225146D02*
X522101Y228425D01*
G01X479658Y230332D02*
X479328Y211400D01*
G01X478674Y230332D02*
X478344Y211400D01*
G01X472100Y200939D02*
X472102Y201241D01*
G01X507928Y228740D02*
Y228425D01*
G01X507782Y228740D02*
Y220866D01*
G01X497956Y211400D02*
Y210433D01*
G01X497929Y223661D02*
Y231251D01*
G01X497625Y230332D02*
Y231299D01*
G01X496385Y230906D02*
Y231299D01*
G01X496344Y230906D02*
Y231299D01*
G01X496262D02*
Y230906D01*
G01X496221Y231299D02*
Y230906D01*
G01X496139Y231299D02*
Y230906D01*
G01X496098Y231299D02*
Y230906D01*
G01X496016Y231299D02*
Y230906D01*
G01X495975Y231299D02*
Y230906D01*
G01X495934Y231299D02*
Y230906D01*
G01X495893Y231299D02*
Y230906D01*
G01X495829Y231299D02*
Y307325D01*
G01X495769Y231299D02*
Y230906D01*
G01X495728Y231299D02*
Y230906D01*
G01X494990Y231299D02*
Y230906D01*
G01X494839Y231102D02*
Y231299D01*
G01X494744D02*
Y230906D01*
G01X489298D02*
Y231299D01*
G01X489134Y230906D02*
Y231299D01*
G01X489052Y230906D02*
Y231299D01*
G01X488970D02*
Y230906D01*
G01X488888D02*
Y231299D01*
G01X488847D02*
Y230906D01*
G01X488642D02*
Y231299D01*
G01X488478Y230906D02*
Y231299D01*
G01X488314D02*
Y230906D01*
G01X488109Y231299D02*
Y230906D01*
G01X488068D02*
Y231299D01*
G01X487904D02*
Y230906D01*
G01X487658Y231299D02*
Y230906D01*
G01X482999D02*
Y231299D01*
G01X482835Y230906D02*
Y231299D01*
G01X482753D02*
Y230906D01*
G01X482671Y231299D02*
Y230906D01*
G01X482319Y231102D02*
Y231299D01*
G01X481604D02*
Y230906D01*
G01X481358D02*
Y231299D01*
G01X481329D02*
Y307325D01*
G01X479658Y230332D02*
Y231299D01*
G01X479328Y211400D02*
Y210433D01*
G01X479228Y231200D02*
Y223661D01*
G01X473411Y228425D02*
Y228740D01*
G01X472481Y201043D02*
Y200151D01*
G01X472372Y228425D02*
Y228740D01*
G01X472185D02*
Y220866D01*
G01X472102Y201241D02*
Y224607D01*
G01X471714D02*
Y201241D01*
G01X471503Y224607D02*
Y202525D01*
G01X498609Y230332D02*
X498940Y211400D01*
G01X497625Y230332D02*
X497956Y211400D01*
G01X487488Y231168D02*
X487466Y231299D01*
G01X471503Y202525D02*
X471684Y201496D01*
G01X482324Y231081D02*
X482319Y231102D01*
G01X483587Y230906D02*
X483450Y231299D01*
G01X510118Y227011D02*
X509556Y228533D01*
G01X509182Y228425D02*
X509754Y226876D01*
G01X508967Y228425D02*
X510079Y225415D01*
G01X509715Y225280D02*
X508513Y228533D01*
G01X508303D02*
X509505Y225280D01*
G01X509140Y225146D02*
X507928Y228425D01*
G01X489397Y230906D02*
X489234Y231299D01*
G01X484885Y230906D02*
X484657Y231299D01*
G01X484885Y230905D02*
X484657Y231299D01*
G01X483404Y230906D02*
X483083Y231299D01*
G01X533044Y227395D02*
X531699Y228740D01*
G01X525957Y227395D02*
X524612Y228740D01*
G01X518871Y227395D02*
X517526Y228740D01*
G01X511784Y227395D02*
X510439Y228740D01*
G01X504698Y227395D02*
X503353Y228740D01*
G01X482338Y230906D02*
X481980Y231299D01*
G01X484744Y230906D02*
X484375Y231299D01*
G01X481919D02*
X482307Y230906D01*
G01X482122Y231299D02*
X482319Y231102D01*
G01X482302Y230906D02*
X481908Y231299D01*
G01X483638Y222874D02*
X482851Y223661D01*
G01X480453Y206398D02*
X480608Y206243D01*
G01X479624Y205259D02*
X479469Y205414D01*
G01X493508Y230906D02*
X493256Y231055D01*
G01X484720Y230906D02*
X484419Y231055D01*
G01X527953Y227011D02*
X528317Y226876D01*
G01X528892Y225146D02*
X528527Y225280D01*
G01X528317D02*
X527953Y225415D01*
G01X489335Y230906D02*
X489071Y231017D01*
G01X513780Y227011D02*
X514144Y226876D01*
G01X514354Y225280D02*
X514718Y225146D01*
G01X514144Y225280D02*
X513780Y225415D01*
G01X472199Y225146D02*
X471834Y225280D01*
G01X529729Y228533D02*
X530104Y228425D01*
G01X528515Y228533D02*
X528878Y228429D01*
G01X515556Y228533D02*
X515930Y228425D01*
G01X514342Y228533D02*
X514705Y228429D01*
G01X473411Y228425D02*
X473036Y228533D01*
G01X471822D02*
X472185Y228429D01*
G01X488821Y231081D02*
X489074Y231015D01*
G01X484153Y231102D02*
X484419Y231055D01*
G01X498584Y230336D02*
X498609Y230332D01*
G01X488579Y231102D02*
X488825Y231081D01*
G01X527304Y226378D02*
X527691Y226371D01*
G01X513130Y226378D02*
X513518Y226371D01*
G01X479230Y230338D02*
X479658Y230332D01*
G01X497625Y231299D02*
X479658D01*
G01X483650Y230906D02*
X481358D01*
G01X489298D02*
X484720D01*
G01X492438D02*
X489335D01*
G01X496385D02*
X493508D01*
G01X497625Y230332D02*
X479658D01*
G01X502368Y228740D02*
X558667D01*
G01X528159Y228533D02*
X528515D01*
G01X513986D02*
X514342D01*
G01X471466D02*
X471822D01*
G01X473036D02*
X472826D01*
G01X508513D02*
X508303D01*
G01X515556D02*
X515346D01*
G01X522686D02*
X522476D01*
G01X529729D02*
X529519D01*
G01X536859D02*
X536649D01*
G01X523729D02*
X524085D01*
G01X509556D02*
X509912D01*
G01X502368Y228425D02*
X514892D01*
G01X473628D02*
X473411D01*
G01X529065D02*
X515930D01*
G01X543238D02*
X530104D01*
G01X473628Y228252D02*
X472185D01*
G01X507782D02*
X502368D01*
G01X521955D02*
X517427D01*
G01X517067D02*
X514705D01*
G01X531240D02*
X528878D01*
G01X536128D02*
X531601D01*
G01X507913Y227395D02*
X504698D01*
G01X515000D02*
X510183D01*
G01X522086D02*
X518871D01*
G01X529173D02*
X524356D01*
G01X536259D02*
X533044D01*
G01X527793Y227011D02*
X527953D01*
G01X513620D02*
X513780D01*
G01X510278D02*
X510118D01*
G01X524451D02*
X524291D01*
G01X524024Y226338D02*
X524941D01*
G01X509850D02*
X510768D01*
G01X527303D02*
X528221D01*
G01X513130D02*
X514048D01*
G01X521266Y225787D02*
X517340D01*
G01X535439D02*
X531513D01*
G01X514354Y225280D02*
X514144D01*
G01X528527D02*
X528317D01*
G01X471834D02*
X471624D01*
G01X509715D02*
X509505D01*
G01X523888D02*
X523678D01*
G01X527808Y224607D02*
X528795D01*
G01X523410D02*
X524397D01*
G01X513635D02*
X514622D01*
G01X509237D02*
X510224D01*
G01X478558Y223661D02*
X498726D01*
G01X493520Y222874D02*
X483638D01*
G01X473628Y220866D02*
X472185D01*
G01X507782D02*
X502368D01*
G01X521955D02*
X517427D01*
G01X517067D02*
X514705D01*
G01X531240D02*
X528878D01*
G01X536128D02*
X531601D01*
G01X510768Y226378D02*
X510380Y226371D01*
G01X524941Y226378D02*
X524553Y226371D01*
G01X488579Y231102D02*
X488331Y231080D01*
G01X472372Y228425D02*
X472750Y228514D01*
G01X514892Y228425D02*
X515269Y228514D01*
G01X529065Y228425D02*
X529442Y228514D01*
G01X472750D02*
X472826Y228533D01*
G01X515269Y228514D02*
X515346Y228533D01*
G01X529442Y228514D02*
X529519Y228533D01*
G01X488082Y231015D02*
X488335Y231081D01*
G01X498333Y211395D02*
X497956Y211400D01*
G01X498331Y211395D02*
X498653Y211394D01*
G01X497956Y211400D02*
X479328D01*
G01X500728Y210433D02*
X475925D01*
G01X475138Y209646D02*
X501516D01*
G01X496201Y206398D02*
X480453D01*
G01X496046Y206243D02*
X480608D01*
G01X479624Y205259D02*
X497030D01*
G01X524009Y202525D02*
X528196D01*
G01X509836D02*
X514023D01*
G01X513635Y202247D02*
X510224D01*
G01X527808D02*
X524397D01*
G01X504478Y201804D02*
X507768D01*
G01X473956D02*
X473628D01*
G01X502857D02*
X502368D01*
G01X522088D02*
X518505D01*
G01X536261D02*
X532678D01*
G01X528407Y201241D02*
X528795D01*
G01X514234D02*
X514622D01*
G01X472102D02*
X471714D01*
G01X509624D02*
X509237D01*
G01X523798D02*
X523410D01*
G01X524215Y201218D02*
X527990D01*
G01X510042D02*
X513816D01*
G01X515001Y201043D02*
X511418D01*
G01X529174D02*
X525591D01*
G01X523412Y200939D02*
X528793D01*
G01X509239D02*
X514619D01*
G01X514804Y200623D02*
X511615D01*
G01X528977D02*
X525788D01*
G01X478631Y211394D02*
X478953Y211395D01*
G01X498650Y211394D02*
X498865Y211395D01*
G01X478950D02*
X479328Y211400D01*
G01X498940D02*
X498866Y211395D01*
G01X477660Y210480D02*
X477360Y210433D01*
G01X490284Y316929D02*
G03X486874I-1705J-984D01*
G01D02*
X481329Y307325D01*
G01X490284Y316929D02*
X495829Y307325D01*
G01X486874Y316929D02*
X490284D01*
G01X481329Y307325D02*
X495829D01*
G01X493622Y698924D02*
G03I-4291J0D01*
G01X495023Y762380D02*
Y765180D01*
G01X597656Y-837696D02*
Y-856633D01*
G01X585982Y-647618D02*
Y-737748D01*
G01X589650Y-692937D02*
X1003305D01*
G01X569094Y-512D02*
G03X580512I5709J0D01*
G01Y4016D02*
Y-512D01*
G01X569094Y4016D02*
Y-512D01*
G01X580512D02*
X569094D01*
G01X588582Y29409D02*
Y4409D01*
G01X586614D02*
Y29409D01*
G01X586181Y25394D02*
Y23425D01*
G01X586023Y11890D02*
Y4409D01*
G01X585787Y25394D02*
Y29409D01*
G01Y25394D02*
Y23425D01*
G01X583819Y25394D02*
Y29409D01*
G01Y25394D02*
Y23425D01*
G01X583425Y25394D02*
Y23425D01*
G01X581102Y11890D02*
Y4016D01*
G01X580950Y11890D02*
Y4409D01*
G01X576181Y25394D02*
Y23425D01*
G01X575787Y25394D02*
Y29409D01*
G01Y25394D02*
Y23425D01*
G01X573819Y25394D02*
Y23425D01*
G01Y29409D02*
Y25394D01*
G01X573425D02*
Y23425D01*
G01X568656Y11890D02*
Y4409D01*
G01X568504Y11890D02*
Y4016D01*
G01X566181Y25394D02*
Y23425D01*
G01X565787Y25394D02*
Y29409D01*
G01Y25394D02*
Y23425D01*
G01X563819Y25394D02*
Y29409D01*
G01Y25394D02*
Y23425D01*
G01X563582Y11890D02*
Y4409D01*
G01X563425Y25394D02*
Y23425D01*
G01X562992Y29409D02*
Y4409D01*
G01X561023Y29409D02*
Y4409D01*
G01X585787Y29409D02*
X588582D01*
G01X561023D02*
X563819D01*
G01X573819D02*
X565787D01*
G01X583819D02*
X575787D01*
G01X566181Y25394D02*
X563425D01*
G01X576181D02*
X573425D01*
G01X586181D02*
X583425D01*
G01X566181Y23425D02*
X563425D01*
G01X576181D02*
X573425D01*
G01X586181D02*
X583425D01*
G01X581102Y11890D02*
X586023D01*
G01X568504D02*
X563582D01*
G01X581102D02*
X568504D01*
G01X588582Y4409D02*
X561023D01*
G01X581102Y4016D02*
X568504D01*
G01X543383Y121385D02*
X543412Y121021D01*
G01X543299Y121735D02*
X543383Y121385D01*
G01X543166Y122056D02*
X543299Y121735D01*
G01X542994Y122334D02*
X543166Y122056D01*
G01X542792Y122562D02*
X542994Y122334D01*
G01X542574Y122736D02*
X542792Y122562D01*
G01X550469Y121385D02*
X550498Y121021D01*
G01X550386Y121735D02*
X550469Y121385D01*
G01X550253Y122056D02*
X550386Y121735D01*
G01X550080Y122334D02*
X550253Y122056D01*
G01X549879Y122562D02*
X550080Y122334D01*
G01X549661Y122736D02*
X549879Y122562D01*
G01X557556Y121385D02*
X557585Y121021D01*
G01X557472Y121735D02*
X557556Y121385D01*
G01X557340Y122056D02*
X557472Y121735D01*
G01X557167Y122334D02*
X557340Y122056D01*
G01X556965Y122562D02*
X557167Y122334D01*
G01X556747Y122736D02*
X556965Y122562D01*
G01X542940Y122514D02*
X542574Y122736D01*
G01X543202Y122234D02*
X542940Y122514D01*
G01X543359Y121920D02*
X543202Y122234D01*
G01X543412Y121593D02*
X543359Y121920D01*
G01X550026Y122514D02*
X549661Y122736D01*
G01X550289Y122234D02*
X550026Y122514D01*
G01X550445Y121920D02*
X550289Y122234D01*
G01X550498Y121593D02*
X550445Y121920D01*
G01X557113Y122514D02*
X556747Y122736D01*
G01X557375Y122234D02*
X557113Y122514D01*
G01X557532Y121920D02*
X557375Y122234D01*
G01X557585Y121593D02*
X557532Y121920D01*
G01X540901Y122562D02*
X541119Y122736D01*
G01X540700Y122334D02*
X540901Y122562D01*
G01X540527Y122056D02*
X540700Y122334D01*
G01X540394Y121735D02*
X540527Y122056D01*
G01X540311Y121385D02*
X540394Y121735D01*
G01X540282Y121021D02*
X540311Y121385D01*
G01X547988Y122562D02*
X548206Y122736D01*
G01X547786Y122334D02*
X547988Y122562D01*
G01X547613Y122056D02*
X547786Y122334D01*
G01X547481Y121735D02*
X547613Y122056D01*
G01X547397Y121385D02*
X547481Y121735D01*
G01X547368Y121021D02*
X547397Y121385D01*
G01X555074Y122562D02*
X555292Y122736D01*
G01X554873Y122334D02*
X555074Y122562D01*
G01X554700Y122056D02*
X554873Y122334D01*
G01X554567Y121735D02*
X554700Y122056D01*
G01X554484Y121385D02*
X554567Y121735D01*
G01X554455Y121021D02*
X554484Y121385D01*
G01X540657Y122429D02*
X541119Y122736D01*
G01X540376Y122029D02*
X540657Y122429D01*
G01X540282Y121593D02*
X540376Y122029D01*
G01X547744Y122429D02*
X548206Y122736D01*
G01X547462Y122029D02*
X547744Y122429D01*
G01X547368Y121593D02*
X547462Y122029D01*
G01X554830Y122429D02*
X555292Y122736D01*
G01X554549Y122029D02*
X554830Y122429D01*
G01X554455Y121593D02*
X554549Y122029D01*
G01X557008Y131496D02*
G03I-709J0D01*
G01X542834D02*
G03I-708J0D01*
G01Y125984D02*
G03I-708J0D01*
G01Y121654D02*
G03I-708J0D01*
G01X549921Y130709D02*
G03I-709J0D01*
G01Y126378D02*
G03I-709J0D01*
G01X557008Y125984D02*
G03I-709J0D01*
G01Y121654D02*
G03I-709J0D01*
G01X542579Y122745D02*
G03X541115I-732J-1394D01*
G01X549665D02*
G03X548201I-732J-1394D01*
G01X556752D02*
G03X555288I-732J-1394D01*
G01X557555Y115256D02*
X556374Y114075D01*
G01X559016Y113091D02*
Y190157D01*
G01X558995Y116437D02*
Y113091D01*
G01Y120492D02*
Y118012D01*
G01X557585Y121593D02*
Y115650D01*
G01X557555Y118012D02*
Y115256D01*
G01X554484Y118012D02*
Y115256D01*
G01X554455Y121593D02*
Y115650D01*
G01X550498Y121593D02*
Y115650D01*
G01X547368Y121593D02*
Y115650D01*
G01X543412Y121593D02*
Y115650D01*
G01X540282Y121593D02*
Y115650D01*
G01X554484Y115256D02*
X555665Y114075D01*
G01X548206Y122736D02*
X542574D01*
G01X555292D02*
X549661D01*
G01X559016D02*
X556747D01*
G01X557555Y115256D02*
X554484D01*
G01X556374Y114075D02*
X555665D01*
G01X556299Y196850D02*
G03X560236Y200787I0J3937D01*
G01X564173Y188976D02*
G03X568110I1968J0D01*
G01Y723480D02*
Y188976D01*
G01X557340Y190749D02*
X557324Y190748D01*
G01X557355Y190751D02*
X557340Y190749D01*
G01X557371Y190754D02*
X557355Y190751D01*
G01X545708Y190836D02*
X545680Y190882D01*
G01X545742Y190797D02*
X545708Y190836D01*
G01X545782Y190770D02*
X545742Y190797D01*
G01X545827Y190753D02*
X545782Y190770D01*
G01X545872Y190748D02*
X545827Y190753D01*
G01X538254Y196164D02*
X538197Y196457D01*
G01X538426Y195905D02*
X538254Y196164D01*
G01X538689Y195730D02*
X538426Y195905D01*
G01X538996Y195669D02*
X538689Y195730D01*
G01X552427Y196164D02*
X552370Y196457D01*
G01X552599Y195905D02*
X552427Y196164D01*
G01X552862Y195730D02*
X552599Y195905D01*
G01X553170Y195669D02*
X552862Y195730D01*
G01X538638Y196264D02*
X538585Y196457D01*
G01X538788Y196117D02*
X538638Y196264D01*
G01X538996Y196063D02*
X538788Y196117D01*
G01X552811Y196264D02*
X552758Y196457D01*
G01X552961Y196117D02*
X552811Y196264D01*
G01X553170Y196063D02*
X552961Y196117D01*
G01X554119Y190749D02*
X554135Y190748D01*
G01X554103Y190751D02*
X554119Y190749D01*
G01X554088Y190755D02*
X554103Y190751D01*
G01X554047Y190761D02*
X554088Y190755D01*
G01X554007Y190776D02*
X554047Y190761D01*
G01X553970Y190800D02*
X554007Y190776D01*
G01X553938Y190833D02*
X553970Y190800D01*
G01X538960Y196270D02*
X539040Y196260D01*
G01X538884Y196288D02*
X538960Y196270D01*
G01X538815Y196312D02*
X538884Y196288D01*
G01X538755Y196343D02*
X538815Y196312D01*
G01X538706Y196378D02*
X538755Y196343D01*
G01X538672Y196417D02*
X538706Y196378D01*
G01X538652Y196457D02*
X538672Y196417D01*
G01X539034Y197005D02*
X539114Y196994D01*
G01X538959Y197022D02*
X539034Y197005D01*
G01X538890Y197047D02*
X538959Y197022D01*
G01X538830Y197078D02*
X538890Y197047D01*
G01X538781Y197113D02*
X538830Y197078D01*
G01X538746Y197151D02*
X538781Y197113D01*
G01X538727Y197191D02*
X538746Y197151D01*
G01X553133Y196270D02*
X553213Y196260D01*
G01X553057Y196288D02*
X553133Y196270D01*
G01X552988Y196312D02*
X553057Y196288D01*
G01X552928Y196343D02*
X552988Y196312D01*
G01X552880Y196378D02*
X552928Y196343D01*
G01X552845Y196417D02*
X552880Y196378D01*
G01X552825Y196457D02*
X552845Y196417D01*
G01X553208Y197005D02*
X553288Y196994D01*
G01X553132Y197022D02*
X553208Y197005D01*
G01X553063Y197047D02*
X553132Y197022D01*
G01X553003Y197078D02*
X553063Y197047D01*
G01X552954Y197113D02*
X553003Y197078D01*
G01X552920Y197151D02*
X552954Y197113D01*
G01X552900Y197191D02*
X552920Y197151D01*
G01X539887Y190764D02*
X539962Y190748D01*
G01X539822Y190806D02*
X539887Y190764D01*
G01X539780Y190871D02*
X539822Y190806D01*
G01X539765Y190945D02*
X539780Y190871D01*
G01X537967Y201043D02*
Y196457D01*
G01X546973Y190764D02*
X547048Y190748D01*
G01X546909Y190806D02*
X546973Y190764D01*
G01X546867Y190871D02*
X546909Y190806D01*
G01X546851Y190945D02*
X546867Y190871D01*
G01X538952Y196073D02*
X539040Y196063D01*
G01X538871Y196102D02*
X538952Y196073D01*
G01X538798Y196149D02*
X538871Y196102D01*
G01X538736Y196212D02*
X538798Y196149D01*
G01X538690Y196287D02*
X538736Y196212D01*
G01X538661Y196369D02*
X538690Y196287D01*
G01X538652Y196457D02*
X538661Y196369D01*
G01X553126Y196073D02*
X553213Y196063D01*
G01X553044Y196102D02*
X553126Y196073D01*
G01X552971Y196149D02*
X553044Y196102D01*
G01X552909Y196212D02*
X552971Y196149D01*
G01X552863Y196287D02*
X552909Y196212D01*
G01X552835Y196369D02*
X552863Y196287D01*
G01X552825Y196457D02*
X552835Y196369D01*
G01X552140Y201043D02*
Y196457D01*
G01X543226Y190764D02*
X543151Y190748D01*
G01X543290Y190806D02*
X543226Y190764D01*
G01X543333Y190871D02*
X543290Y190806D01*
G01X543347Y190945D02*
X543333Y190871D01*
G01X550313Y190764D02*
X550237Y190748D01*
G01X550377Y190806D02*
X550313Y190764D01*
G01X550419Y190871D02*
X550377Y190806D01*
G01X550434Y190945D02*
X550419Y190871D01*
G01X550322Y190766D02*
X550237Y190748D01*
G01X550385Y190815D02*
X550322Y190766D01*
G01X550429Y190882D02*
X550385Y190815D01*
G01X557412Y190761D02*
X557371Y190754D01*
G01X557452Y190776D02*
X557412Y190761D01*
G01X557489Y190800D02*
X557452Y190776D01*
G01X557521Y190833D02*
X557489Y190800D01*
G01X552128Y196457D02*
G03X552521Y196063I394J0D01*
G01X547757D02*
G03X547363Y195669I0J-394D01*
G01X549922D02*
G03X549528Y196063I-394J0D01*
G01X554843D02*
G03X554450Y195669I0J-393D01*
G01X557009D02*
G03X556615Y196063I-394J0D01*
G01X551773Y196457D02*
G03X552521Y195709I748J0D01*
G01X549921Y183071D02*
G03I-709J0D01*
G01X537954Y196457D02*
G03X538348Y196063I394J0D01*
G01X540670D02*
G03X540277Y195669I0J-393D01*
G01X542836D02*
G03X542442Y196063I-394J0D01*
G01X537600Y196457D02*
G03X538348Y195709I748J0D01*
G01X549921Y178740D02*
G03I-709J0D01*
G01Y173228D02*
G03I-709J0D01*
G01X557008Y174016D02*
G03I-709J0D01*
G01X554484Y174944D02*
G03Y173164I1300J-890D01*
G01X557555D02*
G03Y174944I-1299J890D01*
G01X557008Y168504D02*
G03I-709J0D01*
G01X549921Y168898D02*
G03I-709J0D01*
G01X554484Y167621D02*
G03Y165841I1300J-890D01*
G01X557555D02*
G03Y167621I-1299J890D01*
G01X542834Y174016D02*
G03I-708J0D01*
G01Y168504D02*
G03I-708J0D01*
G01X557008Y164173D02*
G03I-709J0D01*
G01Y159843D02*
G03I-709J0D01*
G01X554445Y160650D02*
G03X555999Y159075I1575J0D01*
G01X557398Y156142D02*
G03X558382Y157126I0J984D01*
G01X553658D02*
G03X554642Y156142I984J0D01*
G01X559016Y157500D02*
G03X557441Y159075I-1575J0D01*
G01X542834Y164173D02*
G03I-708J0D01*
G01Y159843D02*
G03I-708J0D01*
G01X549921Y164567D02*
G03I-709J0D01*
G01X547358Y160650D02*
G03X550508I1575J0D01*
G01X540272D02*
G03X543421I1574J0D01*
G01X549921Y159055D02*
G03I-709J0D01*
G01Y154724D02*
G03I-709J0D01*
G01X542834Y154331D02*
G03I-708J0D01*
G01Y150000D02*
G03I-708J0D01*
G01Y145669D02*
G03I-708J0D01*
G01X557008Y154331D02*
G03I-709J0D01*
G01Y150000D02*
G03I-709J0D01*
G01X549921Y150394D02*
G03I-709J0D01*
G01X557008Y145669D02*
G03I-709J0D01*
G01X549921Y144882D02*
G03I-709J0D01*
G01Y140551D02*
G03I-709J0D01*
G01X557008Y140157D02*
G03I-709J0D01*
G01X557988Y140965D02*
G03I-1968J0D01*
G01X550902D02*
G03I-1969J0D01*
G01X557008Y135827D02*
G03I-709J0D01*
G01X549921Y136220D02*
G03I-709J0D01*
G01X542834Y140157D02*
G03I-708J0D01*
G01X543815Y140965D02*
G03I-1968J0D01*
G01X542834Y135827D02*
G03I-708J0D01*
G01X557555Y163607D02*
X556768Y162243D01*
G01X550508Y177161D02*
X551886Y179547D01*
G01X543421Y177161D02*
X544799Y179547D01*
G01X553213Y196260D02*
X553288Y196994D01*
G01X552900Y197191D02*
X552825Y196457D01*
G01X539040Y196260D02*
X539114Y196994D01*
G01X538727Y197191D02*
X538652Y196457D01*
G01X557371Y190754D02*
X557363Y190157D01*
G01X557015Y195644D02*
Y196063D01*
G01X557375Y199961D02*
X557371Y190754D01*
G01X558995Y201804D02*
Y189370D01*
G01X558667Y190157D02*
Y228740D01*
G01X558382Y180551D02*
Y157126D01*
G01X557555Y165841D02*
Y163607D01*
G01Y173164D02*
Y167621D01*
G01Y180551D02*
Y174944D01*
G01X557521Y190833D02*
Y190157D01*
G01X557324Y190748D02*
Y200623D01*
G01X557139Y196063D02*
Y200939D01*
G01X557009Y195669D02*
Y191732D01*
G01X556910Y195906D02*
Y191969D01*
G01X556758Y196036D02*
Y201039D01*
G01X556567Y226338D02*
Y196063D01*
G01X556377D02*
Y200939D01*
G01X556180Y226338D02*
Y196063D01*
G01X556037Y226338D02*
Y196063D01*
G01X555650D02*
Y226338D01*
G01X554548Y195906D02*
Y191969D01*
G01X554484Y165841D02*
Y163607D01*
G01Y173164D02*
Y167621D01*
G01Y180551D02*
Y174944D01*
G01X554450Y197191D02*
Y191732D01*
G01X554445Y165902D02*
Y160650D01*
G01Y173224D02*
Y167561D01*
G01Y177161D02*
Y174884D01*
G01X554135Y200623D02*
Y190748D01*
G01X553938Y190833D02*
Y190157D01*
G01X553658Y180551D02*
Y157126D01*
G01X553288Y196994D02*
Y226338D01*
G01X553213Y196260D02*
Y196063D01*
G01X553170D02*
Y195669D01*
G01X552900Y226338D02*
Y197191D01*
G01X552758Y196457D02*
Y226338D01*
G01X552521Y195694D02*
Y200939D01*
G01X552370Y196457D02*
Y226338D01*
G01X551759Y200939D02*
Y196457D01*
G01X550508Y160650D02*
Y177161D01*
G01X550434Y190157D02*
Y201804D01*
G01X550423D02*
X550424Y190882D01*
G01X550237Y201804D02*
Y190748D01*
G01X549922Y195669D02*
Y191732D01*
G01X554084Y199961D02*
X554088Y190754D01*
G01X554095Y190157D02*
X554088Y190754D01*
G01X542841Y195644D02*
X542842Y196063D01*
G01X547363Y195669D02*
Y191732D01*
G01X547358Y177161D02*
Y160650D01*
G01X547048Y201804D02*
Y190748D01*
G01X546851Y201804D02*
Y190157D01*
G01X545872Y190748D02*
Y225787D01*
G01X545686D02*
Y190882D01*
G01X545675D02*
Y190157D01*
G01X543421Y160650D02*
Y177161D01*
G01X543347Y190157D02*
Y201043D01*
G01X543151Y190748D02*
Y200623D01*
G01X542966Y196063D02*
Y200939D01*
G01X542836Y195669D02*
Y191732D01*
G01X542584Y201039D02*
X542585Y196036D01*
G01X542394Y226338D02*
Y196063D01*
G01X542203D02*
Y200939D01*
G01X542006Y226338D02*
Y196063D01*
G01X541864Y226338D02*
Y196063D01*
G01X541476D02*
Y226338D01*
G01X540277Y197191D02*
Y191732D01*
G01X540272Y177161D02*
Y160650D01*
G01X539962Y200623D02*
Y190748D01*
G01X539765Y201043D02*
Y190157D01*
G01X539114Y196994D02*
Y226338D01*
G01X539040Y196260D02*
Y196063D01*
G01X538996D02*
Y195669D01*
G01X538727Y226338D02*
Y197191D01*
G01X538585Y196457D02*
Y226338D01*
G01X538348Y195694D02*
Y200939D01*
G01X538197Y196457D02*
Y226338D01*
G01X537586Y200939D02*
Y196457D01*
G01X553067Y179547D02*
X554445Y177161D01*
G01X545980Y179547D02*
X547358Y177161D01*
G01X554484Y163607D02*
X555272Y162243D01*
G01X538894Y179547D02*
X540272Y177161D01*
G01X552900Y197191D02*
X554450D01*
G01X538727D02*
X540277D01*
G01X553288Y196994D02*
X554450D01*
G01X539114D02*
X540277D01*
G01Y196457D02*
X537586D01*
G01X554450D02*
X551759D01*
G01X553213Y196260D02*
X554450D01*
G01X539040D02*
X540277D01*
G01X552521Y196075D02*
X554450D01*
G01X538348D02*
X540277D01*
G01X554843Y196063D02*
X556615D01*
G01X542442D02*
X540670D01*
G01X540277D02*
X538996D01*
G01X542966D02*
X542836D01*
G01X549528D02*
X547757D01*
G01X554450D02*
X553170D01*
G01X557139D02*
X557009D01*
G01X556910Y195906D02*
X554548D01*
G01X552521Y195694D02*
X554450D01*
G01X538348D02*
X540277D01*
G01Y195669D02*
X538996D01*
G01X554450D02*
X553170D01*
G01X554548Y195048D02*
X556910D01*
G01X557009Y193567D02*
X558667D01*
G01X547363D02*
X542836D01*
G01X554450D02*
X549922D01*
G01X556910Y193543D02*
X554548D01*
G01X557009Y193370D02*
X558667D01*
G01X549922D02*
X554450D01*
G01X542836D02*
X547363D01*
G01X556910Y191969D02*
X554548D01*
G01X542836Y191732D02*
X540277D01*
G01X549922D02*
X547363D01*
G01X557009D02*
X554450D01*
G01X553938Y190236D02*
X557521D01*
G01X543347D02*
X539765D01*
G01X558995Y180551D02*
X557555D01*
G01X538894Y179547D02*
X537713D01*
G01X545980D02*
X544799D01*
G01X553067D02*
X551886D01*
G01X556768Y162243D02*
X555272D01*
G01X555999Y159075D02*
X557441D01*
G01X558382Y158665D02*
X553658D01*
G01X557398Y156142D02*
X554642D01*
G01X560236Y316929D02*
Y200787D01*
G01X556522Y202464D02*
X556542Y202525D01*
G01X556484Y202405D02*
X556522Y202464D01*
G01X556430Y202352D02*
X556484Y202405D01*
G01X556363Y202308D02*
X556430Y202352D01*
G01X556286Y202275D02*
X556363Y202308D01*
G01X556203Y202253D02*
X556286Y202275D01*
G01X542349Y202464D02*
X542369Y202525D01*
G01X542311Y202405D02*
X542349Y202464D01*
G01X542257Y202352D02*
X542311Y202405D01*
G01X542190Y202308D02*
X542257Y202352D01*
G01X542113Y202275D02*
X542190Y202308D01*
G01X542029Y202253D02*
X542113Y202275D01*
G01X543333Y200746D02*
X543347Y200820D01*
G01X543291Y200682D02*
X543333Y200746D01*
G01X543227Y200640D02*
X543291Y200682D01*
G01X543151Y200623D02*
X543227Y200640D01*
G01X556705Y201438D02*
X556724Y201496D01*
G01X556672Y201383D02*
X556705Y201438D01*
G01X556623Y201332D02*
X556672Y201383D01*
G01X556562Y201289D02*
X556623Y201332D01*
G01X556492Y201255D02*
X556562Y201289D01*
G01X556416Y201231D02*
X556492Y201255D01*
G01X556336Y201218D02*
X556416Y201231D01*
G01X556194Y202252D02*
X556203Y202253D01*
G01X556186Y202251D02*
X556194Y202252D01*
G01X556178Y202249D02*
X556186Y202251D01*
G01X556170Y202248D02*
X556178Y202249D01*
G01X556161Y202248D02*
X556170D01*
G01X556155Y202247D02*
X556161Y202248D01*
G01X542021Y202252D02*
X542029Y202253D01*
G01X542013Y202251D02*
X542021Y202252D01*
G01X542004Y202249D02*
X542013Y202251D01*
G01X541996Y202248D02*
X542004Y202249D01*
G01X541988Y202248D02*
X541996D01*
G01X541981Y202247D02*
X541988Y202248D01*
G01X539773Y200763D02*
X539765Y200820D01*
G01X539796Y200714D02*
X539773Y200763D01*
G01X539829Y200675D02*
X539796Y200714D01*
G01X539870Y200646D02*
X539829Y200675D01*
G01X539915Y200629D02*
X539870Y200646D01*
G01X539962Y200623D02*
X539915Y200629D01*
G01X553947Y200763D02*
X553938Y200820D01*
G01X553969Y200714D02*
X553947Y200763D01*
G01X554002Y200675D02*
X553969Y200714D01*
G01X554043Y200646D02*
X554002Y200675D01*
G01X554089Y200629D02*
X554043Y200646D01*
G01X554135Y200623D02*
X554089Y200629D01*
G01X558104Y228591D02*
X558076Y228533D01*
G01X558142Y228642D02*
X558104Y228591D01*
G01X558190Y228684D02*
X558142Y228642D01*
G01X558245Y228715D02*
X558190Y228684D01*
G01X558305Y228734D02*
X558245Y228715D01*
G01X558367Y228740D02*
X558305Y228734D01*
G01X556534Y228591D02*
X556506Y228533D01*
G01X556572Y228642D02*
X556534Y228591D01*
G01X556620Y228684D02*
X556572Y228642D01*
G01X556675Y228715D02*
X556620Y228684D01*
G01X556735Y228734D02*
X556675Y228715D01*
G01X556797Y228740D02*
X556735Y228734D01*
G01X543930Y228591D02*
X543902Y228533D01*
G01X543969Y228642D02*
X543930Y228591D01*
G01X544017Y228684D02*
X543969Y228642D01*
G01X544072Y228715D02*
X544017Y228684D01*
G01X544132Y228734D02*
X544072Y228715D01*
G01X544194Y228740D02*
X544132Y228734D01*
G01X542360Y228591D02*
X542332Y228533D01*
G01X542399Y228642D02*
X542360Y228591D01*
G01X542447Y228684D02*
X542399Y228642D01*
G01X542502Y228715D02*
X542447Y228684D01*
G01X542562Y228734D02*
X542502Y228715D01*
G01X542624Y228740D02*
X542562Y228734D01*
G01X541936Y226997D02*
X541966Y227011D01*
G01X541888Y226990D02*
X541936Y226997D01*
G01X541826Y226992D02*
X541888Y226990D01*
G01X556109Y226997D02*
X556139Y227011D01*
G01X556061Y226990D02*
X556109Y226997D01*
G01X555999Y226992D02*
X556061Y226990D01*
G01X538019Y201438D02*
X538001Y201496D01*
G01X538053Y201383D02*
X538019Y201438D01*
G01X538102Y201332D02*
X538053Y201383D01*
G01X538162Y201289D02*
X538102Y201332D01*
G01X538232Y201255D02*
X538162Y201289D01*
G01X538309Y201231D02*
X538232Y201255D01*
G01X538389Y201218D02*
X538309Y201231D01*
G01X552193Y201438D02*
X552174Y201496D01*
G01X552226Y201383D02*
X552193Y201438D01*
G01X552275Y201332D02*
X552226Y201383D01*
G01X552336Y201289D02*
X552275Y201332D01*
G01X552405Y201255D02*
X552336Y201289D01*
G01X552482Y201231D02*
X552405Y201255D01*
G01X552562Y201218D02*
X552482Y201231D01*
G01X538562Y202248D02*
X538570Y202247D01*
G01X538553Y202249D02*
X538562Y202248D01*
G01X538545Y202250D02*
X538553Y202249D01*
G01X538537Y202251D02*
X538545Y202250D01*
G01X538529Y202252D02*
X538537Y202251D01*
G01X538522Y202253D02*
X538529Y202252D01*
G01X552735Y202248D02*
X552743Y202247D01*
G01X552727Y202249D02*
X552735Y202248D01*
G01X552718Y202250D02*
X552727Y202249D01*
G01X552710Y202251D02*
X552718Y202250D01*
G01X552702Y202252D02*
X552710Y202251D01*
G01X552695Y202253D02*
X552702Y202252D01*
G01X551109Y228514D02*
X551486Y228425D01*
G01X551032Y228533D02*
X551109Y228514D01*
G01X538703Y226990D02*
X538765Y226992D01*
G01X538655Y226997D02*
X538703Y226990D01*
G01X538625Y227011D02*
X538655Y226997D01*
G01X552877Y226990D02*
X552938Y226992D01*
G01X552829Y226997D02*
X552877Y226990D01*
G01X552798Y227011D02*
X552829Y226997D01*
G01X541892Y227952D02*
X541729Y227395D01*
G01X541972Y228378D02*
X541892Y227952D01*
G01X541964Y228647D02*
X541972Y228378D01*
G01X541870Y228740D02*
X541964Y228647D01*
G01X556065Y227952D02*
X555902Y227395D01*
G01X556146Y228378D02*
X556065Y227952D01*
G01X556138Y228647D02*
X556146Y228378D01*
G01X556043Y228740D02*
X556138Y228647D01*
G01X542097Y228709D02*
X541870Y228740D01*
G01X542244Y228639D02*
X542097Y228709D01*
G01X542332Y228533D02*
X542244Y228639D01*
G01X556270Y228709D02*
X556043Y228740D01*
G01X556417Y228639D02*
X556270Y228709D01*
G01X556506Y228533D02*
X556417Y228639D01*
G01X539017Y226581D02*
X539114Y226378D01*
G01X538899Y226786D02*
X539017Y226581D01*
G01X538676Y227127D02*
X538899Y226786D01*
G01X553190Y226581D02*
X553287Y226378D01*
G01X553073Y226786D02*
X553190Y226581D01*
G01X552850Y227127D02*
X553073Y226786D01*
G01X538598Y227261D02*
X538676Y227127D01*
G01X538529Y227395D02*
X538598Y227261D01*
G01X552771D02*
X552850Y227127D01*
G01X552703Y227395D02*
X552771Y227261D01*
G01X537674Y228734D02*
X537611Y228740D01*
G01X537734Y228714D02*
X537674Y228734D01*
G01X537789Y228683D02*
X537734Y228714D01*
G01X537837Y228641D02*
X537789Y228683D01*
G01X537875Y228590D02*
X537837Y228641D01*
G01X537902Y228533D02*
X537875Y228590D01*
G01X538030Y228734D02*
X537967Y228740D01*
G01X538090Y228714D02*
X538030Y228734D01*
G01X538145Y228683D02*
X538090Y228714D01*
G01X538193Y228641D02*
X538145Y228683D01*
G01X538231Y228590D02*
X538193Y228641D01*
G01X538258Y228533D02*
X538231Y228590D01*
G01X550594Y228734D02*
X550531Y228740D01*
G01X550654Y228714D02*
X550594Y228734D01*
G01X550710Y228683D02*
X550654Y228714D01*
G01X550757Y228641D02*
X550710Y228683D01*
G01X550795Y228590D02*
X550757Y228641D01*
G01X550822Y228533D02*
X550795Y228590D01*
G01X550804Y228734D02*
X550741Y228740D01*
G01X550864Y228714D02*
X550804Y228734D01*
G01X550920Y228683D02*
X550864Y228714D01*
G01X550967Y228641D02*
X550920Y228683D01*
G01X551005Y228590D02*
X550967Y228641D01*
G01X551032Y228533D02*
X551005Y228590D01*
G01X551847Y228734D02*
X551784Y228740D01*
G01X551907Y228714D02*
X551847Y228734D01*
G01X551962Y228683D02*
X551907Y228714D01*
G01X552010Y228641D02*
X551962Y228683D01*
G01X552048Y228590D02*
X552010Y228641D01*
G01X552075Y228533D02*
X552048Y228590D01*
G01X552204Y228734D02*
X552140Y228740D01*
G01X552263Y228714D02*
X552204Y228734D01*
G01X552318Y228683D02*
X552263Y228714D01*
G01X552366Y228641D02*
X552318Y228683D01*
G01X552404Y228590D02*
X552366Y228641D01*
G01X552432Y228533D02*
X552404Y228590D01*
G01X538438Y202275D02*
X538522Y202253D01*
G01X538360Y202309D02*
X538438Y202275D01*
G01X538293Y202353D02*
X538360Y202309D01*
G01X538240Y202406D02*
X538293Y202353D01*
G01X538202Y202464D02*
X538240Y202406D01*
G01X538182Y202525D02*
X538202Y202464D01*
G01X552611Y202275D02*
X552695Y202253D01*
G01X552533Y202309D02*
X552611Y202275D01*
G01X552466Y202353D02*
X552533Y202309D01*
G01X552413Y202406D02*
X552466Y202353D01*
G01X552375Y202464D02*
X552413Y202406D01*
G01X552356Y202525D02*
X552375Y202464D01*
G01X538627Y228649D02*
X538721Y228740D01*
G01X538618Y228383D02*
X538627Y228649D01*
G01X538698Y227957D02*
X538618Y228383D01*
G01X538862Y227395D02*
X538698Y227957D01*
G01X542199Y201040D02*
X542203Y200939D01*
G01X542185Y201135D02*
X542199Y201040D01*
G01X542163Y201218D02*
X542185Y201135D01*
G01X538713Y226585D02*
X538726Y226371D01*
G01X538679Y226800D02*
X538713Y226585D01*
G01X538625Y227011D02*
X538679Y226800D01*
G01X542562Y201419D02*
X542551Y201496D01*
G01X542573Y201333D02*
X542562Y201419D01*
G01X542581Y201241D02*
X542573Y201333D01*
G01X556736Y201419D02*
X556724Y201496D01*
G01X556746Y201333D02*
X556736Y201419D01*
G01X556754Y201241D02*
X556746Y201333D01*
G01X538128Y225061D02*
X538061Y225280D01*
G01X538169Y224835D02*
X538128Y225061D01*
G01X538182Y224607D02*
X538169Y224835D01*
G01X552301Y225061D02*
X552234Y225280D01*
G01X552342Y224835D02*
X552301Y225061D01*
G01X552356Y224607D02*
X552342Y224835D01*
G01X538506Y225152D02*
X538425Y225415D01*
G01X538554Y224881D02*
X538506Y225152D01*
G01X538570Y224607D02*
X538554Y224881D01*
G01X552679Y225152D02*
X552599Y225415D01*
G01X552727Y224881D02*
X552679Y225152D01*
G01X552743Y224607D02*
X552727Y224881D01*
G01X537917Y225061D02*
X537851Y225280D01*
G01X537957Y224836D02*
X537917Y225061D01*
G01X537971Y224607D02*
X537957Y224836D01*
G01X552091Y225061D02*
X552024Y225280D01*
G01X552131Y224836D02*
X552091Y225061D01*
G01X552144Y224607D02*
X552131Y224836D01*
G01X538531Y226792D02*
X538465Y227011D01*
G01X538571Y226566D02*
X538531Y226792D01*
G01X538585Y226338D02*
X538571Y226566D01*
G01X552704Y226792D02*
X552638Y227011D01*
G01X552744Y226566D02*
X552704Y226792D01*
G01X552758Y226338D02*
X552744Y226566D01*
G01X556358Y201135D02*
X556336Y201218D01*
G01X556372Y201040D02*
X556358Y201135D01*
G01X556377Y200939D02*
X556372Y201040D01*
G01X537584Y201037D02*
X537586Y200939D01*
G01X537584Y201137D02*
Y201037D01*
G01X537583Y201241D02*
X537584Y201137D01*
G01X542583Y201141D02*
X542581Y201241D01*
G01X542584Y201039D02*
X542583Y201141D01*
G01X537968Y201144D02*
X537967Y201043D01*
G01X537971Y201241D02*
X537968Y201144D01*
G01X538367Y201135D02*
X538389Y201218D01*
G01X538353Y201040D02*
X538367Y201135D01*
G01X538348Y200939D02*
X538353Y201040D01*
G01X552800Y228649D02*
X552894Y228740D01*
G01X552791Y228383D02*
X552800Y228649D01*
G01X552871Y227957D02*
X552791Y228383D01*
G01X553036Y227395D02*
X552871Y227957D01*
G01X552886Y226585D02*
X552900Y226371D01*
G01X552852Y226800D02*
X552886Y226585D01*
G01X552798Y227011D02*
X552852Y226800D01*
G01X538443Y227630D02*
X538625Y227011D01*
G01X538327Y228112D02*
X538443Y227630D01*
G01X538258Y228533D02*
X538327Y228112D01*
G01X552616Y227630D02*
X552798Y227011D01*
G01X552500Y228112D02*
X552616Y227630D01*
G01X552432Y228533D02*
X552500Y228112D01*
G01X554040Y199978D02*
X554084Y199961D01*
G01X554000Y200007D02*
X554040Y199978D01*
G01X553968Y200046D02*
X554000Y200007D01*
G01X553946Y200094D02*
X553968Y200046D01*
G01X553938Y200151D02*
X553946Y200094D01*
G01X551758Y201037D02*
X551759Y200939D01*
G01X551758Y201137D02*
Y201037D01*
G01X551756Y201241D02*
X551758Y201137D01*
G01X556756Y201141D02*
X556754Y201241D01*
G01X556758Y201039D02*
X556756Y201141D01*
G01X552142Y201144D02*
X552140Y201043D01*
G01X552144Y201241D02*
X552142Y201144D01*
G01X552540Y201135D02*
X552562Y201218D01*
G01X552526Y201040D02*
X552540Y201135D01*
G01X552521Y200939D02*
X552526Y201040D01*
G01X542634Y225061D02*
X542700Y225280D01*
G01X542594Y224836D02*
X542634Y225061D01*
G01X542581Y224607D02*
X542594Y224836D01*
G01X556807Y225061D02*
X556874Y225280D01*
G01X556767Y224836D02*
X556807Y225061D01*
G01X556754Y224607D02*
X556767Y224836D01*
G01X541912Y226800D02*
X541966Y227011D01*
G01X541878Y226585D02*
X541912Y226800D01*
G01X541864Y226371D02*
X541878Y226585D01*
G01X556085Y226800D02*
X556139Y227011D01*
G01X556051Y226585D02*
X556085Y226800D01*
G01X556038Y226371D02*
X556051Y226585D01*
G01X537979Y201333D02*
X537971Y201241D01*
G01X537989Y201419D02*
X537979Y201333D01*
G01X538001Y201496D02*
X537989Y201419D01*
G01X552152Y201333D02*
X552144Y201241D01*
G01X552162Y201419D02*
X552152Y201333D01*
G01X552174Y201496D02*
X552162Y201419D01*
G01X542147Y227626D02*
X541966Y227011D01*
G01X542263Y228109D02*
X542147Y227626D01*
G01X542332Y228533D02*
X542263Y228109D01*
G01X556320Y227626D02*
X556139Y227011D01*
G01X556436Y228109D02*
X556320Y227626D01*
G01X556506Y228533D02*
X556436Y228109D01*
G01X542020Y226566D02*
X542006Y226338D01*
G01X542060Y226792D02*
X542020Y226566D01*
G01X542126Y227011D02*
X542060Y226792D01*
G01X541998Y224881D02*
X541981Y224607D01*
G01X542046Y225152D02*
X541998Y224881D01*
G01X542126Y225415D02*
X542046Y225152D01*
G01X542383Y224835D02*
X542369Y224607D01*
G01X542423Y225061D02*
X542383Y224835D01*
G01X542490Y225280D02*
X542423Y225061D01*
G01X557399Y200639D02*
X557324Y200623D01*
G01X557463Y200681D02*
X557399Y200639D01*
G01X557505Y200746D02*
X557463Y200681D01*
G01X557521Y200820D02*
X557505Y200746D01*
G01X556193Y226566D02*
X556180Y226338D01*
G01X556233Y226792D02*
X556193Y226566D01*
G01X556299Y227011D02*
X556233Y226792D01*
G01X556171Y224881D02*
X556155Y224607D01*
G01X556219Y225152D02*
X556171Y224881D01*
G01X556299Y225415D02*
X556219Y225152D01*
G01X556556Y224835D02*
X556542Y224607D01*
G01X556596Y225061D02*
X556556Y224835D01*
G01X556664Y225280D02*
X556596Y225061D01*
G01X542244Y201231D02*
X542163Y201218D01*
G01X542320Y201255D02*
X542244Y201231D01*
G01X542391Y201290D02*
X542320Y201255D01*
G01X542451Y201334D02*
X542391Y201290D01*
G01X542499Y201384D02*
X542451Y201334D01*
G01X542533Y201439D02*
X542499Y201384D01*
G01X542551Y201496D02*
X542533Y201439D01*
G01X542917Y228734D02*
X542980Y228740D01*
G01X542857Y228714D02*
X542917Y228734D01*
G01X542801Y228683D02*
X542857Y228714D01*
G01X542754Y228641D02*
X542801Y228683D01*
G01X542716Y228590D02*
X542754Y228641D01*
G01X542689Y228533D02*
X542716Y228590D01*
G01X543920Y228734D02*
X543984Y228740D01*
G01X543861Y228714D02*
X543920Y228734D01*
G01X543805Y228683D02*
X543861Y228714D01*
G01X543758Y228641D02*
X543805Y228683D01*
G01X543720Y228590D02*
X543758Y228641D01*
G01X543692Y228533D02*
X543720Y228590D01*
G01X557090Y228734D02*
X557153Y228740D01*
G01X557030Y228714D02*
X557090Y228734D01*
G01X556974Y228683D02*
X557030Y228714D01*
G01X556927Y228641D02*
X556974Y228683D01*
G01X556889Y228590D02*
X556927Y228641D01*
G01X556862Y228533D02*
X556889Y228590D01*
G01X558094Y228734D02*
X558157Y228740D01*
G01X558034Y228714D02*
X558094Y228734D01*
G01X557978Y228683D02*
X558034Y228714D01*
G01X557931Y228641D02*
X557978Y228683D01*
G01X557893Y228590D02*
X557931Y228641D01*
G01X557866Y228533D02*
X557893Y228590D01*
G01X541574Y226581D02*
X541691Y226785D01*
G01X541477Y226378D02*
X541574Y226581D01*
G01X555747D02*
X555865Y226785D01*
G01X555650Y226378D02*
X555747Y226581D01*
G01X541993Y227261D02*
X542061Y227395D01*
G01X541914Y227127D02*
X541993Y227261D01*
G01X541691Y226785D02*
X541914Y227127D01*
G01X556166Y227261D02*
X556235Y227395D01*
G01X556088Y227127D02*
X556166Y227261D01*
G01X555865Y226785D02*
X556088Y227127D01*
G01X538498Y228710D02*
X538721Y228740D01*
G01X538340Y228633D02*
X538498Y228710D01*
G01X538258Y228533D02*
X538340Y228633D01*
G01X552671Y228710D02*
X552894Y228740D01*
G01X552513Y228633D02*
X552671Y228710D01*
G01X552432Y228533D02*
X552513Y228633D01*
G01X557512Y200094D02*
X557521Y200151D01*
G01X557490Y200046D02*
X557512Y200094D01*
G01X557458Y200007D02*
X557490Y200046D01*
G01X557419Y199978D02*
X557458Y200007D01*
G01X557375Y199961D02*
X557419Y199978D01*
G01X556680Y226870D02*
G03X556585Y226338I1442J-532D01*
G01X557255Y225139D02*
G03X557160Y224607I1440J-532D01*
G01X542507Y226870D02*
G03X542412Y226338I1440J-532D01*
G01X537565Y224607D02*
G03X537470Y225140I-1535J1D01*
G01X551738Y224607D02*
G03X551643Y225140I-1535J1D01*
G01X552352Y226338D02*
G03X552256Y226870I-1536J-3D01*
G01X538179Y226338D02*
G03X538083Y226870I-1536J-3D01*
G01X543082Y225139D02*
G03X542987Y224607I1440J-532D01*
G01X552599Y225415D02*
X552234Y225280D01*
G01X552024D02*
X551660Y225146D01*
G01X558274Y228740D02*
X556929Y227395D01*
G01X552075Y228533D02*
X551701Y228425D01*
G01X550448D02*
X550822Y228533D01*
G01X537902D02*
X537528Y228425D01*
G01X552638Y227011D02*
X552274Y226876D01*
G01X538426Y225415D02*
X538061Y225280D01*
G01X537851D02*
X537487Y225146D01*
G01X538465Y227011D02*
X538100Y226876D01*
G01X551778Y228740D02*
X550433Y227395D01*
G01X544691Y228740D02*
X543346Y227395D01*
G01X558450Y228425D02*
X557238Y225146D01*
G01X556874Y225280D02*
X558076Y228533D01*
G01X557866D02*
X556664Y225280D01*
G01X556299Y225415D02*
X557412Y228425D01*
G01X556664Y226877D02*
X557225Y228394D01*
G01X556862Y228533D02*
X556299Y227011D01*
G01X544277Y228425D02*
X543065Y225146D01*
G01X542700Y225280D02*
X543902Y228533D01*
G01X543692D02*
X542490Y225280D01*
G01X542126Y225415D02*
X543238Y228425D01*
G01X542490Y226877D02*
X543051Y228394D01*
G01X542689Y228533D02*
X542126Y227011D01*
G01X552743Y202247D02*
X552562Y201218D01*
G01X552174Y201496D02*
X552356Y202525D01*
G01X538570Y202247D02*
X538389Y201218D01*
G01X538001Y201496D02*
X538182Y202525D01*
G01X556038Y226371D02*
X556037Y226338D01*
G01X555650D02*
Y226378D01*
G01X557139Y200939D02*
X557141Y201241D01*
G01X558450Y228425D02*
Y228740D01*
G01X557521Y201043D02*
Y200151D01*
G01X557412Y228425D02*
Y228740D01*
G01X557225D02*
Y220866D01*
G01X557142Y201241D02*
Y224607D01*
G01X556754D02*
Y201241D01*
G01X556542Y224607D02*
Y202525D01*
G01X556155Y202247D02*
Y224607D01*
G01X553938Y201043D02*
Y200151D01*
G01X552743Y202247D02*
Y224607D01*
G01X552356Y202525D02*
Y224607D01*
G01X552144D02*
Y201241D01*
G01X551756Y224607D02*
Y201241D01*
G01X551701Y228740D02*
Y228425D01*
G01X551486D02*
Y228740D01*
G01X550448D02*
Y228425D01*
G01X550301Y228740D02*
Y220866D01*
G01X549612Y225787D02*
Y201804D01*
G01X552900Y226371D02*
Y226338D01*
G01X553287Y226378D02*
X553288Y226338D01*
G01X556542Y202525D02*
X556724Y201496D01*
G01X556336Y201218D02*
X556155Y202247D01*
G01X542369Y202525D02*
X542551Y201496D01*
G01X542163Y201218D02*
X541981Y202247D01*
G01X541864Y226371D02*
Y226338D01*
G01X541476D02*
X541477Y226378D01*
G01X542966Y200939D02*
X542968Y201241D01*
G01X545774Y220866D02*
Y228740D01*
G01X545414D02*
Y220866D01*
G01X544277Y228425D02*
Y228740D01*
G01X543238Y228425D02*
Y228740D01*
G01X543051D02*
Y220866D01*
G01X542968Y201241D02*
Y224607D01*
G01X542581Y201241D02*
Y224607D01*
G01X542369D02*
Y202525D01*
G01X541981Y202247D02*
Y224607D01*
G01X538570Y202247D02*
Y224607D01*
G01X538182Y202525D02*
Y224607D01*
G01X537971D02*
Y201241D01*
G01X537583Y224607D02*
Y201241D01*
G01X537528Y228740D02*
Y228425D01*
G01X537313D02*
Y228740D01*
G01X538726Y226371D02*
X538727Y226338D01*
G01X539114Y226378D02*
Y226338D01*
G01X552638Y227011D02*
X552075Y228533D01*
G01X551701Y228425D02*
X552274Y226876D01*
G01X551486Y228425D02*
X552599Y225415D01*
G01X552234Y225280D02*
X551032Y228533D01*
G01X550822D02*
X552024Y225280D01*
G01X551660Y225146D02*
X550448Y228425D01*
G01X538465Y227011D02*
X537902Y228533D01*
G01X537528Y228425D02*
X538100Y226876D01*
G01X537313Y228425D02*
X538426Y225415D01*
G01X552959Y228740D02*
X554304Y227395D01*
G01X545872Y228740D02*
X547217Y227395D01*
G01X540131D02*
X538786Y228740D01*
G01X556299Y227011D02*
X556664Y226876D01*
G01X557238Y225146D02*
X556874Y225280D01*
G01X556664D02*
X556299Y225415D01*
G01X542126Y227011D02*
X542490Y226876D01*
G01X543065Y225146D02*
X542700Y225280D01*
G01X542490D02*
X542126Y225415D01*
G01X558450Y228425D02*
X558076Y228533D01*
G01X556862D02*
X557225Y228429D01*
G01X543902Y228533D02*
X544277Y228425D01*
G01X542689Y228533D02*
X543051Y228429D01*
G01X555650Y226378D02*
X556038Y226371D01*
G01X541477Y226378D02*
X541864Y226371D01*
G01X556506Y228533D02*
X556862D01*
G01X542332D02*
X542689D01*
G01X543902D02*
X543692D01*
G01X551032D02*
X550822D01*
G01X558076D02*
X557866D01*
G01X537902D02*
X538258D01*
G01X552075D02*
X552432D01*
G01X557412Y228425D02*
X544277D01*
G01X558667D02*
X558450D01*
G01X545414Y228252D02*
X543051D01*
G01X550301D02*
X545774D01*
G01X558667D02*
X557225D01*
G01X543346Y227395D02*
X538529D01*
G01X550433D02*
X547217D01*
G01X556929D02*
X552703D01*
G01X556139Y227011D02*
X556299D01*
G01X541966D02*
X542126D01*
G01X538625D02*
X538465D01*
G01X552798D02*
X552638D01*
G01X552370Y226338D02*
X553288D01*
G01X538197D02*
X539114D01*
G01X555650D02*
X556567D01*
G01X541476D02*
X542394D01*
G01X549612Y225787D02*
X545687D01*
G01X542700Y225280D02*
X542490D01*
G01X556874D02*
X556664D01*
G01X538061D02*
X537851D01*
G01X552234D02*
X552024D01*
G01X551756Y224607D02*
X552743D01*
G01X541981D02*
X542968D01*
G01X537583D02*
X538570D01*
G01X557142D02*
X556155D01*
G01X558667Y220866D02*
X557225D01*
G01X545414D02*
X543051D01*
G01X550301D02*
X545774D01*
G01X539114Y226378D02*
X538726Y226371D01*
G01X553287Y226378D02*
X552900Y226371D01*
G01X552356Y202525D02*
X556542D01*
G01X538182D02*
X542369D01*
G01X541981Y202247D02*
X538570D01*
G01X556155D02*
X552743D01*
G01X550434Y201804D02*
X546851D01*
G01X558995D02*
X558667D01*
G01X542581Y201241D02*
X542968D01*
G01X537971D02*
X537583D01*
G01X552144D02*
X551756D01*
G01X557142D02*
X556754D01*
G01X552562Y201218D02*
X556336D01*
G01X538389D02*
X542163D01*
G01X543347Y201043D02*
X539765D01*
G01X557521D02*
X553938D01*
G01X551759Y200939D02*
X557139D01*
G01X537586D02*
X542966D01*
G01X543151Y200623D02*
X539962D01*
G01X557324D02*
X554135D01*
G01X553938Y200374D02*
X557521D01*
G01X554084Y199961D02*
X557375D01*
G01X543238Y228425D02*
X543616Y228514D01*
G01X557412Y228425D02*
X557789Y228514D01*
G01X543616D02*
X543692Y228533D01*
G01X557789Y228514D02*
X557866Y228533D01*
G01X568110Y316929D02*
G03X560236I-3937J0D01*
G01X568110D02*
G03X560236I-3937J0D01*
G01Y690803D02*
Y347638D01*
G01D02*
G03X568110I3937J0D01*
G01X560236D02*
G03X568110I3937J0D01*
G01X560236Y721512D02*
Y723481D01*
G01X561484Y728764D02*
G03X560236Y723482I10563J-5284D01*
G01X568526Y725241D02*
G03X568110Y723480I3521J-1761D01*
G01X560236Y721512D02*
G03X568110I3937J0D01*
G01Y690803D02*
G03X560236I-3937J0D01*
G01Y721512D02*
G03X568110I3937J0D01*
G01Y690803D02*
G03X560236I-3937J0D01*
G01X576143Y758082D02*
G03X572622Y763780I-3521J1761D01*
G01X576143Y758082D02*
X561483Y728762D01*
G01X586707Y761603D02*
X568526Y725241D01*
G01X590228Y763780D02*
G03X586707Y761603I1J-3937D01*
G01X903079Y763780D02*
X590228D01*
G01X597656Y1340060D02*
Y1321123D01*
G01X604654Y2665D02*
X604330Y2441D01*
G01X655551D02*
X654710Y1220D01*
G01X655219Y2653D02*
X654330Y1262D01*
G01X654134Y-4016D02*
X652480Y-11496D01*
G01X653758Y-3933D02*
X652086Y-11496D01*
G01X654710Y1220D02*
X654134Y-4016D01*
G01X654330Y1262D02*
X653758Y-3933D01*
G01X652480Y-11496D02*
Y-21890D01*
G01X652086D02*
Y-22283D01*
G01Y127323D02*
Y-11496D01*
G01X651102Y126339D02*
Y-22283D01*
G01X650118D02*
Y127323D01*
G01X648641Y-12402D02*
Y-18819D01*
G01X643917D02*
Y-12402D01*
G01X635590Y-9094D02*
Y-14016D01*
G01X634176Y-9094D02*
Y-14016D01*
G01X633464Y-9094D02*
Y-14016D01*
G01X633050Y-9094D02*
Y-14016D01*
G01X626831Y-9094D02*
Y-14016D01*
G01X626417Y-9094D02*
Y-14016D01*
G01X625705Y-9094D02*
Y-14016D01*
G01X624291Y-9094D02*
Y-14016D01*
G01X615964Y-12402D02*
Y-18819D01*
G01X611240D02*
Y-12402D01*
G01X609764Y127323D02*
Y-22283D01*
G01X608779Y126339D02*
Y-22283D01*
G01X607795Y-11496D02*
Y127323D01*
G01Y-21890D02*
Y-22283D01*
G01X607401Y-11496D02*
Y-21890D01*
G01X605551Y1373D02*
X606134Y-3980D01*
G01X605178Y1220D02*
X605748Y-4016D01*
G01X606134Y-3980D02*
X607795Y-11496D01*
G01X605748Y-4016D02*
X607401Y-11496D01*
G01X604654Y2665D02*
X605551Y1373D01*
G01X604330Y2441D02*
X605178Y1220D01*
G01X655551Y2441D02*
X655219Y2653D01*
G01X609764Y2717D02*
X650118D01*
G01X609764Y2700D02*
X650118D01*
G01X609764Y2653D02*
X650118D01*
G01X609764Y2441D02*
X650118D01*
G01X609764Y1262D02*
X650118D01*
G01X609764Y1220D02*
X650118D01*
G01X651102Y-3189D02*
X608779D01*
G01X609764Y-3933D02*
X650118D01*
G01X609764Y-4016D02*
X650118D01*
G01X652086Y-4173D02*
X607795D01*
G01X635590Y-9094D02*
X624291D01*
G01X652480Y-11496D02*
X607401D01*
G01X643917Y-12402D02*
X648641D01*
G01X611240D02*
X615964D01*
G01X624291Y-14016D02*
X635590D01*
G01X615964Y-18819D02*
X611240D01*
G01X648641D02*
X643917D01*
G01X652480Y-21890D02*
X607401D01*
G01X652086Y-22283D02*
X607795D01*
G01X634252Y57874D02*
G03X625591I-4331J0D01*
G01D02*
G03X634252I4331J0D01*
G01X653464Y40157D02*
G03X652874Y40748I-591J0D01*
G01X652086Y41339D02*
G03X652677Y40748I591J0D01*
G01X651102Y41339D02*
G03X652480Y39776I1575J0D01*
G01X652874Y32717D02*
G03X653464Y33307I0J590D01*
G01X652677Y32717D02*
G03X652086Y32126I0J-591D01*
G01X652480Y33688D02*
G03X651102Y32126I196J-1562D01*
G01X607008Y40748D02*
G03X606417Y40157I0J-591D01*
G01X607204Y40748D02*
G03X607795Y41339I0J591D01*
G01X607401Y39776D02*
G03X608779Y41339I-197J1563D01*
G01X633878Y57874D02*
G03I-3937J0D01*
G01X634252D02*
G03I-4331J0D01*
G01X606417Y33307D02*
G03X607008Y32717I590J0D01*
G01X607795Y32126D02*
G03X607204Y32717I-591J0D01*
G01X608779Y32126D02*
G03X607401Y33688I-1574J0D01*
G01X613307Y31398D02*
X614488Y35335D01*
G01X653464Y40157D02*
Y33307D01*
G01X653086Y57126D02*
Y8976D01*
G01X652874Y32717D02*
Y40748D01*
G01X652677D02*
Y32717D01*
G01X652480Y33688D02*
Y39776D01*
G01X649134Y126398D02*
Y64783D01*
G01X647559D02*
Y31398D01*
G01X645393Y55531D02*
Y35335D01*
G01X637618Y50197D02*
Y64783D01*
G01X632397Y40118D02*
Y33228D01*
G01X631397D02*
Y40118D01*
G01X622264Y64783D02*
Y50197D01*
G01X614488Y55531D02*
Y35335D01*
G01X612323Y64783D02*
Y31398D01*
G01X610748Y126398D02*
Y64783D01*
G01X607401Y33688D02*
Y39776D01*
G01X607204Y32717D02*
Y40748D01*
G01X607008D02*
Y32717D01*
G01X606795Y57126D02*
Y8976D01*
G01X606417Y33307D02*
Y40157D01*
G01X646575Y31398D02*
X645393Y35335D01*
G01X649134Y64783D02*
X610748D01*
G01X651102Y64291D02*
X608779D01*
G01X647559Y57146D02*
X612323D01*
G01X606795Y57126D02*
X607795D01*
G01X653086D02*
X652086D01*
G01X645393Y55531D02*
X614488D01*
G01X622264Y50197D02*
X637618D01*
G01X607204Y40748D02*
X607008D01*
G01X652874D02*
X652677D01*
G01X631397Y40118D02*
X632397D01*
G01X651102Y38189D02*
X653464D01*
G01X606417D02*
X608779D01*
G01X645393Y35335D02*
X614488D01*
G01X651102Y35276D02*
X653464D01*
G01X606417D02*
X608779D01*
G01X632397Y33228D02*
X631397D01*
G01X607204Y32717D02*
X607008D01*
G01X652874D02*
X652677D01*
G01X647559Y31398D02*
X612323D01*
G01X608779Y21476D02*
X607795D01*
G01X652086D02*
X651102D01*
G01X606795Y20079D02*
X607795D01*
G01X653086D02*
X652086D01*
G01X651102Y18602D02*
X652086D01*
G01X608779D02*
X607795D01*
G01X606795Y8976D02*
X607795D01*
G01X653086D02*
X652086D01*
G01X653464Y99213D02*
G03X652874Y99803I-590J0D01*
G01X652086Y100394D02*
G03X652677Y99803I591J0D01*
G01X651102Y100394D02*
G03X652480Y98831I1575J0D01*
G01X652874Y91772D02*
G03X653464Y92362I0J590D01*
G01X652677Y91772D02*
G03X652086Y91181I0J-591D01*
G01X652480Y92744D02*
G03X651102Y91181I197J-1563D01*
G01X607008Y99803D02*
G03X606417Y99213I0J-591D01*
G01X607204Y99803D02*
G03X607795Y100394I0J591D01*
G01X607401Y98831D02*
G03X608779Y100394I-197J1563D01*
G01X606417Y92362D02*
G03X607008Y91772I590J0D01*
G01X607795Y91181D02*
G03X607204Y91772I-591J0D01*
G01X608779Y91181D02*
G03X607401Y92744I-1575J0D01*
G01X653464Y99213D02*
Y92362D01*
G01X653086Y127323D02*
Y115512D01*
G01X652874Y91772D02*
Y99803D01*
G01X652677D02*
Y91772D01*
G01X652480Y98831D02*
Y92744D01*
G01X650807Y91280D02*
Y126339D01*
G01X643149D02*
Y127323D01*
G01X642102Y116378D02*
Y118307D01*
G01Y101417D02*
Y103346D01*
G01Y86457D02*
Y88386D01*
G01Y71496D02*
Y73425D01*
G01X641401D02*
Y71496D01*
G01Y88386D02*
Y86457D01*
G01Y103346D02*
Y101417D01*
G01Y118307D02*
Y116378D01*
G01X640275Y127323D02*
Y126339D01*
G01X639149Y113622D02*
Y115551D01*
G01Y98661D02*
Y100591D01*
G01Y83701D02*
Y85630D01*
G01Y68740D02*
Y70669D01*
G01X638449D02*
Y68740D01*
G01Y85630D02*
Y83701D01*
G01Y100591D02*
Y98661D01*
G01Y115551D02*
Y113622D01*
G01X636197Y119134D02*
Y121063D01*
G01Y104173D02*
Y106102D01*
G01Y89213D02*
Y91142D01*
G01Y74252D02*
Y76181D01*
G01X635496D02*
Y74252D01*
G01Y91142D02*
Y89213D01*
G01Y106102D02*
Y104173D01*
G01Y121063D02*
Y119134D01*
G01X633244Y116378D02*
Y118307D01*
G01Y101417D02*
Y103346D01*
G01Y86457D02*
Y88386D01*
G01Y71496D02*
Y73425D01*
G01X632543D02*
Y71496D01*
G01Y88386D02*
Y86457D01*
G01Y103346D02*
Y101417D01*
G01Y118307D02*
Y116378D01*
G01X630291Y113622D02*
Y115551D01*
G01Y98661D02*
Y100591D01*
G01Y83701D02*
Y85630D01*
G01Y68740D02*
Y70669D01*
G01X629590D02*
Y68740D01*
G01Y85630D02*
Y83701D01*
G01Y100591D02*
Y98661D01*
G01Y115551D02*
Y113622D01*
G01X627338Y119134D02*
Y121063D01*
G01Y104173D02*
Y106102D01*
G01Y89213D02*
Y91142D01*
G01Y74252D02*
Y76181D01*
G01X626638D02*
Y74252D01*
G01Y91142D02*
Y89213D01*
G01Y106102D02*
Y104173D01*
G01Y121063D02*
Y119134D01*
G01X625433Y126339D02*
Y127323D01*
G01X624386Y116378D02*
Y118307D01*
G01Y101417D02*
Y103346D01*
G01Y86457D02*
Y88386D01*
G01Y71496D02*
Y73425D01*
G01X623685D02*
Y71496D01*
G01Y88386D02*
Y86457D01*
G01Y103346D02*
Y101417D01*
G01Y118307D02*
Y116378D01*
G01X622559Y127323D02*
Y126339D01*
G01X621433Y113622D02*
Y115551D01*
G01Y98661D02*
Y100591D01*
G01Y83701D02*
Y85630D01*
G01Y68740D02*
Y70669D01*
G01X620732D02*
Y68740D01*
G01Y85630D02*
Y83701D01*
G01Y100591D02*
Y98661D01*
G01Y115551D02*
Y113622D01*
G01X618480Y119134D02*
Y121063D01*
G01Y104173D02*
Y106102D01*
G01Y89213D02*
Y91142D01*
G01Y74252D02*
Y76181D01*
G01X617779D02*
Y74252D01*
G01Y91142D02*
Y89213D01*
G01Y106102D02*
Y104173D01*
G01Y121063D02*
Y119134D01*
G01X609075Y91280D02*
Y126339D01*
G01X607401Y98831D02*
Y92744D01*
G01X607204Y91772D02*
Y99803D01*
G01X607008D02*
Y91772D01*
G01X606795Y127323D02*
Y115512D01*
G01X606417Y92362D02*
Y99213D01*
G01X606795Y127323D02*
X653086D01*
G01X622559Y126398D02*
X610748D01*
G01X640275D02*
X625433D01*
G01X649134D02*
X643149D01*
G01X651102Y126339D02*
X608779D01*
G01X618480Y121063D02*
X617779D01*
G01X627338D02*
X626638D01*
G01X636197D02*
X635496D01*
G01Y119134D02*
X636197D01*
G01X626638D02*
X627338D01*
G01X617779D02*
X618480D01*
G01X624386Y118307D02*
X623685D01*
G01X633244D02*
X632543D01*
G01X642102D02*
X641401D01*
G01Y116378D02*
X642102D01*
G01X632543D02*
X633244D01*
G01X623685D02*
X624386D01*
G01X621433Y115551D02*
X620732D01*
G01X630291D02*
X629590D01*
G01X639149D02*
X638449D01*
G01X606795Y115512D02*
X607795D01*
G01X653086D02*
X652086D01*
G01X638449Y113622D02*
X639149D01*
G01X629590D02*
X630291D01*
G01X620732D02*
X621433D01*
G01X618480Y106102D02*
X617779D01*
G01X627338D02*
X626638D01*
G01X636197D02*
X635496D01*
G01Y104173D02*
X636197D01*
G01X626638D02*
X627338D01*
G01X617779D02*
X618480D01*
G01X624386Y103346D02*
X623685D01*
G01X633244D02*
X632543D01*
G01X642102D02*
X641401D01*
G01Y101417D02*
X642102D01*
G01X632543D02*
X633244D01*
G01X623685D02*
X624386D01*
G01X621433Y100591D02*
X620732D01*
G01X630291D02*
X629590D01*
G01X639149D02*
X638449D01*
G01X607204Y99803D02*
X607008D01*
G01X652874D02*
X652677D01*
G01X638449Y98661D02*
X639149D01*
G01X629590D02*
X630291D01*
G01X620732D02*
X621433D01*
G01X651102Y97244D02*
X653464D01*
G01X606417D02*
X608779D01*
G01X651102Y94331D02*
X653464D01*
G01X606417D02*
X608779D01*
G01X607204Y91772D02*
X607008D01*
G01X652874D02*
X652677D01*
G01X610748Y91280D02*
X609075D01*
G01X650807D02*
X649134D01*
G01X618480Y91142D02*
X617779D01*
G01X627338D02*
X626638D01*
G01X636197D02*
X635496D01*
G01Y89213D02*
X636197D01*
G01X626638D02*
X627338D01*
G01X617779D02*
X618480D01*
G01X624386Y88386D02*
X623685D01*
G01X633244D02*
X632543D01*
G01X642102D02*
X641401D01*
G01Y86457D02*
X642102D01*
G01X632543D02*
X633244D01*
G01X623685D02*
X624386D01*
G01X621433Y85630D02*
X620732D01*
G01X630291D02*
X629590D01*
G01X639149D02*
X638449D01*
G01Y83701D02*
X639149D01*
G01X629590D02*
X630291D01*
G01X620732D02*
X621433D01*
G01X618480Y76181D02*
X617779D01*
G01X627338D02*
X626638D01*
G01X636197D02*
X635496D01*
G01Y74252D02*
X636197D01*
G01X626638D02*
X627338D01*
G01X617779D02*
X618480D01*
G01X608779Y73878D02*
X607795D01*
G01X652086D02*
X651102D01*
G01X624386Y73425D02*
X623685D01*
G01X633244D02*
X632543D01*
G01X642102D02*
X641401D01*
G01Y71496D02*
X642102D01*
G01X632543D02*
X633244D01*
G01X623685D02*
X624386D01*
G01X651102Y71004D02*
X652086D01*
G01X608779D02*
X607795D01*
G01X621433Y70669D02*
X620732D01*
G01X630291D02*
X629590D01*
G01X639149D02*
X638449D01*
G01Y68740D02*
X639149D01*
G01X629590D02*
X630291D01*
G01X620732D02*
X621433D01*
G01X658661Y180000D02*
G03X646850I-5905J0D01*
G01D02*
G03X658661I5906J0D01*
G01X619094Y433071D02*
G03X605315I-6889J0D01*
G01D02*
G03X619094I6890J0D01*
G01Y740157D02*
G03X605315I-6889J0D01*
G01D02*
G03X619094I6890J0D01*
G01X683394Y2665D02*
X683071Y2441D01*
G01X734291D02*
X733451Y1220D01*
G01X733959Y2653D02*
X733071Y1262D01*
G01X732874Y-4016D02*
X731220Y-11496D01*
G01X732498Y-3933D02*
X730827Y-11496D01*
G01X733451Y1220D02*
X732874Y-4016D01*
G01X733071Y1262D02*
X732498Y-3933D01*
G01X731220Y-11496D02*
Y-21890D01*
G01X730827D02*
Y-22283D01*
G01Y127323D02*
Y-11496D01*
G01X729842Y126339D02*
Y-22283D01*
G01X728858D02*
Y127323D01*
G01X727382Y-12402D02*
Y-18819D01*
G01X722657D02*
Y-12402D01*
G01X714330Y-9094D02*
Y-14016D01*
G01X712916Y-9094D02*
Y-14016D01*
G01X712204Y-9094D02*
Y-14016D01*
G01X711790Y-9094D02*
Y-14016D01*
G01X705571Y-9094D02*
Y-14016D01*
G01X705157Y-9094D02*
Y-14016D01*
G01X704445Y-9094D02*
Y-14016D01*
G01X703031Y-9094D02*
Y-14016D01*
G01X694704Y-12402D02*
Y-18819D01*
G01X689980D02*
Y-12402D01*
G01X688504Y127323D02*
Y-22283D01*
G01X687519Y126339D02*
Y-22283D01*
G01X686535Y-11496D02*
Y127323D01*
G01Y-21890D02*
Y-22283D01*
G01X686141Y-11496D02*
Y-21890D01*
G01X684291Y1373D02*
X684874Y-3980D01*
G01X683918Y1220D02*
X684488Y-4016D01*
G01X684874Y-3980D02*
X686535Y-11496D01*
G01X684488Y-4016D02*
X686141Y-11496D01*
G01X683394Y2665D02*
X684291Y1373D01*
G01X683071Y2441D02*
X683918Y1220D01*
G01X688504Y2717D02*
X728858D01*
G01X688504Y2700D02*
X728858D01*
G01X688504Y2653D02*
X728858D01*
G01X688504Y2441D02*
X728858D01*
G01X688504Y1262D02*
X728858D01*
G01X688504Y1220D02*
X728858D01*
G01X729842Y-3189D02*
X687519D01*
G01X688504Y-3933D02*
X728858D01*
G01X688504Y-4016D02*
X728858D01*
G01X730827Y-4173D02*
X686535D01*
G01X714330Y-9094D02*
X703031D01*
G01X731220Y-11496D02*
X686141D01*
G01X722657Y-12402D02*
X727382D01*
G01X689980D02*
X694704D01*
G01X703031Y-14016D02*
X714330D01*
G01X694704Y-18819D02*
X689980D01*
G01X727382D02*
X722657D01*
G01X731220Y-21890D02*
X686141D01*
G01X730827Y-22283D02*
X686535D01*
G01X712992Y57874D02*
G03X704331I-4331J0D01*
G01D02*
G03X712992I4330J0D01*
G01X712618D02*
G03I-3937J0D01*
G01X712992D02*
G03I-4331J0D01*
G01X732204Y40157D02*
G03X731614Y40748I-591J0D01*
G01Y32717D02*
G03X732204Y33307I0J590D01*
G01X730827Y41339D02*
G03X731417Y40748I591J0D01*
G01Y32717D02*
G03X730827Y32126I0J-590D01*
G01X731220Y33688D02*
G03X729842Y32126I196J-1562D01*
G01Y41339D02*
G03X731220Y39776I1575J0D01*
G01X685748Y40748D02*
G03X685157Y40157I0J-591D01*
G01X685945Y40748D02*
G03X686535Y41339I0J590D01*
G01X686141Y39776D02*
G03X687519Y41339I-197J1562D01*
G01X685157Y33307D02*
G03X685748Y32717I590J0D01*
G01X686535Y32126D02*
G03X685945Y32717I-591J0D01*
G01X687519Y32126D02*
G03X686141Y33688I-1574J0D01*
G01X692047Y31398D02*
X693228Y35335D01*
G01X732204Y40157D02*
Y33307D01*
G01X731827Y57126D02*
Y8976D01*
G01X731614Y32717D02*
Y40748D01*
G01X731417D02*
Y32717D01*
G01X731220Y33688D02*
Y39776D01*
G01X727874Y126398D02*
Y64783D01*
G01X726299D02*
Y31398D01*
G01X724134Y55531D02*
Y35335D01*
G01X716358Y50197D02*
Y64783D01*
G01X711138Y40118D02*
Y33228D01*
G01X710138D02*
Y40118D01*
G01X701004Y64783D02*
Y50197D01*
G01X693228Y55531D02*
Y35335D01*
G01X691063Y64783D02*
Y31398D01*
G01X689488Y126398D02*
Y64783D01*
G01X686141Y33688D02*
Y39776D01*
G01X685945Y32717D02*
Y40748D01*
G01X685748D02*
Y32717D01*
G01X685535Y57126D02*
Y8976D01*
G01X685157Y33307D02*
Y40157D01*
G01X725315Y31398D02*
X724134Y35335D01*
G01X727874Y64783D02*
X689488D01*
G01X729842Y64291D02*
X687519D01*
G01X726299Y57146D02*
X691063D01*
G01X685535Y57126D02*
X686535D01*
G01X731827D02*
X730827D01*
G01X724134Y55531D02*
X693228D01*
G01X701004Y50197D02*
X716358D01*
G01X685945Y40748D02*
X685748D01*
G01X731614D02*
X731417D01*
G01X710138Y40118D02*
X711138D01*
G01X729842Y38189D02*
X732204D01*
G01X685157D02*
X687519D01*
G01X724134Y35335D02*
X693228D01*
G01X729842Y35276D02*
X732204D01*
G01X685157D02*
X687519D01*
G01X711138Y33228D02*
X710138D01*
G01X685945Y32717D02*
X685748D01*
G01X731614D02*
X731417D01*
G01X726299Y31398D02*
X691063D01*
G01X687519Y21476D02*
X686535D01*
G01X730827D02*
X729842D01*
G01X685535Y20079D02*
X686535D01*
G01X731827D02*
X730827D01*
G01X729842Y18602D02*
X730827D01*
G01X687519D02*
X686535D01*
G01X685535Y8976D02*
X686535D01*
G01X731827D02*
X730827D01*
G01X732204Y99213D02*
G03X731614Y99803I-590J0D01*
G01Y91772D02*
G03X732204Y92362I0J590D01*
G01X730827Y100394D02*
G03X731417Y99803I591J0D01*
G01Y91772D02*
G03X730827Y91181I0J-590D01*
G01X731220Y92744D02*
G03X729842Y91181I197J-1563D01*
G01Y100394D02*
G03X731220Y98831I1575J0D01*
G01X685748Y99803D02*
G03X685157Y99213I0J-591D01*
G01X685945Y99803D02*
G03X686535Y100394I0J590D01*
G01X686141Y98831D02*
G03X687519Y100394I-197J1562D01*
G01X685157Y92362D02*
G03X685748Y91772I590J0D01*
G01X686535Y91181D02*
G03X685945Y91772I-591J0D01*
G01X687519Y91181D02*
G03X686141Y92744I-1575J1D01*
G01X732204Y99213D02*
Y92362D01*
G01X731827Y127323D02*
Y115512D01*
G01X731614Y91772D02*
Y99803D01*
G01X731417D02*
Y91772D01*
G01X731220Y98831D02*
Y92744D01*
G01X729547Y91280D02*
Y126339D01*
G01X721890D02*
Y127323D01*
G01X720842Y116378D02*
Y118307D01*
G01Y101417D02*
Y103346D01*
G01Y86457D02*
Y88386D01*
G01Y71496D02*
Y73425D01*
G01X720141D02*
Y71496D01*
G01Y88386D02*
Y86457D01*
G01Y103346D02*
Y101417D01*
G01Y118307D02*
Y116378D01*
G01X719015Y127323D02*
Y126339D01*
G01X717890Y113622D02*
Y115551D01*
G01Y98661D02*
Y100591D01*
G01Y83701D02*
Y85630D01*
G01Y68740D02*
Y70669D01*
G01X717189D02*
Y68740D01*
G01Y85630D02*
Y83701D01*
G01Y100591D02*
Y98661D01*
G01Y115551D02*
Y113622D01*
G01X714937Y119134D02*
Y121063D01*
G01Y104173D02*
Y106102D01*
G01Y89213D02*
Y91142D01*
G01Y74252D02*
Y76181D01*
G01X714236D02*
Y74252D01*
G01Y91142D02*
Y89213D01*
G01Y106102D02*
Y104173D01*
G01Y121063D02*
Y119134D01*
G01X711984Y116378D02*
Y118307D01*
G01Y101417D02*
Y103346D01*
G01Y86457D02*
Y88386D01*
G01Y71496D02*
Y73425D01*
G01X711283D02*
Y71496D01*
G01Y88386D02*
Y86457D01*
G01Y103346D02*
Y101417D01*
G01Y118307D02*
Y116378D01*
G01X709031Y113622D02*
Y115551D01*
G01Y98661D02*
Y100591D01*
G01Y83701D02*
Y85630D01*
G01Y68740D02*
Y70669D01*
G01X708330D02*
Y68740D01*
G01Y85630D02*
Y83701D01*
G01Y100591D02*
Y98661D01*
G01Y115551D02*
Y113622D01*
G01X706078Y119134D02*
Y121063D01*
G01Y104173D02*
Y106102D01*
G01Y89213D02*
Y91142D01*
G01Y74252D02*
Y76181D01*
G01X705378D02*
Y74252D01*
G01Y91142D02*
Y89213D01*
G01Y106102D02*
Y104173D01*
G01Y121063D02*
Y119134D01*
G01X704173Y126339D02*
Y127323D01*
G01X703126Y116378D02*
Y118307D01*
G01Y101417D02*
Y103346D01*
G01Y86457D02*
Y88386D01*
G01Y71496D02*
Y73425D01*
G01X702425D02*
Y71496D01*
G01Y88386D02*
Y86457D01*
G01Y103346D02*
Y101417D01*
G01Y118307D02*
Y116378D01*
G01X701299Y127323D02*
Y126339D01*
G01X700173Y113622D02*
Y115551D01*
G01Y98661D02*
Y100591D01*
G01Y83701D02*
Y85630D01*
G01Y68740D02*
Y70669D01*
G01X699472D02*
Y68740D01*
G01Y85630D02*
Y83701D01*
G01Y100591D02*
Y98661D01*
G01Y115551D02*
Y113622D01*
G01X697220Y119134D02*
Y121063D01*
G01Y104173D02*
Y106102D01*
G01Y89213D02*
Y91142D01*
G01Y74252D02*
Y76181D01*
G01X696519D02*
Y74252D01*
G01Y91142D02*
Y89213D01*
G01Y106102D02*
Y104173D01*
G01Y121063D02*
Y119134D01*
G01X687815Y91280D02*
Y126339D01*
G01X686141Y98831D02*
Y92744D01*
G01X685945Y91772D02*
Y99803D01*
G01X685748D02*
Y91772D01*
G01X685535Y127323D02*
Y115512D01*
G01X685157Y92362D02*
Y99213D01*
G01X685535Y127323D02*
X731827D01*
G01X701299Y126398D02*
X689488D01*
G01X719015D02*
X704173D01*
G01X727874D02*
X721890D01*
G01X729842Y126339D02*
X687519D01*
G01X697220Y121063D02*
X696519D01*
G01X706078D02*
X705378D01*
G01X714937D02*
X714236D01*
G01Y119134D02*
X714937D01*
G01X705378D02*
X706078D01*
G01X696519D02*
X697220D01*
G01X703126Y118307D02*
X702425D01*
G01X711984D02*
X711283D01*
G01X720842D02*
X720141D01*
G01Y116378D02*
X720842D01*
G01X711283D02*
X711984D01*
G01X702425D02*
X703126D01*
G01X700173Y115551D02*
X699472D01*
G01X709031D02*
X708330D01*
G01X717890D02*
X717189D01*
G01X685535Y115512D02*
X686535D01*
G01X731827D02*
X730827D01*
G01X717189Y113622D02*
X717890D01*
G01X708330D02*
X709031D01*
G01X699472D02*
X700173D01*
G01X697220Y106102D02*
X696519D01*
G01X706078D02*
X705378D01*
G01X714937D02*
X714236D01*
G01Y104173D02*
X714937D01*
G01X705378D02*
X706078D01*
G01X696519D02*
X697220D01*
G01X703126Y103346D02*
X702425D01*
G01X711984D02*
X711283D01*
G01X720842D02*
X720141D01*
G01Y101417D02*
X720842D01*
G01X711283D02*
X711984D01*
G01X702425D02*
X703126D01*
G01X700173Y100591D02*
X699472D01*
G01X709031D02*
X708330D01*
G01X717890D02*
X717189D01*
G01X685945Y99803D02*
X685748D01*
G01X731614D02*
X731417D01*
G01X717189Y98661D02*
X717890D01*
G01X708330D02*
X709031D01*
G01X699472D02*
X700173D01*
G01X729842Y97244D02*
X732204D01*
G01X685157D02*
X687519D01*
G01X729842Y94331D02*
X732204D01*
G01X685157D02*
X687519D01*
G01X685945Y91772D02*
X685748D01*
G01X731614D02*
X731417D01*
G01X689488Y91280D02*
X687815D01*
G01X729547D02*
X727874D01*
G01X697220Y91142D02*
X696519D01*
G01X706078D02*
X705378D01*
G01X714937D02*
X714236D01*
G01Y89213D02*
X714937D01*
G01X705378D02*
X706078D01*
G01X696519D02*
X697220D01*
G01X703126Y88386D02*
X702425D01*
G01X711984D02*
X711283D01*
G01X720842D02*
X720141D01*
G01Y86457D02*
X720842D01*
G01X711283D02*
X711984D01*
G01X702425D02*
X703126D01*
G01X700173Y85630D02*
X699472D01*
G01X709031D02*
X708330D01*
G01X717890D02*
X717189D01*
G01Y83701D02*
X717890D01*
G01X708330D02*
X709031D01*
G01X699472D02*
X700173D01*
G01X697220Y76181D02*
X696519D01*
G01X706078D02*
X705378D01*
G01X714937D02*
X714236D01*
G01Y74252D02*
X714937D01*
G01X705378D02*
X706078D01*
G01X696519D02*
X697220D01*
G01X687519Y73878D02*
X686535D01*
G01X730827D02*
X729842D01*
G01X703126Y73425D02*
X702425D01*
G01X711984D02*
X711283D01*
G01X720842D02*
X720141D01*
G01Y71496D02*
X720842D01*
G01X711283D02*
X711984D01*
G01X702425D02*
X703126D01*
G01X729842Y71004D02*
X730827D01*
G01X687519D02*
X686535D01*
G01X700173Y70669D02*
X699472D01*
G01X709031D02*
X708330D01*
G01X717890D02*
X717189D01*
G01Y68740D02*
X717890D01*
G01X708330D02*
X709031D01*
G01X699472D02*
X700173D01*
G01X709842Y305512D02*
Y207087D01*
G01X808267D02*
X709842D01*
G01X808267Y305512D02*
X709842D01*
G01X711967Y1321123D02*
X1042675D01*
G01X774959Y-647618D02*
Y-737748D01*
G01X758071Y-512D02*
G03X769488I5709J0D01*
G01Y4016D02*
Y-512D01*
G01X758071Y4016D02*
Y-512D01*
G01X734291Y2441D02*
X733959Y2653D01*
G01X769488Y-512D02*
X758071D01*
G01X797244Y29409D02*
Y4409D01*
G01X777559Y29409D02*
Y4409D01*
G01X775590D02*
Y29409D01*
G01X775157Y25394D02*
Y23425D01*
G01X775000Y11890D02*
Y4409D01*
G01X774764Y25394D02*
Y29409D01*
G01Y25394D02*
Y23425D01*
G01X772795Y25394D02*
Y29409D01*
G01Y25394D02*
Y23425D01*
G01X772401Y25394D02*
Y23425D01*
G01X770078Y11890D02*
Y4016D01*
G01X769926Y11890D02*
Y4409D01*
G01X765157Y25394D02*
Y23425D01*
G01X764764Y25394D02*
Y29409D01*
G01Y25394D02*
Y23425D01*
G01X762795Y25394D02*
Y23425D01*
G01Y29409D02*
Y25394D01*
G01X762401D02*
Y23425D01*
G01X757633Y11890D02*
Y4409D01*
G01X757480Y11890D02*
Y4016D01*
G01X755157Y25394D02*
Y23425D01*
G01X754764Y25394D02*
Y29409D01*
G01Y25394D02*
Y23425D01*
G01X752795Y25394D02*
Y29409D01*
G01Y25394D02*
Y23425D01*
G01X752559Y11890D02*
Y4409D01*
G01X752401Y25394D02*
Y23425D01*
G01X751968Y29409D02*
Y4409D01*
G01X750000Y29409D02*
Y4409D01*
G01X797244Y29409D02*
X800039D01*
G01X774764D02*
X777559D01*
G01X750000D02*
X752795D01*
G01X762795D02*
X754764D01*
G01X772795D02*
X764764D01*
G01X755157Y25394D02*
X752401D01*
G01X765157D02*
X762401D01*
G01X775157D02*
X772401D01*
G01X755157Y23425D02*
X752401D01*
G01X765157D02*
X762401D01*
G01X775157D02*
X772401D01*
G01X770078Y11890D02*
X775000D01*
G01X757480D02*
X752559D01*
G01X770078D02*
X757480D01*
G01X777559Y4409D02*
X750000D01*
G01X824803D02*
X797244D01*
G01X770078Y4016D02*
X757480D01*
G01X778937Y278465D02*
Y234134D01*
G01X739173Y278465D02*
Y234134D01*
G01X778937D02*
X739173D01*
G01X778937Y278465D02*
X739173D01*
G01X817325Y-837696D02*
Y-856633D01*
G01X805315Y-512D02*
G03X816732I5708J0D01*
G01Y4016D02*
Y-512D01*
G01X805315Y4016D02*
Y-512D01*
G01X816732D02*
X805315D01*
G01X824803Y29409D02*
Y4409D01*
G01X822834D02*
Y29409D01*
G01X822401Y25394D02*
Y23425D01*
G01X822244Y11890D02*
Y4409D01*
G01X822008Y25394D02*
Y29409D01*
G01Y25394D02*
Y23425D01*
G01X820039Y25394D02*
Y29409D01*
G01Y25394D02*
Y23425D01*
G01X819645Y25394D02*
Y23425D01*
G01X817323Y11890D02*
Y4016D01*
G01X817170Y11890D02*
Y4409D01*
G01X812401Y25394D02*
Y23425D01*
G01X812008Y25394D02*
Y29409D01*
G01Y25394D02*
Y23425D01*
G01X810039Y25394D02*
Y23425D01*
G01Y29409D02*
Y25394D01*
G01X809645D02*
Y23425D01*
G01X804877Y11890D02*
Y4409D01*
G01X804724Y11890D02*
Y4016D01*
G01X802401Y25394D02*
Y23425D01*
G01X802008Y25394D02*
Y29409D01*
G01Y25394D02*
Y23425D01*
G01X800039Y25394D02*
Y29409D01*
G01Y25394D02*
Y23425D01*
G01X799803Y11890D02*
Y4409D01*
G01X799645Y25394D02*
Y23425D01*
G01X799212Y29409D02*
Y4409D01*
G01X822008Y29409D02*
X824803D01*
G01X810039D02*
X802008D01*
G01X820039D02*
X812008D01*
G01X802401Y25394D02*
X799645D01*
G01X812401D02*
X809645D01*
G01X822401D02*
X819645D01*
G01X802401Y23425D02*
X799645D01*
G01X812401D02*
X809645D01*
G01X822401D02*
X819645D01*
G01X817323Y11890D02*
X822244D01*
G01X804724D02*
X799803D01*
G01X817323D02*
X804724D01*
G01X817323Y4016D02*
X804724D01*
G01X808267Y305512D02*
Y207087D01*
G01X859449Y332598D02*
G03X871260I5905J0D01*
G01D02*
G03X859449I-5906J0D01*
G01X817325Y1340060D02*
Y1321123D01*
G01X921260Y0D02*
G03X925197Y3937I0J3937D01*
G01X883858Y59055D02*
G03X868110I-7874J0D01*
G01D02*
G03X883858I7874J0D01*
G01X925197Y3937D02*
Y723480D01*
G01X882874Y433071D02*
G03X869094I-6890J0D01*
G01D02*
G03X882874I6890J0D01*
G01X925197Y723726D02*
Y793248D01*
G01Y723480D02*
G03X924781Y725241I-3937J0D01*
G01X882874Y740157D02*
G03X869094I-6890J0D01*
G01D02*
G03X882874I6890J0D01*
G01X906600Y761603D02*
G03X903079Y763780I-3522J-1760D01*
G01X924781Y725241D02*
X906600Y761603D01*
G01X1003305Y-798326D02*
Y-542541D01*
G01X1042675Y1321123D02*
Y-837696D01*
G01X1042676Y-693011D02*
Y-837696D01*
G01X1042675Y-621814D02*
X1061612D01*
G01X1042675Y-405932D02*
X1061612D01*
G01X1042675Y-190050D02*
X1061612D01*
G01X1042675Y25832D02*
X1061612D01*
G01X1042675Y241714D02*
X1061612D01*
G01X1042675Y457595D02*
X1061612D01*
G01X1042675Y673477D02*
X1061612D01*
G01X1042675Y889359D02*
X1061612D01*
G01X1042486Y1105241D02*
X1061423D01*
G01X1042675Y1321123D02*
Y1226635D01*
G01X1061612Y1340060D02*
Y-856633D01*
M02*
